G04 ================== begin FILE IDENTIFICATION RECORD ==================*
G04 Layout Name:  9324_DA0F0TMBIJ0_F0T_Motherboard_J_v01_20230324_0910.brd*
G04 Film Name:    vcc1*
G04 File Format:  Gerber RS274X*
G04 File Origin:  Cadence Allegro 17.2-S081*
G04 Origin Date:  Sat Mar 25 08:45:00 2023*
G04 *
G04 Layer:  DRAWING FORMAT/TITLE_BLOCK_A*
G04 Layer:  PIN/SPECIAL_DRILL*
G04 Layer:  VIA CLASS/VCC1*
G04 Layer:  PIN/VCC1*
G04 Layer:  MANUFACTURING/PHOTOPLOT_OUTLINE*
G04 Layer:  ETCH/VCC1*
G04 Layer:  DRAWING FORMAT/TITLE_BLOCK*
G04 Layer:  DRAWING FORMAT/TITLE_DATA_VCC1*
G04 *
G04 Offset:    (0.00 0.00)*
G04 Mirror:    No*
G04 Mode:      Negative*
G04 Rotation:  0*
G04 FullContactRelief:  No*
G04 UndefLineWidth:     6.00*
G04 ================== end FILE IDENTIFICATION RECORD ====================*
%FSLAX25Y25*MOIN*%
%IR0*IPPOS*OFA0.00000B0.00000*MIA0B0*SFA1.00000B1.00000*%
%ADD20O,.121X.072*%
%ADD11C,.03*%
%ADD56O,.127X.074*%
%ADD51C,.042*%
%ADD31C,.024*%
%ADD30C,.06*%
%ADD44C,.061*%
%ADD24C,.07*%
%ADD48C,.071*%
%ADD28C,.062*%
%ADD14C,.026*%
%AMMACRO27*
4,1,36,.0025,0.0,
.002462,.000434,
.002349,.000855,
.002165,.00125,
.001915,.001607,
.001607,.001915,
.00125,.002165,
.000855,.002349,
.000434,.002462,
0.0,.0025,
-.000434,.002462,
-.000855,.002349,
-.00125,.002165,
-.001607,.001915,
-.001915,.001607,
-.002165,.00125,
-.002349,.000855,
-.002462,.000434,
-.0025,0.0,
-.002462,-.000434,
-.002349,-.000855,
-.002165,-.00125,
-.001915,-.001607,
-.001607,-.001915,
-.00125,-.002165,
-.000855,-.002349,
-.000434,-.002462,
0.0,-.0025,
.000434,-.002462,
.000855,-.002349,
.00125,-.002165,
.001607,-.001915,
.001915,-.001607,
.002165,-.00125,
.002349,-.000855,
.002462,-.000434,
.0025,0.0,
270.*
%
%ADD27MACRO27*%
%AMMACRO25*
4,1,36,.0025,0.0,
.002462,.000434,
.002349,.000855,
.002165,.00125,
.001915,.001607,
.001607,.001915,
.00125,.002165,
.000855,.002349,
.000434,.002462,
0.0,.0025,
-.000434,.002462,
-.000855,.002349,
-.00125,.002165,
-.001607,.001915,
-.001915,.001607,
-.002165,.00125,
-.002349,.000855,
-.002462,.000434,
-.0025,0.0,
-.002462,-.000434,
-.002349,-.000855,
-.002165,-.00125,
-.001915,-.001607,
-.001607,-.001915,
-.00125,-.002165,
-.000855,-.002349,
-.000434,-.002462,
0.0,-.0025,
.000434,-.002462,
.000855,-.002349,
.00125,-.002165,
.001607,-.001915,
.001915,-.001607,
.002165,-.00125,
.002349,-.000855,
.002462,-.000434,
.0025,0.0,
180.*
%
%ADD25MACRO25*%
%ADD21C,.064*%
%AMMACRO65*
4,1,36,.003,0.0,
.002954,.000521,
.002819,.001026,
.002598,.0015,
.002298,.001928,
.001928,.002298,
.0015,.002598,
.001026,.002819,
.000521,.002954,
0.0,.003,
-.000521,.002954,
-.001026,.002819,
-.0015,.002598,
-.001928,.002298,
-.002298,.001928,
-.002598,.0015,
-.002819,.001026,
-.002954,.000521,
-.003,0.0,
-.002954,-.000521,
-.002819,-.001026,
-.002598,-.0015,
-.002298,-.001928,
-.001928,-.002298,
-.0015,-.002598,
-.001026,-.002819,
-.000521,-.002954,
0.0,-.003,
.000521,-.002954,
.001026,-.002819,
.0015,-.002598,
.001928,-.002298,
.002298,-.001928,
.002598,-.0015,
.002819,-.001026,
.002954,-.000521,
.003,0.0,
270.*
%
%ADD65MACRO65*%
%AMMACRO49*
4,1,36,-.0025,0.0,
-.002462,.000434,
-.002349,.000855,
-.002165,.00125,
-.001915,.001607,
-.001607,.001915,
-.00125,.002165,
-.000855,.002349,
-.000434,.002462,
0.0,.0025,
.000434,.002462,
.000855,.002349,
.00125,.002165,
.001607,.001915,
.001915,.001607,
.002165,.00125,
.002349,.000855,
.002462,.000434,
.0025,0.0,
.002462,-.000434,
.002349,-.000855,
.002165,-.00125,
.001915,-.001607,
.001607,-.001915,
.00125,-.002165,
.000855,-.002349,
.000434,-.002462,
0.0,-.0025,
-.000434,-.002462,
-.000855,-.002349,
-.00125,-.002165,
-.001607,-.001915,
-.001915,-.001607,
-.002165,-.00125,
-.002349,-.000855,
-.002462,-.000434,
-.0025,0.0,
180.*
%
%ADD49MACRO49*%
%AMMACRO41*
4,1,36,.003,0.0,
.002954,.000521,
.002819,.001026,
.002598,.0015,
.002298,.001928,
.001928,.002298,
.0015,.002598,
.001026,.002819,
.000521,.002954,
0.0,.003,
-.000521,.002954,
-.001026,.002819,
-.0015,.002598,
-.001928,.002298,
-.002298,.001928,
-.002598,.0015,
-.002819,.001026,
-.002954,.000521,
-.003,0.0,
-.002954,-.000521,
-.002819,-.001026,
-.002598,-.0015,
-.002298,-.001928,
-.001928,-.002298,
-.0015,-.002598,
-.001026,-.002819,
-.000521,-.002954,
0.0,-.003,
.000521,-.002954,
.001026,-.002819,
.0015,-.002598,
.001928,-.002298,
.002298,-.001928,
.002598,-.0015,
.002819,-.001026,
.002954,-.000521,
.003,0.0,
180.*
%
%ADD41MACRO41*%
%ADD22C,.074*%
%AMMACRO66*
4,1,36,-.003,0.0,
-.002954,.000521,
-.002819,.001026,
-.002598,.0015,
-.002298,.001928,
-.001928,.002298,
-.0015,.002598,
-.001026,.002819,
-.000521,.002954,
0.0,.003,
.000521,.002954,
.001026,.002819,
.0015,.002598,
.001928,.002298,
.002298,.001928,
.002598,.0015,
.002819,.001026,
.002954,.000521,
.003,0.0,
.002954,-.000521,
.002819,-.001026,
.002598,-.0015,
.002298,-.001928,
.001928,-.002298,
.0015,-.002598,
.001026,-.002819,
.000521,-.002954,
0.0,-.003,
-.000521,-.002954,
-.001026,-.002819,
-.0015,-.002598,
-.001928,-.002298,
-.002298,-.001928,
-.002598,-.0015,
-.002819,-.001026,
-.002954,-.000521,
-.003,0.0,
270.*
%
%ADD66MACRO66*%
%ADD64C,.0435*%
%ADD58C,.06015*%
%ADD46C,.076*%
%ADD45C,.095*%
%ADD19C,.0257*%
%ADD69C,.087*%
%ADD34C,.03417*%
%ADD40C,.0259*%
%ADD17C,.0277*%
%ADD55C,.099*%
%AMMACRO47*
4,1,18,.09673,.06845,
.107147,.050613,
.114308,.031238,
.117996,.010914,
.118098,-.009741,
.114613,-.030101,
.107644,-.049546,
.097406,-.067485,
.09673,-.06845,
.10175,-.07347,
.112962,-.054685,
.120742,-.034239,
.124853,-.012752,
.125171,.009122,
.121685,.030719,
.114502,.051383,
.10384,.070486,
.10175,.07347,
.09673,.06845,
0.0*
4,1,18,.06845,-.09673,
.050613,-.107147,
.031238,-.114308,
.010914,-.117996,
-.009741,-.118098,
-.030101,-.114613,
-.049546,-.107644,
-.067485,-.097406,
-.06845,-.09673,
-.07347,-.10175,
-.054685,-.112962,
-.034239,-.120742,
-.012752,-.124853,
.009122,-.125171,
.030719,-.121685,
.051383,-.114502,
.070486,-.10384,
.07347,-.10175,
.06845,-.09673,
0.0*
4,1,18,-.09673,-.06845,
-.107147,-.050613,
-.114308,-.031238,
-.117996,-.010914,
-.118098,.009741,
-.114613,.030101,
-.107644,.049546,
-.097406,.067485,
-.09673,.06845,
-.10175,.07347,
-.112962,.054685,
-.120742,.034239,
-.124853,.012752,
-.125171,-.009122,
-.121685,-.030719,
-.114502,-.051383,
-.10384,-.070486,
-.10175,-.07347,
-.09673,-.06845,
0.0*
4,1,18,-.06845,.09673,
-.050613,.107147,
-.031238,.114308,
-.010914,.117996,
.009741,.118098,
.030101,.114613,
.049546,.107644,
.067485,.097406,
.06845,.09673,
.07347,.10175,
.054685,.112962,
.034239,.120742,
.012752,.124853,
-.009122,.125171,
-.030719,.121685,
-.051383,.114502,
-.070486,.10384,
-.07347,.10175,
-.06845,.09673,
0.0*
%
%ADD47MACRO47*%
%ADD35C,.03187*%
%AMMACRO42*
4,1,15,.02438,.01377,
.026401,.009327,
.027619,.004601,
.027999,-.000265,
.027527,-.005123,
.02622,-.009825,
.02438,-.01377,
.02948,-.01887,
.032309,-.013464,
.034156,-.007649,
.034965,-.001602,
.034712,.004494,
.033405,.010454,
.031082,.016095,
.02948,.01887,
.02438,.01377,
90.*
4,1,15,.01377,-.02438,
.009327,-.026401,
.004601,-.027619,
-.000265,-.027999,
-.005123,-.027527,
-.009825,-.02622,
-.01377,-.02438,
-.01887,-.02948,
-.013464,-.032309,
-.007649,-.034156,
-.001602,-.034965,
.004494,-.034712,
.010454,-.033405,
.016095,-.031082,
.01887,-.02948,
.01377,-.02438,
90.*
4,1,15,-.02438,-.01377,
-.026401,-.009327,
-.027619,-.004601,
-.027999,.000265,
-.027527,.005123,
-.02622,.009825,
-.02438,.01377,
-.02948,.01887,
-.032309,.013464,
-.034156,.007649,
-.034965,.001602,
-.034712,-.004494,
-.033405,-.010454,
-.031082,-.016095,
-.02948,-.01887,
-.02438,-.01377,
90.*
4,1,15,-.01377,.02438,
-.009327,.026401,
-.004601,.027619,
.000265,.027999,
.005123,.027527,
.009825,.02622,
.01377,.02438,
.01887,.02948,
.013464,.032309,
.007649,.034156,
.001602,.034965,
-.004494,.034712,
-.010454,.033405,
-.016095,.031082,
-.01887,.02948,
-.01377,.02438,
90.*
%
%ADD42MACRO42*%
%AMMACRO61*
4,1,18,.07103,.05689,
.07983,.043691,
.086204,.029165,
.089959,.013753,
.09098,-.002077,
.089237,-.017844,
.084783,-.033069,
.077753,-.047289,
.07103,-.05689,
.07601,-.06186,
.085597,-.047721,
.092583,-.032132,
.096757,-.015567,
.09799,.001471,
.096246,.018464,
.091577,.034897,
.084126,.050269,
.07601,.06186,
.07103,.05689,
0.0*
4,1,18,.05689,-.07103,
.043691,-.07983,
.029165,-.086204,
.013753,-.089959,
-.002077,-.09098,
-.017844,-.089237,
-.033069,-.084783,
-.047289,-.077753,
-.05689,-.07103,
-.06186,-.07601,
-.047721,-.085597,
-.032132,-.092583,
-.015567,-.096757,
.001471,-.09799,
.018464,-.096246,
.034897,-.091577,
.050269,-.084126,
.06186,-.07601,
.05689,-.07103,
0.0*
4,1,18,-.07103,-.05689,
-.07983,-.043691,
-.086204,-.029165,
-.089959,-.013753,
-.09098,.002077,
-.089237,.017844,
-.084783,.033069,
-.077753,.047289,
-.07103,.05689,
-.07601,.06186,
-.085597,.047721,
-.092583,.032132,
-.096757,.015567,
-.09799,-.001471,
-.096246,-.018464,
-.091577,-.034897,
-.084126,-.050269,
-.07601,-.06186,
-.07103,-.05689,
0.0*
4,1,18,-.05689,.07103,
-.043691,.07983,
-.029165,.086204,
-.013753,.089959,
.002077,.09098,
.017844,.089237,
.033069,.084783,
.047289,.077753,
.05689,.07103,
.06186,.07601,
.047721,.085597,
.032132,.092583,
.015567,.096757,
-.001471,.09799,
-.018464,.096246,
-.034897,.091577,
-.050269,.084126,
-.06186,.07601,
-.05689,.07103,
0.0*
%
%ADD61MACRO61*%
%AMMACRO60*
4,1,15,.02475,.01414,
.026829,.009627,
.028094,.004822,
.028504,-.000129,
.028049,-.005077,
.026741,-.009871,
.02475,-.01414,
.02984,-.01923,
.032726,-.013756,
.034617,-.007864,
.035457,-.001734,
.03522,.00445,
.033912,.010498,
.031574,.016227,
.02984,.01923,
.02475,.01414,
0.0*
4,1,15,.01414,-.02475,
.009627,-.026829,
.004822,-.028094,
-.000129,-.028504,
-.005077,-.028049,
-.009871,-.026741,
-.01414,-.02475,
-.01923,-.02984,
-.013756,-.032726,
-.007864,-.034617,
-.001734,-.035457,
.00445,-.03522,
.010498,-.033912,
.016227,-.031574,
.01923,-.02984,
.01414,-.02475,
0.0*
4,1,15,-.02475,-.01414,
-.026829,-.009627,
-.028094,-.004822,
-.028504,.000129,
-.028049,.005077,
-.026741,.009871,
-.02475,.01414,
-.02984,.01923,
-.032726,.013756,
-.034617,.007864,
-.035457,.001734,
-.03522,-.00445,
-.033912,-.010498,
-.031574,-.016227,
-.02984,-.01923,
-.02475,-.01414,
0.0*
4,1,15,-.01414,.02475,
-.009627,.026829,
-.004822,.028094,
.000129,.028504,
.005077,.028049,
.009871,.026741,
.01414,.02475,
.01923,.02984,
.013756,.032726,
.007864,.034617,
.001734,.035457,
-.00445,.03522,
-.010498,.033912,
-.016227,.031574,
-.01923,.02984,
-.01414,.02475,
0.0*
%
%ADD60MACRO60*%
%AMMACRO37*
4,1,16,.02511,.01451,
.027248,.009929,
.028558,.005047,
.029001,.000011,
.028562,-.005025,
.027256,-.009909,
.025121,-.014491,
.02511,-.01451,
.0302,-.01959,
.033143,-.014048,
.035079,-.00808,
.035949,-.001865,
.035727,.004405,
.034419,.010542,
.032065,.016359,
.0302,.01959,
.02511,.01451,
90.*
4,1,16,.01451,-.02511,
.009929,-.027248,
.005047,-.028558,
.000011,-.029001,
-.005025,-.028562,
-.009909,-.027256,
-.014491,-.025121,
-.01451,-.02511,
-.01959,-.0302,
-.014048,-.033143,
-.00808,-.035079,
-.001865,-.035949,
.004405,-.035727,
.010542,-.034419,
.016359,-.032065,
.01959,-.0302,
.01451,-.02511,
90.*
4,1,16,-.02511,-.01451,
-.027248,-.009929,
-.028558,-.005047,
-.029001,-.000011,
-.028562,.005025,
-.027256,.009909,
-.025121,.014491,
-.02511,.01451,
-.0302,.01959,
-.033143,.014048,
-.035079,.00808,
-.035949,.001865,
-.035727,-.004405,
-.034419,-.010542,
-.032065,-.016359,
-.0302,-.01959,
-.02511,-.01451,
90.*
4,1,16,-.01451,.02511,
-.009929,.027248,
-.005047,.028558,
-.000011,.029001,
.005025,.028562,
.009909,.027256,
.014491,.025121,
.01451,.02511,
.01959,.0302,
.014048,.033143,
.00808,.035079,
.001865,.035949,
-.004405,.035727,
-.010542,.034419,
-.016359,.032065,
-.01959,.0302,
-.01451,.02511,
90.*
%
%ADD37MACRO37*%
%ADD33C,.03968*%
%AMMACRO29*
4,1,16,.02511,.01451,
.027248,.009929,
.028558,.005047,
.029001,.000011,
.028562,-.005025,
.027256,-.009909,
.025121,-.014491,
.02511,-.01451,
.0302,-.01959,
.033143,-.014048,
.035079,-.00808,
.035949,-.001865,
.035727,.004405,
.034419,.010542,
.032065,.016359,
.0302,.01959,
.02511,.01451,
0.0*
4,1,16,.01451,-.02511,
.009929,-.027248,
.005047,-.028558,
.000011,-.029001,
-.005025,-.028562,
-.009909,-.027256,
-.014491,-.025121,
-.01451,-.02511,
-.01959,-.0302,
-.014048,-.033143,
-.00808,-.035079,
-.001865,-.035949,
.004405,-.035727,
.010542,-.034419,
.016359,-.032065,
.01959,-.0302,
.01451,-.02511,
0.0*
4,1,16,-.02511,-.01451,
-.027248,-.009929,
-.028558,-.005047,
-.029001,-.000011,
-.028562,.005025,
-.027256,.009909,
-.025121,.014491,
-.02511,.01451,
-.0302,.01959,
-.033143,.014048,
-.035079,.00808,
-.035949,.001865,
-.035727,-.004405,
-.034419,-.010542,
-.032065,-.016359,
-.0302,-.01959,
-.02511,-.01451,
0.0*
4,1,16,-.01451,.02511,
-.009929,.027248,
-.005047,.028558,
-.000011,.029001,
.005025,.028562,
.009909,.027256,
.014491,.025121,
.01451,.02511,
.01959,.0302,
.014048,.033143,
.00808,.035079,
.001865,.035949,
-.004405,.035727,
-.010542,.034419,
-.016359,.032065,
-.01959,.0302,
-.01451,.02511,
0.0*
%
%ADD29MACRO29*%
%AMMACRO71*
4,1,15,.03682,.01914,
.039584,.012455,
.041146,.005393,
.041457,-.001834,
.040509,-.009005,
.03833,-.015903,
.03682,-.01914,
.04197,-.0243,
.045552,-.016643,
.04775,-.00848,
.048497,-.000059,
.047771,.008363,
.045593,.016531,
.042029,.024197,
.04197,.0243,
.03682,.01914,
0.0*
4,1,15,.01914,-.03682,
.012455,-.039584,
.005393,-.041146,
-.001834,-.041457,
-.009005,-.040509,
-.015903,-.03833,
-.01914,-.03682,
-.0243,-.04197,
-.016643,-.045552,
-.00848,-.04775,
-.000059,-.048497,
.008363,-.047771,
.016531,-.045593,
.024197,-.042029,
.0243,-.04197,
.01914,-.03682,
0.0*
4,1,15,-.03682,-.01914,
-.039584,-.012455,
-.041146,-.005393,
-.041457,.001834,
-.040509,.009005,
-.03833,.015903,
-.03682,.01914,
-.04197,.0243,
-.045552,.016643,
-.04775,.00848,
-.048497,.000059,
-.047771,-.008363,
-.045593,-.016531,
-.042029,-.024197,
-.04197,-.0243,
-.03682,-.01914,
0.0*
4,1,15,-.01914,.03682,
-.012455,.039584,
-.005393,.041146,
.001834,.041457,
.009005,.040509,
.015903,.03833,
.01914,.03682,
.0243,.04197,
.016643,.045552,
.00848,.04775,
.000059,.048497,
-.008363,.047771,
-.016531,.045593,
-.024197,.042029,
-.0243,.04197,
-.01914,.03682,
0.0*
%
%ADD71MACRO71*%
%AMMACRO68*
4,1,15,-.03682,.01914,
-.039584,.012455,
-.041146,.005393,
-.041457,-.001834,
-.040509,-.009005,
-.03833,-.015903,
-.03682,-.01914,
-.04197,-.0243,
-.045552,-.016643,
-.04775,-.00848,
-.048497,-.000059,
-.047771,.008363,
-.045593,.016531,
-.042029,.024197,
-.04197,.0243,
-.03682,.01914,
0.0*
4,1,15,-.01914,-.03682,
-.012455,-.039584,
-.005393,-.041146,
.001834,-.041457,
.009005,-.040509,
.015903,-.03833,
.01914,-.03682,
.0243,-.04197,
.016643,-.045552,
.00848,-.04775,
.000059,-.048497,
-.008363,-.047771,
-.016531,-.045593,
-.024197,-.042029,
-.0243,-.04197,
-.01914,-.03682,
0.0*
4,1,15,.03682,-.01914,
.039584,-.012455,
.041146,-.005393,
.041457,.001834,
.040509,.009005,
.03833,.015903,
.03682,.01914,
.04197,.0243,
.045552,.016643,
.04775,.00848,
.048497,.000059,
.047771,-.008363,
.045593,-.016531,
.042029,-.024197,
.04197,-.0243,
.03682,-.01914,
0.0*
4,1,15,.01914,.03682,
.012455,.039584,
.005393,.041146,
-.001834,.041457,
-.009005,.040509,
-.015903,.03833,
-.01914,.03682,
-.0243,.04197,
-.016643,.045552,
-.00848,.04775,
-.000059,.048497,
.008363,.047771,
.016531,.045593,
.024197,.042029,
.0243,.04197,
.01914,.03682,
0.0*
%
%ADD68MACRO68*%
%AMMACRO18*
4,1,25,-.0605,.00499,
-.05909,.011105,
-.05664,.016881,
-.053224,.022145,
-.048946,.026736,
-.043935,.030513,
-.038345,.033364,
-.032345,.0352,
-.02985,.03564,
-.025195,.035958,
-.02422,.03599,
-.005,.03599,
-.005,.03099,
-.02474,.03099,
-.026534,.030943,
-.028322,.030793,
-.02985,.03058,
-.035086,.029247,
-.040011,.027025,
-.044475,.023982,
-.048343,.020209,
-.051497,.015823,
-.053842,.010955,
-.055305,.005754,
-.05544,.00499,
-.0605,.00499,
0.0*
4,1,27,.005,.03599,
.02451,.03599,
.026071,.035998,
.027631,.035916,
.029183,.035743,
.02985,.03564,
.035965,.03423,
.041741,.03178,
.047005,.028364,
.051596,.024086,
.055373,.019075,
.058224,.013485,
.06006,.007485,
.0605,.00499,
.05544,.00499,
.054107,.010226,
.051885,.015151,
.048842,.019615,
.045069,.023483,
.040683,.026637,
.035815,.028982,
.030614,.030445,
.02985,.03058,
.0281,.030818,
.02634,.030955,
.02482,.03099,
.005,.03099,
.005,.03599,
0.0*
4,1,25,-.0605,-.00501,
-.05544,-.00501,
-.054107,-.010246,
-.051885,-.015171,
-.048842,-.019635,
-.045069,-.023503,
-.040683,-.026657,
-.035815,-.029002,
-.030614,-.030465,
-.02985,-.0306,
-.028079,-.03084,
-.026298,-.030976,
-.02487,-.03101,
-.005,-.03101,
-.005,-.03601,
-.02375,-.03601,
-.028562,-.035772,
-.02985,-.03566,
-.035965,-.03425,
-.041741,-.0318,
-.047005,-.028384,
-.051596,-.024106,
-.055373,-.019095,
-.058224,-.013505,
-.06006,-.007505,
-.0605,-.00501,
0.0*
4,1,27,.005,-.03101,
.02485,-.03101,
.02659,-.030963,
.028324,-.030815,
.02985,-.0306,
.035086,-.029267,
.040011,-.027045,
.044475,-.024002,
.048343,-.020229,
.051497,-.015843,
.053842,-.010975,
.055305,-.005774,
.05544,-.00501,
.0605,-.00501,
.05909,-.011125,
.05664,-.016901,
.053224,-.022165,
.048946,-.026756,
.043935,-.030533,
.038345,-.033384,
.032345,-.03522,
.02985,-.03566,
.028758,-.035841,
.027658,-.035958,
.026553,-.036011,
.02578,-.03601,
.005,-.03601,
.005,-.03101,
0.0*
%
%ADD18MACRO18*%
%ADD57R,.285X.23*%
%ADD62C,.142*%
%ADD32O,.219X.156*%
%ADD10C,.241*%
%ADD36C,.17*%
%ADD12C,.125*%
%ADD15C,.424*%
%ADD39C,.146*%
%ADD16C,.155*%
%ADD50C,.291*%
%ADD38C,.165*%
%ADD52C,.247*%
%ADD43C,.256*%
%AMMACRO26*
4,1,36,.0025,0.0,
.002462,.000434,
.002349,.000855,
.002165,.00125,
.001915,.001607,
.001607,.001915,
.00125,.002165,
.000855,.002349,
.000434,.002462,
0.0,.0025,
-.000434,.002462,
-.000855,.002349,
-.00125,.002165,
-.001607,.001915,
-.001915,.001607,
-.002165,.00125,
-.002349,.000855,
-.002462,.000434,
-.0025,0.0,
-.002462,-.000434,
-.002349,-.000855,
-.002165,-.00125,
-.001915,-.001607,
-.001607,-.001915,
-.00125,-.002165,
-.000855,-.002349,
-.000434,-.002462,
0.0,-.0025,
.000434,-.002462,
.000855,-.002349,
.00125,-.002165,
.001607,-.001915,
.001915,-.001607,
.002165,-.00125,
.002349,-.000855,
.002462,-.000434,
.0025,0.0,
90.*
%
%ADD26MACRO26*%
%AMMACRO67*
4,1,36,.003,0.0,
.002954,.000521,
.002819,.001026,
.002598,.0015,
.002298,.001928,
.001928,.002298,
.0015,.002598,
.001026,.002819,
.000521,.002954,
0.0,.003,
-.000521,.002954,
-.001026,.002819,
-.0015,.002598,
-.001928,.002298,
-.002298,.001928,
-.002598,.0015,
-.002819,.001026,
-.002954,.000521,
-.003,0.0,
-.002954,-.000521,
-.002819,-.001026,
-.002598,-.0015,
-.002298,-.001928,
-.001928,-.002298,
-.0015,-.002598,
-.001026,-.002819,
-.000521,-.002954,
0.0,-.003,
.000521,-.002954,
.001026,-.002819,
.0015,-.002598,
.001928,-.002298,
.002298,-.001928,
.002598,-.0015,
.002819,-.001026,
.002954,-.000521,
.003,0.0,
90.*
%
%ADD67MACRO67*%
%AMMACRO53*
4,1,36,0.0,.019,
-.003299,.018711,
-.006498,.017854,
-.0095,.016454,
-.012213,.014555,
-.014555,.012213,
-.016454,.0095,
-.017854,.006498,
-.018711,.003299,
-.019,0.0,
-.018711,-.003299,
-.017854,-.006498,
-.016454,-.0095,
-.014555,-.012213,
-.012213,-.014555,
-.0095,-.016454,
-.006498,-.017854,
-.003299,-.018711,
0.0,-.019,
.003299,-.018711,
.006498,-.017854,
.0095,-.016454,
.012213,-.014555,
.014555,-.012213,
.016454,-.0095,
.017854,-.006498,
.018711,-.003299,
.019,0.0,
.018711,.003299,
.017854,.006498,
.016454,.0095,
.014555,.012213,
.012213,.014555,
.0095,.016454,
.006498,.017854,
.003299,.018711,
0.0,.019,
270.*
%
%ADD53MACRO53*%
%AMMACRO23*
4,1,36,.0025,0.0,
.002462,.000434,
.002349,.000855,
.002165,.00125,
.001915,.001607,
.001607,.001915,
.00125,.002165,
.000855,.002349,
.000434,.002462,
0.0,.0025,
-.000434,.002462,
-.000855,.002349,
-.00125,.002165,
-.001607,.001915,
-.001915,.001607,
-.002165,.00125,
-.002349,.000855,
-.002462,.000434,
-.0025,0.0,
-.002462,-.000434,
-.002349,-.000855,
-.002165,-.00125,
-.001915,-.001607,
-.001607,-.001915,
-.00125,-.002165,
-.000855,-.002349,
-.000434,-.002462,
0.0,-.0025,
.000434,-.002462,
.000855,-.002349,
.00125,-.002165,
.001607,-.001915,
.001915,-.001607,
.002165,-.00125,
.002349,-.000855,
.002462,-.000434,
.0025,0.0,
0.0*
%
%ADD23MACRO23*%
%AMMACRO63*
4,1,36,-.003,0.0,
-.002954,.000521,
-.002819,.001026,
-.002598,.0015,
-.002298,.001928,
-.001928,.002298,
-.0015,.002598,
-.001026,.002819,
-.000521,.002954,
0.0,.003,
.000521,.002954,
.001026,.002819,
.0015,.002598,
.001928,.002298,
.002298,.001928,
.002598,.0015,
.002819,.001026,
.002954,.000521,
.003,0.0,
.002954,-.000521,
.002819,-.001026,
.002598,-.0015,
.002298,-.001928,
.001928,-.002298,
.0015,-.002598,
.001026,-.002819,
.000521,-.002954,
0.0,-.003,
-.000521,-.002954,
-.001026,-.002819,
-.0015,-.002598,
-.001928,-.002298,
-.002298,-.001928,
-.002598,-.0015,
-.002819,-.001026,
-.002954,-.000521,
-.003,0.0,
90.*
%
%ADD63MACRO63*%
%AMMACRO59*
4,1,36,-.0025,0.0,
-.002462,.000434,
-.002349,.000855,
-.002165,.00125,
-.001915,.001607,
-.001607,.001915,
-.00125,.002165,
-.000855,.002349,
-.000434,.002462,
0.0,.0025,
.000434,.002462,
.000855,.002349,
.00125,.002165,
.001607,.001915,
.001915,.001607,
.002165,.00125,
.002349,.000855,
.002462,.000434,
.0025,0.0,
.002462,-.000434,
.002349,-.000855,
.002165,-.00125,
.001915,-.001607,
.001607,-.001915,
.00125,-.002165,
.000855,-.002349,
.000434,-.002462,
0.0,-.0025,
-.000434,-.002462,
-.000855,-.002349,
-.00125,-.002165,
-.001607,-.001915,
-.001915,-.001607,
-.002165,-.00125,
-.002349,-.000855,
-.002462,-.000434,
-.0025,0.0,
0.0*
%
%ADD59MACRO59*%
%ADD54C,.188*%
%AMMACRO13*
4,1,36,.003,0.0,
.002954,.000521,
.002819,.001026,
.002598,.0015,
.002298,.001928,
.001928,.002298,
.0015,.002598,
.001026,.002819,
.000521,.002954,
0.0,.003,
-.000521,.002954,
-.001026,.002819,
-.0015,.002598,
-.001928,.002298,
-.002298,.001928,
-.002598,.0015,
-.002819,.001026,
-.002954,.000521,
-.003,0.0,
-.002954,-.000521,
-.002819,-.001026,
-.002598,-.0015,
-.002298,-.001928,
-.001928,-.002298,
-.0015,-.002598,
-.001026,-.002819,
-.000521,-.002954,
0.0,-.003,
.000521,-.002954,
.001026,-.002819,
.0015,-.002598,
.001928,-.002298,
.002298,-.001928,
.002598,-.0015,
.002819,-.001026,
.002954,-.000521,
.003,0.0,
0.0*
%
%ADD13MACRO13*%
%AMMACRO72*
4,1,15,.03682,.01914,
.039584,.012455,
.041146,.005393,
.041457,-.001834,
.040509,-.009005,
.03833,-.015903,
.03682,-.01914,
.04197,-.0243,
.045552,-.016643,
.04775,-.00848,
.048497,-.000059,
.047771,.008363,
.045593,.016531,
.042029,.024197,
.04197,.0243,
.03682,.01914,
180.*
4,1,15,.01914,-.03682,
.012455,-.039584,
.005393,-.041146,
-.001834,-.041457,
-.009005,-.040509,
-.015903,-.03833,
-.01914,-.03682,
-.0243,-.04197,
-.016643,-.045552,
-.00848,-.04775,
-.000059,-.048497,
.008363,-.047771,
.016531,-.045593,
.024197,-.042029,
.0243,-.04197,
.01914,-.03682,
180.*
4,1,15,-.03682,-.01914,
-.039584,-.012455,
-.041146,-.005393,
-.041457,.001834,
-.040509,.009005,
-.03833,.015903,
-.03682,.01914,
-.04197,.0243,
-.045552,.016643,
-.04775,.00848,
-.048497,.000059,
-.047771,-.008363,
-.045593,-.016531,
-.042029,-.024197,
-.04197,-.0243,
-.03682,-.01914,
180.*
4,1,15,-.01914,.03682,
-.012455,.039584,
-.005393,.041146,
.001834,.041457,
.009005,.040509,
.015903,.03833,
.01914,.03682,
.0243,.04197,
.016643,.045552,
.00848,.04775,
.000059,.048497,
-.008363,.047771,
-.016531,.045593,
-.024197,.042029,
-.0243,.04197,
-.01914,.03682,
180.*
%
%ADD72MACRO72*%
%AMMACRO70*
4,1,15,-.03682,.01914,
-.039584,.012455,
-.041146,.005393,
-.041457,-.001834,
-.040509,-.009005,
-.03833,-.015903,
-.03682,-.01914,
-.04197,-.0243,
-.045552,-.016643,
-.04775,-.00848,
-.048497,-.000059,
-.047771,.008363,
-.045593,.016531,
-.042029,.024197,
-.04197,.0243,
-.03682,.01914,
180.*
4,1,15,-.01914,-.03682,
-.012455,-.039584,
-.005393,-.041146,
.001834,-.041457,
.009005,-.040509,
.015903,-.03833,
.01914,-.03682,
.0243,-.04197,
.016643,-.045552,
.00848,-.04775,
.000059,-.048497,
-.008363,-.047771,
-.016531,-.045593,
-.024197,-.042029,
-.0243,-.04197,
-.01914,-.03682,
180.*
4,1,15,.03682,-.01914,
.039584,-.012455,
.041146,-.005393,
.041457,.001834,
.040509,.009005,
.03833,.015903,
.03682,.01914,
.04197,.0243,
.045552,.016643,
.04775,.00848,
.048497,.000059,
.047771,-.008363,
.045593,-.016531,
.042029,-.024197,
.04197,-.0243,
.03682,-.01914,
180.*
4,1,15,.01914,.03682,
.012455,.039584,
.005393,.041146,
-.001834,.041457,
-.009005,.040509,
-.015903,.03833,
-.01914,.03682,
-.0243,.04197,
-.016643,.045552,
-.00848,.04775,
-.000059,.048497,
.008363,.047771,
.016531,.045593,
.024197,.042029,
.0243,.04197,
.01914,.03682,
180.*
%
%ADD70MACRO70*%
%ADD73C,.006*%
%ADD100C,.03016*%
%ADD91C,.04006*%
%ADD88C,.03018*%
%ADD92C,.076*%
%ADD90C,.07006*%
%ADD89C,.07008*%
%ADD76C,.07306*%
%ADD81C,.07208*%
%ADD95C,.07308*%
%ADD84C,.07608*%
%ADD83C,.07808*%
%ADD82C,.09708*%
%ADD80O,.1621X.2251*%
%ADD98C,.311*%
%ADD96C,.1621*%
%ADD75O,.03004X.06404*%
%ADD99C,.16211*%
%ADD97C,.1751*%
%ADD74O,.03006X.06406*%
%ADD86C,.41506*%
%ADD85C,.43406*%
%ADD77C,.16506*%
%ADD93C,.23944*%
%ADD87C,.43376*%
%ADD94O,.43374X.77626*%
%ADD78O,.43374X.69752*%
%ADD79O,.43376X.69754*%
G75*
%LPD*%
G75*
G36*
G01X-984580Y-698988D02*
X5868320D01*
Y4193602D01*
X-984580D01*
Y-698988D01*
G37*
%LPC*%
G75*
G36*
G01X1828062Y36504D02*
X1828081Y36500D01*
G03X1828470Y36462I388J1962D01*
G03X1828859Y36500I1J2000D01*
G01X1828878Y36504D01*
X1849606D01*
G02X1855480Y30630I0J-5874D01*
G01Y-40945D01*
G02X1849606Y-46819I-5874J0D01*
G01X7874D01*
G02X2000Y-40945I0J5874D01*
G01Y30630D01*
G02X7874Y36504I5874J0D01*
G01X35835D01*
G02X41709Y30630I0J-5874D01*
G01Y-3937D01*
G03X51583Y-13811I9874J0D01*
G01X321661D01*
G03X331535Y-3937I0J9874D01*
G01Y30630D01*
G02X337409Y36504I5874J0D01*
G01X480717D01*
G02X486591Y30630I0J-5874D01*
G01Y16850D01*
G03X496465Y6976I9874J0D01*
G01X766543D01*
G03X776417Y16850I0J9874D01*
G01Y30630D01*
G02X782291Y36504I5874J0D01*
G01X879134D01*
G03X889008Y46378I0J9874D01*
G01Y122824D01*
X895188Y129004D01*
X1002542D01*
X1009024Y122522D01*
Y46378D01*
G03X1018898Y36504I9874J0D01*
G01X1510244D01*
G02X1516118Y30630I0J-5874D01*
G01Y-3937D01*
G03X1525992Y-13811I9874J0D01*
G01X1796071D01*
G03X1805945Y-3937I0J9874D01*
G01Y30630D01*
G02X1811819Y36504I5874J0D01*
G01X1828062D01*
G37*
G36*
G01X315661Y27782D02*
G02X315038Y27450I-400J0D01*
G03Y21133I-2117J-3159D01*
G02X315661Y20801I223J-332D01*
G01Y6000D01*
X57583D01*
Y17233D01*
G02X57850Y17421I200J0D01*
G01X57909Y17400D01*
X57934Y17380D01*
G03X58024Y17311I2358J2983D01*
G03X62587Y23395I2283J3041D01*
G03X58204Y23525I-2284J-3041D01*
G02X57583Y23858I-221J333D01*
G01Y38504D01*
G03X43709Y52378I-13874J0D01*
G01X7874D01*
G02X6000Y54252I0J1874D01*
G01Y305794D01*
G02X6549Y307118I1873J-1D01*
G01X9811Y310380D01*
G03X13874Y320189I-9810J9809D01*
G01Y1588078D01*
G02X14423Y1589402I1873J-1D01*
G01X27529Y1602508D01*
G03X31591Y1612315I-9809J9807D01*
G01Y1706064D01*
G02X32354Y1706232I400J0D01*
G03X51181Y1694208I18828J8729D01*
G03X71934Y1714961I0J20753D01*
G03X60774Y1733363I-20752J0D01*
G02X60958Y1734118I184J355D01*
G01X228891D01*
X228914Y1733945D01*
G03X232898I1992J267D01*
G01X232921Y1734118D01*
X244639D01*
X244662Y1733945D01*
G03X248646I1992J267D01*
G01X248669Y1734118D01*
X260387D01*
X260410Y1733945D01*
G03X264394I1992J267D01*
G01X264417Y1734118D01*
X276135D01*
X276158Y1733945D01*
G03X280142I1992J267D01*
G01X280165Y1734118D01*
X295820D01*
X295843Y1733945D01*
G03X299827I1992J267D01*
G01X299850Y1734118D01*
X311568D01*
X311591Y1733945D01*
G03X315575I1992J267D01*
G01X315598Y1734118D01*
X327316D01*
X327339Y1733945D01*
G03X331323I1992J267D01*
G01X331346Y1734118D01*
X343064D01*
X343087Y1733945D01*
G03X347071I1992J267D01*
G01X347094Y1734118D01*
X385893D01*
G02X386077Y1733363I0J-400D01*
G03X374918Y1714961I9594J-18402D01*
G03X416422I20752J0D01*
G03X405263Y1733363I-20753J0D01*
G02X405447Y1734118I184J355D01*
G01X427418D01*
Y1705442D01*
G03X425644Y1698268I13625J-7175D01*
G03X427418Y1691094I15399J1D01*
G01Y1656978D01*
X455212D01*
Y1692240D01*
G03X456442Y1698268I-14168J6031D01*
G03X455212Y1704296I-15398J-3D01*
G01Y1734118D01*
X493064D01*
X493087Y1733945D01*
G03X497071I1992J267D01*
G01X497094Y1734118D01*
X508812D01*
X508835Y1733945D01*
G03X512819I1992J267D01*
G01X512842Y1734118D01*
X524560D01*
X524583Y1733945D01*
G03X528567I1992J267D01*
G01X528590Y1734118D01*
X540308D01*
X540331Y1733945D01*
G03X544315I1992J267D01*
G01X544338Y1734118D01*
X559993D01*
X560016Y1733945D01*
G03X564000I1992J267D01*
G01X564023Y1734118D01*
X575741D01*
X575764Y1733945D01*
G03X579748I1992J267D01*
G01X579771Y1734118D01*
X591489D01*
X591512Y1733945D01*
G03X595496I1992J267D01*
G01X595519Y1734118D01*
X607237D01*
X607260Y1733945D01*
G03X611244I1992J267D01*
G01X611267Y1734118D01*
X656434D01*
X658560Y1731992D01*
Y1641270D01*
G03X658926Y1640386I1251J0D01*
G01X670238Y1629074D01*
G03X671122Y1628708I884J885D01*
G01X709835D01*
G03X711305I735J1181D01*
G01X712777D01*
G03X714805I1014J1108D01*
G01X727122D01*
Y1608233D01*
G03X727488Y1607349I1251J0D01*
G01X727922Y1606915D01*
Y1603507D01*
G03X727550Y1602518I1129J-989D01*
G03X727554Y1602417I1502J9D01*
G01X727560Y1602325D01*
X726988Y1601753D01*
G03X726622Y1600869I885J-884D01*
G01Y1577501D01*
G03X727872Y1576251I1250J0D01*
G01X743045D01*
G03X743935Y1576624I-1J1250D01*
G01X744730Y1577431D01*
G03X745090Y1578308I-890J878D01*
G01Y1588651D01*
X745940D01*
G03X746824Y1589017I0J1251D01*
G01X747656Y1589849D01*
G03X748022Y1590733I-885J884D01*
G01Y1591915D01*
X749314Y1593207D01*
X749411Y1593194D01*
G03X749612Y1593181I197J1489D01*
G03X751114Y1594683I0J1502D01*
G03X751101Y1594884I-1502J4D01*
G01X751088Y1594982D01*
X751976Y1595870D01*
X774954D01*
X778870Y1591954D01*
Y1578322D01*
G03X779236Y1577438I1251J0D01*
G01X779988Y1576686D01*
G03X780872Y1576320I884J885D01*
G01X795258D01*
G03X796142Y1576686I0J1251D01*
G01X796924Y1577468D01*
G03X797290Y1578352I-885J884D01*
G01Y1591854D01*
X797656Y1592220D01*
G03X798022Y1593104I-885J884D01*
G01Y1604234D01*
X804298Y1610510D01*
X812654D01*
X820122Y1603042D01*
Y1593082D01*
G03X820488Y1592198I1251J0D01*
G01X820870Y1591816D01*
Y1578322D01*
G03X821236Y1577438I1251J0D01*
G01X821988Y1576686D01*
G03X822872Y1576320I884J885D01*
G01X837278D01*
G03X838162Y1576686I0J1251D01*
G01X838914Y1577438D01*
G03X839280Y1578322I-885J884D01*
G01Y1591944D01*
X839614Y1592278D01*
G03X839980Y1593162I-885J884D01*
G01Y1603914D01*
X846166Y1610100D01*
X854886D01*
X862122Y1602864D01*
Y1593202D01*
G03X862488Y1592318I1251J0D01*
G01X862840Y1591966D01*
Y1578372D01*
G03X863206Y1577488I1251J0D01*
G01X864008Y1576686D01*
G03X864892Y1576320I884J885D01*
G01X879228D01*
G03X880112Y1576686I0J1251D01*
G01X880944Y1577518D01*
G03X881310Y1578402I-885J884D01*
G01Y1591922D01*
X881656Y1592268D01*
G03X882022Y1593152I-885J884D01*
G01Y1603434D01*
X889128Y1610540D01*
X896864D01*
X904022Y1603382D01*
Y1593222D01*
G03X904388Y1592338I1251J0D01*
G01X904830Y1591896D01*
Y1578352D01*
G03X905196Y1577468I1251J0D01*
G01X905988Y1576676D01*
G03X906872Y1576310I884J885D01*
G01X921248D01*
G03X922132Y1576676I0J1251D01*
G01X922924Y1577468D01*
G03X923290Y1578352I-885J884D01*
G01Y1591914D01*
X927766Y1596390D01*
X936008D01*
G03X936892Y1596756I0J1251D01*
G01X940214Y1600078D01*
X940822D01*
X941000Y1599900D01*
Y1566299D01*
G03X941092Y1565829I1250J1D01*
G01X941313Y1565284D01*
G03X941602Y1564855I1159J469D01*
G01X941807Y1564658D01*
X943672Y1562793D01*
G03X945581Y1562000I1911J1907D01*
G01X1079201D01*
G03X1079671Y1562092I-1J1250D01*
G01X1080216Y1562313D01*
G03X1080645Y1562602I-469J1159D01*
G01X1080842Y1562807D01*
X1081707Y1563672D01*
G03X1081801Y1563770I-1901J1917D01*
G02X1082380Y1563784I296J-269D01*
G01X1083798Y1562366D01*
G03X1084682Y1562000I884J885D01*
G01X1105660D01*
G03X1106544Y1562366I0J1251D01*
G01X1108636Y1564458D01*
G03X1109002Y1565342I-885J884D01*
G01Y1598066D01*
G03X1108636Y1598950I-1251J0D01*
G01X1107332Y1600254D01*
G03X1106448Y1600620I-884J-885D01*
G01X1095210D01*
G03X1095052Y1600630I-158J-1240D01*
G01X1084062D01*
G03X1083178Y1600264I0J-1251D01*
G01X1083024Y1600110D01*
G02X1082367Y1600255I-282J284D01*
G03X1081707Y1601328I-2566J-839D01*
G01X1080194Y1602842D01*
Y1603162D01*
X1081112Y1604080D01*
X1102758D01*
G03X1103642Y1604446I0J1251D01*
G01X1105274Y1606078D01*
G03X1105640Y1606962I-885J884D01*
G01Y1633288D01*
X1151544D01*
X1151601Y1633181D01*
G03X1154259I1329J698D01*
G01X1154316Y1633288D01*
X1200179D01*
X1200232Y1633170D01*
G03X1202968I1368J620D01*
G01X1203021Y1633288D01*
X1216928D01*
G03X1217812Y1633654I0J1251D01*
G01X1222474Y1638316D01*
G03X1222840Y1639200I-885J884D01*
G01Y1732462D01*
X1224496Y1734118D01*
X1236765D01*
X1236788Y1733945D01*
G03X1240772I1992J267D01*
G01X1240795Y1734118D01*
X1252513D01*
X1252536Y1733945D01*
G03X1256520I1992J267D01*
G01X1256543Y1734118D01*
X1268261D01*
X1268284Y1733945D01*
G03X1272268I1992J267D01*
G01X1272291Y1734118D01*
X1284009D01*
X1284032Y1733945D01*
G03X1288016I1992J267D01*
G01X1288039Y1734118D01*
X1303694D01*
X1303717Y1733945D01*
G03X1307701I1992J267D01*
G01X1307724Y1734118D01*
X1319442D01*
X1319465Y1733945D01*
G03X1323449I1992J267D01*
G01X1323472Y1734118D01*
X1335190D01*
X1335213Y1733945D01*
G03X1339197I1992J267D01*
G01X1339220Y1734118D01*
X1350938D01*
X1350961Y1733945D01*
G03X1354945I1992J267D01*
G01X1354968Y1734118D01*
X1402508D01*
Y1704833D01*
G03Y1691701I13929J-6566D01*
G01Y1656858D01*
X1430302D01*
Y1691571D01*
G03Y1704963I-13867J6696D01*
G01Y1734118D01*
X1452028D01*
G02X1452212Y1733363I0J-400D01*
G03X1441052Y1714961I9592J-18402D01*
G03X1482558I20753J0D01*
G03X1471398Y1733363I-20752J0D01*
G02X1471582Y1734118I184J355D01*
G01X1500938D01*
X1500961Y1733945D01*
G03X1504945I1992J267D01*
G01X1504968Y1734118D01*
X1516686D01*
X1516709Y1733945D01*
G03X1520693I1992J267D01*
G01X1520716Y1734118D01*
X1532434D01*
X1532457Y1733945D01*
G03X1536441I1992J267D01*
G01X1536464Y1734118D01*
X1548182D01*
X1548205Y1733945D01*
G03X1552189I1992J267D01*
G01X1552212Y1734118D01*
X1567867D01*
X1567890Y1733945D01*
G03X1571874I1992J267D01*
G01X1571897Y1734118D01*
X1583615D01*
X1583638Y1733945D01*
G03X1587622I1992J267D01*
G01X1587645Y1734118D01*
X1599363D01*
X1599386Y1733945D01*
G03X1603370I1992J267D01*
G01X1603393Y1734118D01*
X1615111D01*
X1615134Y1733945D01*
G03X1619118I1992J267D01*
G01X1619141Y1734118D01*
X1796522D01*
G02X1796706Y1733363I0J-400D01*
G03X1785546Y1714961I9592J-18402D01*
G03X1806299Y1694208I20753J0D01*
G03X1825127Y1706234I0J20752D01*
G02X1825890Y1706066I363J-168D01*
G01Y1612315D01*
G03X1829953Y1602506I13873J0D01*
G01X1837152Y1595307D01*
G02X1837701Y1593983I-1324J-1325D01*
G01Y1433025D01*
G02X1836974Y1432795I-400J0D01*
G03X1819209Y1442032I-17765J-12465D01*
G01X1819208D01*
G03Y1398628I0J-21702D01*
G01X1819209D01*
G03X1836974Y1407865I0J21702D01*
G02X1837701Y1407635I327J-230D01*
G01Y1373990D01*
G02X1836913Y1373894I-400J1D01*
G03X1816771Y1389650I-20142J-4996D01*
G03Y1348144I0J-20753D01*
G03X1836913Y1363900I0J20752D01*
G02X1837701Y1363804I388J-97D01*
G01Y636983D01*
G02X1836913Y636887I-400J1D01*
G03X1816771Y652642I-20142J-4998D01*
G03Y611138I0J-20752D01*
G03X1836913Y626893I0J20753D01*
G02X1837701Y626797I388J-97D01*
G01Y460596D01*
X1837562Y460551D01*
G03Y457691I457J-1430D01*
G01X1837701Y457646D01*
Y455261D01*
G03Y452581I678J-1340D01*
G01Y326094D01*
G03X1841764Y316285I13873J0D01*
G01X1850931Y307118D01*
G02X1851480Y305794I-1324J-1325D01*
G01Y54252D01*
G02X1849606Y52378I-1874J0D01*
G01X1803945D01*
G03X1790071Y38504I0J-13874D01*
G01Y27781D01*
G02X1789448Y27449I-400J0D01*
G03Y21133I-2118J-3158D01*
G02X1790071Y20801I223J-332D01*
G01Y6000D01*
X1531992D01*
Y16851D01*
G02X1532613Y17184I400J0D01*
G03Y23525I2099J3170D01*
G02X1531992Y23858I-221J333D01*
G01Y38504D01*
G03X1518118Y52378I-13874J0D01*
G01X1262702D01*
X1262658Y52517D01*
G03X1261227Y53563I-1431J-456D01*
G03X1260240Y53193I0J-1501D01*
G02X1259714I-263J302D01*
G03X1258727Y53563I-987J-1131D01*
G03X1257296Y52517I0J-1502D01*
G01X1257252Y52378D01*
X1026772D01*
G02X1024898Y54252I0J1874D01*
G01Y82853D01*
G02X1025687Y82946I400J0D01*
G03X1045865Y67042I20178J4848D01*
G03Y108548I0J20753D01*
G03X1025687Y92644I0J-20752D01*
G02X1024898Y92737I-389J93D01*
G01Y131004D01*
G03X1011024Y144878I-13874J0D01*
G01X887008D01*
G03X873134Y131004I0J-13874D01*
G01Y54252D01*
G02X871260Y52378I-1874J0D01*
G01X774417D01*
G03X762331Y45318I0J-13875D01*
G02X761585Y45473I-348J196D01*
G03X760292Y42204I-3782J-394D01*
G02X760944Y41814I262J-302D01*
G03X760543Y38504I13473J-3311D01*
G01Y26787D01*
X502465D01*
Y37639D01*
G02X503086Y37972I400J0D01*
G03X502189Y43484I2099J3171D01*
G02X501502Y43583I-315J246D01*
G03X488591Y52378I-12911J-5079D01*
G01X329535D01*
G03X315661Y38504I0J-13874D01*
G01Y27782D01*
G37*
G36*
G01X1218684Y1734118D02*
X1220340Y1732462D01*
Y1639718D01*
X1216410Y1635788D01*
X1104908D01*
X1102962Y1637734D01*
G03X1102078Y1638100I-884J-885D01*
G01X1085876D01*
X1065772Y1658204D01*
G03X1064888Y1658570I-884J-885D01*
G01X918518D01*
X909510Y1667578D01*
Y1712848D01*
G03X909144Y1713732I-1251J0D01*
G01X902102Y1720774D01*
G03X901218Y1721140I-884J-885D01*
G01X816942D01*
G03X816058Y1720774I0J-1251D01*
G01X810826Y1715542D01*
G03X810460Y1714658I885J-884D01*
G01Y1692196D01*
X776704Y1658440D01*
X758850D01*
G03X757966Y1658074I0J-1251D01*
G01X731100Y1631208D01*
X713959D01*
X713947Y1631209D01*
G03X713791Y1631218I-159J-1393D01*
G03X713635Y1631209I3J-1402D01*
G01X713623Y1631208D01*
X711019D01*
X710989Y1631217D01*
G03X710570Y1631282I-420J-1327D01*
G03X710151Y1631217I1J-1392D01*
G01X710121Y1631208D01*
X671640D01*
X661060Y1641788D01*
Y1731992D01*
X663186Y1734118D01*
X762234D01*
G03X769705Y1728921I7471J2772D01*
G01X1087854D01*
G03X1095325Y1734118I0J7969D01*
G01X1218684D01*
G37*
G36*
G01X817460Y1718640D02*
X900700D01*
X907010Y1712330D01*
Y1667060D01*
G03X907376Y1666176I1251J0D01*
G01X917116Y1656436D01*
G03X918000Y1656070I884J885D01*
G01X1064370D01*
X1084474Y1635966D01*
G03X1085358Y1635600I884J885D01*
G01X1101560D01*
X1103140Y1634020D01*
Y1607480D01*
X1102240Y1606580D01*
X943698D01*
G03X942814Y1606214I0J-1251D01*
G01X935490Y1598890D01*
X927248D01*
G03X926364Y1598524I0J-1251D01*
G01X921156Y1593316D01*
G03X920790Y1592432I885J-884D01*
G01Y1578870D01*
X920730Y1578810D01*
X907390D01*
X907330Y1578870D01*
Y1592414D01*
G03X906964Y1593298I-1251J0D01*
G01X906522Y1593740D01*
Y1603900D01*
G03X906156Y1604784I-1251J0D01*
G01X898266Y1612674D01*
G03X897382Y1613040I-884J-885D01*
G01X888610D01*
G03X887726Y1612674I0J-1251D01*
G01X879888Y1604836D01*
G03X879522Y1603952I885J-884D01*
G01Y1593670D01*
X879176Y1593324D01*
G03X878810Y1592440I885J-884D01*
G01Y1578920D01*
X878710Y1578820D01*
X865410D01*
X865340Y1578890D01*
Y1592484D01*
G03X864974Y1593368I-1251J0D01*
G01X864622Y1593720D01*
Y1603382D01*
G03X864256Y1604266I-1251J0D01*
G01X856288Y1612234D01*
G03X855404Y1612600I-884J-885D01*
G01X845648D01*
G03X844764Y1612234I0J-1251D01*
G01X837846Y1605316D01*
G03X837480Y1604432I885J-884D01*
G01Y1593680D01*
X837146Y1593346D01*
G03X836780Y1592462I885J-884D01*
G01Y1578840D01*
X836760Y1578820D01*
X823390D01*
X823370Y1578840D01*
Y1592334D01*
G03X823004Y1593218I-1251J0D01*
G01X822622Y1593600D01*
Y1603560D01*
G03X822256Y1604444I-1251J0D01*
G01X814056Y1612644D01*
G03X813172Y1613010I-884J-885D01*
G01X803780D01*
G03X802896Y1612644I0J-1251D01*
G01X795888Y1605636D01*
G03X795522Y1604752I885J-884D01*
G01Y1593622D01*
X795156Y1593256D01*
G03X794790Y1592372I885J-884D01*
G01Y1578870D01*
X794740Y1578820D01*
X781390D01*
X781370Y1578840D01*
Y1592472D01*
G03X781004Y1593356I-1251J0D01*
G01X776356Y1598004D01*
G03X775472Y1598370I-884J-885D01*
G01X751458D01*
G03X750574Y1598004I0J-1251D01*
G01X745888Y1593317D01*
G03X745522Y1592433I885J-884D01*
G01Y1591251D01*
X745422Y1591151D01*
X744540D01*
G03X743656Y1590785I0J-1251D01*
G01X742956Y1590085D01*
G03X742590Y1589201I885J-884D01*
G01Y1578820D01*
X742522Y1578751D01*
X729122D01*
Y1600351D01*
X730056Y1601285D01*
G03X730360Y1601779I-884J885D01*
G03X730554Y1602518I-1308J738D01*
G03X730438Y1603098I-1502J1D01*
G01X730422Y1603135D01*
Y1607433D01*
G03X730056Y1608317I-1251J0D01*
G01X729622Y1608751D01*
Y1626194D01*
X759368Y1655940D01*
X777222D01*
G03X778106Y1656306I0J1251D01*
G01X812594Y1690794D01*
G03X812960Y1691678I-885J884D01*
G01Y1714140D01*
X817460Y1718640D01*
G37*
G36*
G01X1077918Y1601500D02*
G02X1078058Y1601442I-1J-200D01*
G01X1079940Y1599560D01*
G03X1080000Y1599504I882J885D01*
G01Y1565496D01*
G03X1079940Y1565440I822J-941D01*
G01X1079067Y1564567D01*
G03X1079004Y1564500I879J-889D01*
G01X945496D01*
G03X945440Y1564560I-941J-822D01*
G01X943567Y1566433D01*
X943566Y1566434D01*
G03X943500Y1566496I-888J-880D01*
G01Y1600504D01*
G03X943560Y1600560I-822J941D01*
G01X944440Y1601440D01*
G03X944496Y1601500I-885J882D01*
G01X1077918D01*
G37*
G36*
G01X1105930Y1598120D02*
X1106502Y1597548D01*
Y1565860D01*
X1105142Y1564500D01*
X1085200D01*
X1084200Y1565500D01*
Y1597750D01*
X1084580Y1598130D01*
X1094904D01*
X1094915Y1598129D01*
G03X1095062Y1598120I150J1241D01*
G01X1105930D01*
G37*
G36*
G01X1867354Y305795D02*
G03X1862156Y318343I-17746J-1D01*
G01X1855296Y325203D01*
G02X1853575Y329357I4153J4154D01*
G01Y1593984D01*
G03X1848377Y1606532I-17746J-1D01*
G01X1843484Y1611425D01*
G02X1841764Y1615579I4156J4154D01*
G01Y1732244D01*
G02X1847638Y1738118I5874J0D01*
G01X1857480D01*
G03X1867354Y1747992I0J9874D01*
G01Y1815072D01*
G02X1873228Y1820946I5874J0D01*
G01X2093700D01*
G02X2099574Y1815072I0J-5874D01*
G01Y1791450D01*
G02X2093700Y1785576I-5874J0D01*
G01X2031574D01*
G03X2021700Y1775702I0J-9874D01*
G01Y1229954D01*
G03X2031574Y1220080I9874J0D01*
G01X2093700D01*
G02X2099574Y1214206I0J-5874D01*
G01Y-40945D01*
G02X2093700Y-46819I-5874J0D01*
G01X1873228D01*
G02X1867354Y-40945I0J5874D01*
G01Y305795D01*
G37*
%LPD*%
G75*
G36*
G01X1758669Y52153D02*
G02X1760173Y50649I0J-1504D01*
G01Y50648D01*
G02X1760172Y50593I-1504J0D01*
G02X1758669Y49100I-1503J10D01*
G01X1755269D01*
G02X1753766Y50593I0J1503D01*
G02X1753765Y50648I1503J55D01*
G01Y50649D01*
G02X1755269Y52153I1504J0D01*
G02X1755620Y52112I2J-1504D01*
G01X1755643Y52106D01*
X1758295D01*
X1758318Y52112D01*
G02X1758669Y52153I349J-1463D01*
G37*
G36*
G01X880168Y504762D02*
Y508162D01*
G02X881670Y509664I1502J0D01*
G02X882945Y508955I0J-1501D01*
G02X883184Y508142I-1265J-813D01*
G01Y508141D01*
G02X883173Y507963I-1504J4D01*
G01X883172Y507952D01*
Y504897D01*
X883173Y504888D01*
G02X883180Y504743I-1493J-145D01*
G01Y504742D01*
G02X881680Y503242I-1500J0D01*
G02X880398Y503963I0J1500D01*
G02X880168Y504762I1273J799D01*
G37*
G36*
G01X963269Y1556947D02*
G03X963539I135J148D01*
G02X965904Y1557866I2365J-2584D01*
G02X969159Y1555655I0J-3501D01*
G02X970402Y1554262I-159J-1393D01*
G02X969067Y1552862I-1402J0D01*
G02X965904Y1550862I-3163J1501D01*
G02X963539Y1551781I0J3503D01*
G03X963269I-135J-148D01*
G02X960904Y1550862I-2365J2584D01*
G02Y1557866I0J3502D01*
G02X963269Y1556947I0J-3503D01*
G37*
G36*
G01X986635D02*
G03X986905I135J148D01*
G02X989270Y1557866I2365J-2584D01*
G02X992522Y1555663I0J-3502D01*
G02X993868Y1554262I-56J-1401D01*
G02X992466Y1552860I-1402J0D01*
G01X992433D01*
G02X989270Y1550862I-3163J1505D01*
G02X986905Y1551781I0J3503D01*
G03X986635I-135J-148D01*
G02X984270Y1550862I-2365J2584D01*
G02Y1557866I0J3502D01*
G02X986635Y1556947I0J-3503D01*
G37*
G36*
G01X1010001D02*
G03X1010271I135J148D01*
G02X1012636Y1557866I2365J-2584D01*
G02X1015890Y1555659I0J-3502D01*
G02X1016012Y1555664I118J-1397D01*
G02Y1552860I0J-1402D01*
G01X1016009D01*
G02X1015806Y1552875I2J1402D01*
G02X1012636Y1550862I-3170J1490D01*
G02X1010271Y1551781I0J3503D01*
G03X1010001I-135J-148D01*
G02X1007636Y1550862I-2365J2584D01*
G02Y1557866I0J3502D01*
G02X1010001Y1556947I0J-3503D01*
G37*
G36*
G01X1033367D02*
G03X1033637I135J148D01*
G02X1036002Y1557866I2365J-2584D01*
G02X1039254Y1555663I0J-3502D01*
G02X1039298Y1555664I54J-1401D01*
G02Y1552860I0J-1402D01*
G02X1039167Y1552866I-1J1402D01*
G02X1036002Y1550862I-3165J1497D01*
G02X1033637Y1551781I0J3503D01*
G03X1033367I-135J-148D01*
G02X1031002Y1550862I-2365J2584D01*
G02Y1557866I0J3502D01*
G02X1033367Y1556947I0J-3503D01*
G37*
G36*
G01X1056733D02*
G03X1057003I135J148D01*
G02X1059368Y1557866I2365J-2584D01*
G02X1062623Y1555655I0J-3501D01*
G02X1063866Y1554262I-159J-1393D01*
G02X1062531Y1552862I-1402J0D01*
G02X1059368Y1550862I-3163J1501D01*
G02X1057003Y1551781I0J3503D01*
G03X1056733I-135J-148D01*
G02X1054368Y1550862I-2365J2584D01*
G02Y1557866I0J3502D01*
G02X1056733Y1556947I0J-3503D01*
G37*
G36*
G01X1080099D02*
G03X1080369I135J148D01*
G02X1082734Y1557866I2365J-2584D01*
G02X1085989Y1555655I0J-3501D01*
G02X1087232Y1554262I-159J-1393D01*
G02X1085897Y1552862I-1402J0D01*
G02X1082734Y1550862I-3163J1501D01*
G02X1080369Y1551781I0J3503D01*
G03X1080099I-135J-148D01*
G02X1077734Y1550862I-2365J2584D01*
G02Y1557866I0J3502D01*
G02X1080099Y1556947I0J-3503D01*
G37*
G36*
G01X229206Y1656840D02*
X232906D01*
G02X233208Y1656537I-1J-303D01*
G01Y1646531D01*
G02X232906Y1646228I-302J-1D01*
G01X229206D01*
G02X228904Y1646531I1J303D01*
G01Y1648936D01*
G02X228890Y1649173I2002J237D01*
G02X228904Y1649410I2016J0D01*
G01Y1653660D01*
G02X228890Y1653897I2002J237D01*
G02X228904Y1654134I2016J0D01*
G01Y1656537D01*
G02X229206Y1656840I302J1D01*
G37*
G36*
G01X276450D02*
X280150D01*
G02X280452Y1656537I-1J-303D01*
G01Y1646531D01*
G02X280150Y1646228I-302J-1D01*
G01X276450D01*
G02X276148Y1646531I1J303D01*
G01Y1648936D01*
G02X276134Y1649173I2002J237D01*
G02X276148Y1649410I2016J0D01*
G01Y1653660D01*
G02X276134Y1653897I2002J237D01*
G02X276148Y1654134I2016J0D01*
G01Y1656537D01*
G02X276450Y1656840I302J1D01*
G37*
G36*
G01X237080Y1660776D02*
X240780D01*
G02X241082Y1660474I0J-302D01*
G01Y1650468D01*
G02X240780Y1650166I-302J0D01*
G01X237080D01*
G02X236778Y1650468I0J302D01*
G01Y1652873D01*
G02X236764Y1653110I2002J237D01*
G02X236778Y1653347I2016J0D01*
G01Y1657597D01*
G02X236764Y1657834I2002J237D01*
G02X236778Y1658071I2016J0D01*
G01Y1660474D01*
G02X237080Y1660776I302J0D01*
G37*
G36*
G01X268576D02*
X272276D01*
G02X272578Y1660474I0J-302D01*
G01Y1650468D01*
G02X272276Y1650166I-302J0D01*
G01X268576D01*
G02X268274Y1650468I0J302D01*
G01Y1652873D01*
G02X268260Y1653110I2002J237D01*
G02X268274Y1653347I2016J0D01*
G01Y1657597D01*
G02X268260Y1657834I2002J237D01*
G02X268274Y1658071I2016J0D01*
G01Y1660474D01*
G02X268576Y1660776I302J0D01*
G37*
G36*
G01X284324D02*
X288024D01*
G02X288326Y1660474I0J-302D01*
G01Y1650468D01*
G02X288024Y1650166I-302J0D01*
G01X284324D01*
G02X284022Y1650468I0J302D01*
G01Y1652873D01*
G02X284008Y1653110I2002J237D01*
G02X284022Y1653347I2016J0D01*
G01Y1657597D01*
G02X284008Y1657834I2002J237D01*
G02X284022Y1658071I2016J0D01*
G01Y1660474D01*
G02X284324Y1660776I302J0D01*
G37*
G36*
G01X229206Y1671014D02*
X232906D01*
G02X233208Y1670711I-1J-303D01*
G01Y1660705D01*
G02X232906Y1660402I-302J-1D01*
G01X229206D01*
G02X228904Y1660705I1J303D01*
G01Y1663109D01*
G02X228890Y1663346I2002J237D01*
G02X228904Y1663583I2016J0D01*
G01Y1667833D01*
G02X228890Y1668070I2002J237D01*
G02X228904Y1668307I2016J0D01*
G01Y1670711D01*
G02X229206Y1671014I302J1D01*
G37*
G36*
G01X244954D02*
X248654D01*
G02X248956Y1670711I-1J-303D01*
G01Y1660705D01*
G02X248654Y1660402I-302J-1D01*
G01X244954D01*
G02X244652Y1660705I1J303D01*
G01Y1663109D01*
G02X244638Y1663346I2002J237D01*
G02X244652Y1663583I2016J0D01*
G01Y1667833D01*
G02X244638Y1668070I2002J237D01*
G02X244652Y1668307I2016J0D01*
G01Y1670711D01*
G02X244954Y1671014I302J1D01*
G37*
G36*
G01X276450D02*
X280150D01*
G02X280452Y1670711I-1J-303D01*
G01Y1660705D01*
G02X280150Y1660402I-302J-1D01*
G01X276450D01*
G02X276148Y1660705I1J303D01*
G01Y1663109D01*
G02X276134Y1663346I2002J237D01*
G02X276148Y1663583I2016J0D01*
G01Y1667833D01*
G02X276134Y1668070I2002J237D01*
G02X276148Y1668307I2016J0D01*
G01Y1670711D01*
G02X276450Y1671014I302J1D01*
G37*
G36*
G01X252828Y1674950D02*
X256528D01*
G02X256830Y1674648I0J-302D01*
G01Y1664642D01*
G02X256528Y1664340I-302J0D01*
G01X252828D01*
G02X252526Y1664642I0J302D01*
G01Y1667046D01*
G02X252512Y1667283I2002J237D01*
G02X252526Y1667520I2016J0D01*
G01Y1671770D01*
G02X252512Y1672007I2002J237D01*
G02X252526Y1672244I2016J0D01*
G01Y1674648D01*
G02X252828Y1674950I302J0D01*
G37*
G36*
G01X268576D02*
X272276D01*
G02X272578Y1674648I0J-302D01*
G01Y1664642D01*
G02X272276Y1664340I-302J0D01*
G01X268576D01*
G02X268274Y1664642I0J302D01*
G01Y1667046D01*
G02X268260Y1667283I2002J237D01*
G02X268274Y1667520I2016J0D01*
G01Y1671770D01*
G02X268260Y1672007I2002J237D01*
G02X268274Y1672244I2016J0D01*
G01Y1674648D01*
G02X268576Y1674950I302J0D01*
G37*
G36*
G01X284324D02*
X288024D01*
G02X288326Y1674648I0J-302D01*
G01Y1664642D01*
G02X288024Y1664340I-302J0D01*
G01X284324D01*
G02X284022Y1664642I0J302D01*
G01Y1667046D01*
G02X284008Y1667283I2002J237D01*
G02X284022Y1667520I2016J0D01*
G01Y1671770D01*
G02X284008Y1672007I2002J237D01*
G02X284022Y1672244I2016J0D01*
G01Y1674648D01*
G02X284324Y1674950I302J0D01*
G37*
G36*
G01X229206Y1685186D02*
X232906D01*
G02X233208Y1684884I0J-302D01*
G01Y1674878D01*
G02X232906Y1674576I-302J0D01*
G01X229206D01*
G02X228904Y1674878I0J302D01*
G01Y1677282D01*
G02X228890Y1677519I2002J237D01*
G02X228904Y1677756I2016J0D01*
G01Y1682007D01*
G02X228890Y1682244I2002J237D01*
G02X228904Y1682481I2016J0D01*
G01Y1684884D01*
G02X229206Y1685186I302J0D01*
G37*
G36*
G01X244954D02*
X248654D01*
G02X248956Y1684884I0J-302D01*
G01Y1674878D01*
G02X248654Y1674576I-302J0D01*
G01X244954D01*
G02X244652Y1674878I0J302D01*
G01Y1677282D01*
G02X244638Y1677519I2002J237D01*
G02X244652Y1677756I2016J0D01*
G01Y1682007D01*
G02X244638Y1682244I2002J237D01*
G02X244652Y1682481I2016J0D01*
G01Y1684884D01*
G02X244954Y1685186I302J0D01*
G37*
G36*
G01X260702D02*
X264402D01*
G02X264704Y1684884I0J-302D01*
G01Y1674878D01*
G02X264402Y1674576I-302J0D01*
G01X260702D01*
G02X260400Y1674878I0J302D01*
G01Y1677282D01*
G02X260386Y1677519I2002J237D01*
G02X260400Y1677756I2016J0D01*
G01Y1682007D01*
G02X260386Y1682244I2002J237D01*
G02X260400Y1682481I2016J0D01*
G01Y1684884D01*
G02X260702Y1685186I302J0D01*
G37*
G36*
G01X276450D02*
X280150D01*
G02X280452Y1684884I0J-302D01*
G01Y1674878D01*
G02X280150Y1674576I-302J0D01*
G01X276450D01*
G02X276148Y1674878I0J302D01*
G01Y1677282D01*
G02X276134Y1677519I2002J237D01*
G02X276148Y1677756I2016J0D01*
G01Y1682007D01*
G02X276134Y1682244I2002J237D01*
G02X276148Y1682481I2016J0D01*
G01Y1684884D01*
G02X276450Y1685186I302J0D01*
G37*
G36*
G01X560308D02*
X564008D01*
G02X564310Y1684884I0J-302D01*
G01Y1674878D01*
G02X564008Y1674576I-302J0D01*
G01X560308D01*
G02X560006Y1674878I0J302D01*
G01Y1677282D01*
G02X559992Y1677519I2002J237D01*
G02X560006Y1677756I2016J0D01*
G01Y1682007D01*
G02X559992Y1682244I2002J237D01*
G02X560006Y1682481I2016J0D01*
G01Y1684884D01*
G02X560308Y1685186I302J0D01*
G37*
G36*
G01X576056D02*
X579756D01*
G02X580058Y1684884I0J-302D01*
G01Y1674878D01*
G02X579756Y1674576I-302J0D01*
G01X576056D01*
G02X575754Y1674878I0J302D01*
G01Y1677282D01*
G02X575740Y1677519I2002J237D01*
G02X575754Y1677756I2016J0D01*
G01Y1682007D01*
G02X575740Y1682244I2002J237D01*
G02X575754Y1682481I2016J0D01*
G01Y1684884D01*
G02X576056Y1685186I302J0D01*
G37*
G36*
G01X591804D02*
X595504D01*
G02X595806Y1684884I0J-302D01*
G01Y1674878D01*
G02X595504Y1674576I-302J0D01*
G01X591804D01*
G02X591502Y1674878I0J302D01*
G01Y1677282D01*
G02X591488Y1677519I2002J237D01*
G02X591502Y1677756I2016J0D01*
G01Y1682007D01*
G02X591488Y1682244I2002J237D01*
G02X591502Y1682481I2016J0D01*
G01Y1684884D01*
G02X591804Y1685186I302J0D01*
G37*
G36*
G01X607552D02*
X611252D01*
G02X611554Y1684884I0J-302D01*
G01Y1674878D01*
G02X611252Y1674576I-302J0D01*
G01X607552D01*
G02X607250Y1674878I0J302D01*
G01Y1677282D01*
G02X607236Y1677519I2002J237D01*
G02X607250Y1677756I2016J0D01*
G01Y1682007D01*
G02X607236Y1682244I2002J237D01*
G02X607250Y1682481I2016J0D01*
G01Y1684884D01*
G02X607552Y1685186I302J0D01*
G37*
G36*
G01X1237080D02*
X1240780D01*
G02X1241082Y1684884I0J-302D01*
G01Y1674878D01*
G02X1240780Y1674576I-302J0D01*
G01X1237080D01*
G02X1236778Y1674878I0J302D01*
G01Y1677282D01*
G02X1236764Y1677519I2002J237D01*
G02X1236778Y1677756I2016J0D01*
G01Y1682007D01*
G02X1236764Y1682244I2002J237D01*
G02X1236778Y1682481I2016J0D01*
G01Y1684884D01*
G02X1237080Y1685186I302J0D01*
G37*
G36*
G01X1252828D02*
X1256528D01*
G02X1256830Y1684884I0J-302D01*
G01Y1674878D01*
G02X1256528Y1674576I-302J0D01*
G01X1252828D01*
G02X1252526Y1674878I0J302D01*
G01Y1677282D01*
G02X1252512Y1677519I2002J237D01*
G02X1252526Y1677756I2016J0D01*
G01Y1682007D01*
G02X1252512Y1682244I2002J237D01*
G02X1252526Y1682481I2016J0D01*
G01Y1684884D01*
G02X1252828Y1685186I302J0D01*
G37*
G36*
G01X1268576D02*
X1272276D01*
G02X1272578Y1684884I0J-302D01*
G01Y1674878D01*
G02X1272276Y1674576I-302J0D01*
G01X1268576D01*
G02X1268274Y1674878I0J302D01*
G01Y1677282D01*
G02X1268260Y1677519I2002J237D01*
G02X1268274Y1677756I2016J0D01*
G01Y1682007D01*
G02X1268260Y1682244I2002J237D01*
G02X1268274Y1682481I2016J0D01*
G01Y1684884D01*
G02X1268576Y1685186I302J0D01*
G37*
G36*
G01X1284324D02*
X1288024D01*
G02X1288326Y1684884I0J-302D01*
G01Y1674878D01*
G02X1288024Y1674576I-302J0D01*
G01X1284324D01*
G02X1284022Y1674878I0J302D01*
G01Y1677282D01*
G02X1284008Y1677519I2002J237D01*
G02X1284022Y1677756I2016J0D01*
G01Y1682007D01*
G02X1284008Y1682244I2002J237D01*
G02X1284022Y1682481I2016J0D01*
G01Y1684884D01*
G02X1284324Y1685186I302J0D01*
G37*
G36*
G01X1568182D02*
X1571882D01*
G02X1572184Y1684884I0J-302D01*
G01Y1674878D01*
G02X1571882Y1674576I-302J0D01*
G01X1568182D01*
G02X1567880Y1674878I0J302D01*
G01Y1677282D01*
G02X1567866Y1677519I2002J237D01*
G02X1567880Y1677756I2016J0D01*
G01Y1682007D01*
G02X1567866Y1682244I2002J237D01*
G02X1567880Y1682481I2016J0D01*
G01Y1684884D01*
G02X1568182Y1685186I302J0D01*
G37*
G36*
G01X1583930D02*
X1587630D01*
G02X1587932Y1684884I0J-302D01*
G01Y1674878D01*
G02X1587630Y1674576I-302J0D01*
G01X1583930D01*
G02X1583628Y1674878I0J302D01*
G01Y1677282D01*
G02X1583614Y1677519I2002J237D01*
G02X1583628Y1677756I2016J0D01*
G01Y1682007D01*
G02X1583614Y1682244I2002J237D01*
G02X1583628Y1682481I2016J0D01*
G01Y1684884D01*
G02X1583930Y1685186I302J0D01*
G37*
G36*
G01X1599678D02*
X1603378D01*
G02X1603680Y1684884I0J-302D01*
G01Y1674878D01*
G02X1603378Y1674576I-302J0D01*
G01X1599678D01*
G02X1599376Y1674878I0J302D01*
G01Y1677282D01*
G02X1599362Y1677519I2002J237D01*
G02X1599376Y1677756I2016J0D01*
G01Y1682007D01*
G02X1599362Y1682244I2002J237D01*
G02X1599376Y1682481I2016J0D01*
G01Y1684884D01*
G02X1599678Y1685186I302J0D01*
G37*
G36*
G01X1615426D02*
X1619126D01*
G02X1619428Y1684884I0J-302D01*
G01Y1674878D01*
G02X1619126Y1674576I-302J0D01*
G01X1615426D01*
G02X1615124Y1674878I0J302D01*
G01Y1677282D01*
G02X1615110Y1677519I2002J237D01*
G02X1615124Y1677756I2016J0D01*
G01Y1682007D01*
G02X1615110Y1682244I2002J237D01*
G02X1615124Y1682481I2016J0D01*
G01Y1684884D01*
G02X1615426Y1685186I302J0D01*
G37*
G36*
G01X296135D02*
X299835D01*
G02X300138Y1684884I1J-302D01*
G01Y1674878D01*
G02X299835Y1674576I-303J1D01*
G01X296135D01*
G02X295832Y1674878I-1J302D01*
G01Y1677290D01*
G02X295819Y1677519I2003J229D01*
G02X295832Y1677748I2016J0D01*
G01Y1682015D01*
G02X295819Y1682244I2003J229D01*
G02X295832Y1682473I2016J0D01*
G01Y1684884D01*
G02X296135Y1685186I303J-1D01*
G37*
G36*
G01X311883D02*
X315583D01*
G02X315886Y1684884I1J-302D01*
G01Y1674878D01*
G02X315583Y1674576I-303J1D01*
G01X311883D01*
G02X311580Y1674878I-1J302D01*
G01Y1677290D01*
G02X311567Y1677519I2003J229D01*
G02X311580Y1677748I2016J0D01*
G01Y1682015D01*
G02X311567Y1682244I2003J229D01*
G02X311580Y1682473I2016J0D01*
G01Y1684884D01*
G02X311883Y1685186I303J-1D01*
G37*
G36*
G01X327631D02*
X331331D01*
G02X331634Y1684884I1J-302D01*
G01Y1674878D01*
G02X331331Y1674576I-303J1D01*
G01X327631D01*
G02X327328Y1674878I-1J302D01*
G01Y1677290D01*
G02X327315Y1677519I2003J229D01*
G02X327328Y1677748I2016J0D01*
G01Y1682015D01*
G02X327315Y1682244I2003J229D01*
G02X327328Y1682473I2016J0D01*
G01Y1684884D01*
G02X327631Y1685186I303J-1D01*
G37*
G36*
G01X343379D02*
X347079D01*
G02X347382Y1684884I1J-302D01*
G01Y1674878D01*
G02X347079Y1674576I-303J1D01*
G01X343379D01*
G02X343076Y1674878I-1J302D01*
G01Y1677290D01*
G02X343063Y1677519I2003J229D01*
G02X343076Y1677748I2016J0D01*
G01Y1682015D01*
G02X343063Y1682244I2003J229D01*
G02X343076Y1682473I2016J0D01*
G01Y1684884D01*
G02X343379Y1685186I303J-1D01*
G37*
G36*
G01X493379D02*
X497079D01*
G02X497382Y1684884I1J-302D01*
G01Y1674878D01*
G02X497079Y1674576I-303J1D01*
G01X493379D01*
G02X493076Y1674878I-1J302D01*
G01Y1677290D01*
G02X493063Y1677519I2003J229D01*
G02X493076Y1677748I2016J0D01*
G01Y1682015D01*
G02X493063Y1682244I2003J229D01*
G02X493076Y1682473I2016J0D01*
G01Y1684884D01*
G02X493379Y1685186I303J-1D01*
G37*
G36*
G01X509127D02*
X512827D01*
G02X513130Y1684884I1J-302D01*
G01Y1674878D01*
G02X512827Y1674576I-303J1D01*
G01X509127D01*
G02X508824Y1674878I-1J302D01*
G01Y1677290D01*
G02X508811Y1677519I2003J229D01*
G02X508824Y1677748I2016J0D01*
G01Y1682015D01*
G02X508811Y1682244I2003J229D01*
G02X508824Y1682473I2016J0D01*
G01Y1684884D01*
G02X509127Y1685186I303J-1D01*
G37*
G36*
G01X524875D02*
X528575D01*
G02X528878Y1684884I1J-302D01*
G01Y1674878D01*
G02X528575Y1674576I-303J1D01*
G01X524875D01*
G02X524572Y1674878I-1J302D01*
G01Y1677290D01*
G02X524559Y1677519I2003J229D01*
G02X524572Y1677748I2016J0D01*
G01Y1682015D01*
G02X524559Y1682244I2003J229D01*
G02X524572Y1682473I2016J0D01*
G01Y1684884D01*
G02X524875Y1685186I303J-1D01*
G37*
G36*
G01X540623D02*
X544323D01*
G02X544626Y1684884I1J-302D01*
G01Y1674878D01*
G02X544323Y1674576I-303J1D01*
G01X540623D01*
G02X540320Y1674878I-1J302D01*
G01Y1677290D01*
G02X540307Y1677519I2003J229D01*
G02X540320Y1677748I2016J0D01*
G01Y1682015D01*
G02X540307Y1682244I2003J229D01*
G02X540320Y1682473I2016J0D01*
G01Y1684884D01*
G02X540623Y1685186I303J-1D01*
G37*
G36*
G01X1304009D02*
X1307709D01*
G02X1308012Y1684884I1J-302D01*
G01Y1674878D01*
G02X1307709Y1674576I-303J1D01*
G01X1304009D01*
G02X1303706Y1674878I-1J302D01*
G01Y1677290D01*
G02X1303693Y1677519I2003J229D01*
G02X1303706Y1677748I2016J0D01*
G01Y1682015D01*
G02X1303693Y1682244I2003J229D01*
G02X1303706Y1682473I2016J0D01*
G01Y1684884D01*
G02X1304009Y1685186I303J-1D01*
G37*
G36*
G01X1319757D02*
X1323457D01*
G02X1323760Y1684884I1J-302D01*
G01Y1674878D01*
G02X1323457Y1674576I-303J1D01*
G01X1319757D01*
G02X1319454Y1674878I-1J302D01*
G01Y1677290D01*
G02X1319441Y1677519I2003J229D01*
G02X1319454Y1677748I2016J0D01*
G01Y1682015D01*
G02X1319441Y1682244I2003J229D01*
G02X1319454Y1682473I2016J0D01*
G01Y1684884D01*
G02X1319757Y1685186I303J-1D01*
G37*
G36*
G01X1335505D02*
X1339205D01*
G02X1339508Y1684884I1J-302D01*
G01Y1674878D01*
G02X1339205Y1674576I-303J1D01*
G01X1335505D01*
G02X1335202Y1674878I-1J302D01*
G01Y1677290D01*
G02X1335189Y1677519I2003J229D01*
G02X1335202Y1677748I2016J0D01*
G01Y1682015D01*
G02X1335189Y1682244I2003J229D01*
G02X1335202Y1682473I2016J0D01*
G01Y1684884D01*
G02X1335505Y1685186I303J-1D01*
G37*
G36*
G01X1351253D02*
X1354953D01*
G02X1355256Y1684884I1J-302D01*
G01Y1674878D01*
G02X1354953Y1674576I-303J1D01*
G01X1351253D01*
G02X1350950Y1674878I-1J302D01*
G01Y1677290D01*
G02X1350937Y1677519I2003J229D01*
G02X1350950Y1677748I2016J0D01*
G01Y1682015D01*
G02X1350937Y1682244I2003J229D01*
G02X1350950Y1682473I2016J0D01*
G01Y1684884D01*
G02X1351253Y1685186I303J-1D01*
G37*
G36*
G01X1501253D02*
X1504953D01*
G02X1505256Y1684884I1J-302D01*
G01Y1674878D01*
G02X1504953Y1674576I-303J1D01*
G01X1501253D01*
G02X1500950Y1674878I-1J302D01*
G01Y1677290D01*
G02X1500937Y1677519I2003J229D01*
G02X1500950Y1677748I2016J0D01*
G01Y1682015D01*
G02X1500937Y1682244I2003J229D01*
G02X1500950Y1682473I2016J0D01*
G01Y1684884D01*
G02X1501253Y1685186I303J-1D01*
G37*
G36*
G01X1517001D02*
X1520701D01*
G02X1521004Y1684884I1J-302D01*
G01Y1674878D01*
G02X1520701Y1674576I-303J1D01*
G01X1517001D01*
G02X1516698Y1674878I-1J302D01*
G01Y1677290D01*
G02X1516685Y1677519I2003J229D01*
G02X1516698Y1677748I2016J0D01*
G01Y1682015D01*
G02X1516685Y1682244I2003J229D01*
G02X1516698Y1682473I2016J0D01*
G01Y1684884D01*
G02X1517001Y1685186I303J-1D01*
G37*
G36*
G01X1532749D02*
X1536449D01*
G02X1536752Y1684884I1J-302D01*
G01Y1674878D01*
G02X1536449Y1674576I-303J1D01*
G01X1532749D01*
G02X1532446Y1674878I-1J302D01*
G01Y1677290D01*
G02X1532433Y1677519I2003J229D01*
G02X1532446Y1677748I2016J0D01*
G01Y1682015D01*
G02X1532433Y1682244I2003J229D01*
G02X1532446Y1682473I2016J0D01*
G01Y1684884D01*
G02X1532749Y1685186I303J-1D01*
G37*
G36*
G01X1548497D02*
X1552197D01*
G02X1552500Y1684884I1J-302D01*
G01Y1674878D01*
G02X1552197Y1674576I-303J1D01*
G01X1548497D01*
G02X1548194Y1674878I-1J302D01*
G01Y1677290D01*
G02X1548181Y1677519I2003J229D01*
G02X1548194Y1677748I2016J0D01*
G01Y1682015D01*
G02X1548181Y1682244I2003J229D01*
G02X1548194Y1682473I2016J0D01*
G01Y1684884D01*
G02X1548497Y1685186I303J-1D01*
G37*
G36*
G01X237080Y1689124D02*
X240780D01*
G02X241082Y1688821I-1J-303D01*
G01Y1678815D01*
G02X240780Y1678512I-302J-1D01*
G01X237080D01*
G02X236778Y1678815I1J303D01*
G01Y1681219D01*
G02X236764Y1681456I2002J237D01*
G02X236778Y1681693I2016J0D01*
G01Y1685943D01*
G02X236764Y1686180I2002J237D01*
G02X236778Y1686417I2016J0D01*
G01Y1688821D01*
G02X237080Y1689124I302J1D01*
G37*
G36*
G01X252828D02*
X256528D01*
G02X256830Y1688821I-1J-303D01*
G01Y1678815D01*
G02X256528Y1678512I-302J-1D01*
G01X252828D01*
G02X252526Y1678815I1J303D01*
G01Y1681219D01*
G02X252512Y1681456I2002J237D01*
G02X252526Y1681693I2016J0D01*
G01Y1685943D01*
G02X252512Y1686180I2002J237D01*
G02X252526Y1686417I2016J0D01*
G01Y1688821D01*
G02X252828Y1689124I302J1D01*
G37*
G36*
G01X268576D02*
X272276D01*
G02X272578Y1688821I-1J-303D01*
G01Y1678815D01*
G02X272276Y1678512I-302J-1D01*
G01X268576D01*
G02X268274Y1678815I1J303D01*
G01Y1681219D01*
G02X268260Y1681456I2002J237D01*
G02X268274Y1681693I2016J0D01*
G01Y1685943D01*
G02X268260Y1686180I2002J237D01*
G02X268274Y1686417I2016J0D01*
G01Y1688821D01*
G02X268576Y1689124I302J1D01*
G37*
G36*
G01X284324D02*
X288024D01*
G02X288326Y1688821I-1J-303D01*
G01Y1678815D01*
G02X288024Y1678512I-302J-1D01*
G01X284324D01*
G02X284022Y1678815I1J303D01*
G01Y1681219D01*
G02X284008Y1681456I2002J237D01*
G02X284022Y1681693I2016J0D01*
G01Y1685943D01*
G02X284008Y1686180I2002J237D01*
G02X284022Y1686417I2016J0D01*
G01Y1688821D01*
G02X284324Y1689124I302J1D01*
G37*
G36*
G01X304009D02*
X307709D01*
G02X308012Y1688821I0J-303D01*
G01Y1678815D01*
G02X307709Y1678512I-303J0D01*
G01X304009D01*
G02X303706Y1678815I0J303D01*
G01Y1681227D01*
G02X303693Y1681456I2003J229D01*
G02X303706Y1681685I2016J0D01*
G01Y1685951D01*
G02X303693Y1686180I2003J229D01*
G02X303706Y1686409I2016J0D01*
G01Y1688821D01*
G02X304009Y1689124I303J0D01*
G37*
G36*
G01X319757D02*
X323457D01*
G02X323760Y1688821I0J-303D01*
G01Y1678815D01*
G02X323457Y1678512I-303J0D01*
G01X319757D01*
G02X319454Y1678815I0J303D01*
G01Y1681227D01*
G02X319441Y1681456I2003J229D01*
G02X319454Y1681685I2016J0D01*
G01Y1685951D01*
G02X319441Y1686180I2003J229D01*
G02X319454Y1686409I2016J0D01*
G01Y1688821D01*
G02X319757Y1689124I303J0D01*
G37*
G36*
G01X335505D02*
X339205D01*
G02X339508Y1688821I0J-303D01*
G01Y1678815D01*
G02X339205Y1678512I-303J0D01*
G01X335505D01*
G02X335202Y1678815I0J303D01*
G01Y1681227D01*
G02X335189Y1681456I2003J229D01*
G02X335202Y1681685I2016J0D01*
G01Y1685951D01*
G02X335189Y1686180I2003J229D01*
G02X335202Y1686409I2016J0D01*
G01Y1688821D01*
G02X335505Y1689124I303J0D01*
G37*
G36*
G01X351253D02*
X354953D01*
G02X355256Y1688821I0J-303D01*
G01Y1678815D01*
G02X354953Y1678512I-303J0D01*
G01X351253D01*
G02X350950Y1678815I0J303D01*
G01Y1681227D01*
G02X350937Y1681456I2003J229D01*
G02X350950Y1681685I2016J0D01*
G01Y1685951D01*
G02X350937Y1686180I2003J229D01*
G02X350950Y1686409I2016J0D01*
G01Y1688821D01*
G02X351253Y1689124I303J0D01*
G37*
G36*
G01X501253D02*
X504953D01*
G02X505256Y1688821I0J-303D01*
G01Y1678815D01*
G02X504953Y1678512I-303J0D01*
G01X501253D01*
G02X500950Y1678815I0J303D01*
G01Y1681227D01*
G02X500937Y1681456I2003J229D01*
G02X500950Y1681685I2016J0D01*
G01Y1685951D01*
G02X500937Y1686180I2003J229D01*
G02X500950Y1686409I2016J0D01*
G01Y1688821D01*
G02X501253Y1689124I303J0D01*
G37*
G36*
G01X517001D02*
X520701D01*
G02X521004Y1688821I0J-303D01*
G01Y1678815D01*
G02X520701Y1678512I-303J0D01*
G01X517001D01*
G02X516698Y1678815I0J303D01*
G01Y1681227D01*
G02X516685Y1681456I2003J229D01*
G02X516698Y1681685I2016J0D01*
G01Y1685951D01*
G02X516685Y1686180I2003J229D01*
G02X516698Y1686409I2016J0D01*
G01Y1688821D01*
G02X517001Y1689124I303J0D01*
G37*
G36*
G01X532749D02*
X536449D01*
G02X536752Y1688821I0J-303D01*
G01Y1678815D01*
G02X536449Y1678512I-303J0D01*
G01X532749D01*
G02X532446Y1678815I0J303D01*
G01Y1681227D01*
G02X532433Y1681456I2003J229D01*
G02X532446Y1681685I2016J0D01*
G01Y1685951D01*
G02X532433Y1686180I2003J229D01*
G02X532446Y1686409I2016J0D01*
G01Y1688821D01*
G02X532749Y1689124I303J0D01*
G37*
G36*
G01X548497D02*
X552197D01*
G02X552500Y1688821I0J-303D01*
G01Y1678815D01*
G02X552197Y1678512I-303J0D01*
G01X548497D01*
G02X548194Y1678815I0J303D01*
G01Y1681227D01*
G02X548181Y1681456I2003J229D01*
G02X548194Y1681685I2016J0D01*
G01Y1685951D01*
G02X548181Y1686180I2003J229D01*
G02X548194Y1686409I2016J0D01*
G01Y1688821D01*
G02X548497Y1689124I303J0D01*
G37*
G36*
G01X568182D02*
X571882D01*
G02X572184Y1688821I-1J-303D01*
G01Y1678815D01*
G02X571882Y1678512I-302J-1D01*
G01X568182D01*
G02X567880Y1678815I1J303D01*
G01Y1681219D01*
G02X567866Y1681456I2002J237D01*
G02X567880Y1681693I2016J0D01*
G01Y1685943D01*
G02X567866Y1686180I2002J237D01*
G02X567880Y1686417I2016J0D01*
G01Y1688821D01*
G02X568182Y1689124I302J1D01*
G37*
G36*
G01X583930D02*
X587630D01*
G02X587932Y1688821I-1J-303D01*
G01Y1678815D01*
G02X587630Y1678512I-302J-1D01*
G01X583930D01*
G02X583628Y1678815I1J303D01*
G01Y1681219D01*
G02X583614Y1681456I2002J237D01*
G02X583628Y1681693I2016J0D01*
G01Y1685943D01*
G02X583614Y1686180I2002J237D01*
G02X583628Y1686417I2016J0D01*
G01Y1688821D01*
G02X583930Y1689124I302J1D01*
G37*
G36*
G01X599678D02*
X603378D01*
G02X603680Y1688821I-1J-303D01*
G01Y1678815D01*
G02X603378Y1678512I-302J-1D01*
G01X599678D01*
G02X599376Y1678815I1J303D01*
G01Y1681219D01*
G02X599362Y1681456I2002J237D01*
G02X599376Y1681693I2016J0D01*
G01Y1685943D01*
G02X599362Y1686180I2002J237D01*
G02X599376Y1686417I2016J0D01*
G01Y1688821D01*
G02X599678Y1689124I302J1D01*
G37*
G36*
G01X615426D02*
X619126D01*
G02X619428Y1688821I-1J-303D01*
G01Y1678815D01*
G02X619126Y1678512I-302J-1D01*
G01X615426D01*
G02X615124Y1678815I1J303D01*
G01Y1681219D01*
G02X615110Y1681456I2002J237D01*
G02X615124Y1681693I2016J0D01*
G01Y1685943D01*
G02X615110Y1686180I2002J237D01*
G02X615124Y1686417I2016J0D01*
G01Y1688821D01*
G02X615426Y1689124I302J1D01*
G37*
G36*
G01X1244954D02*
X1248654D01*
G02X1248956Y1688821I-1J-303D01*
G01Y1678815D01*
G02X1248654Y1678512I-302J-1D01*
G01X1244954D01*
G02X1244652Y1678815I1J303D01*
G01Y1681219D01*
G02X1244638Y1681456I2002J237D01*
G02X1244652Y1681693I2016J0D01*
G01Y1685943D01*
G02X1244638Y1686180I2002J237D01*
G02X1244652Y1686417I2016J0D01*
G01Y1688821D01*
G02X1244954Y1689124I302J1D01*
G37*
G36*
G01X1260702D02*
X1264402D01*
G02X1264704Y1688821I-1J-303D01*
G01Y1678815D01*
G02X1264402Y1678512I-302J-1D01*
G01X1260702D01*
G02X1260400Y1678815I1J303D01*
G01Y1681219D01*
G02X1260386Y1681456I2002J237D01*
G02X1260400Y1681693I2016J0D01*
G01Y1685943D01*
G02X1260386Y1686180I2002J237D01*
G02X1260400Y1686417I2016J0D01*
G01Y1688821D01*
G02X1260702Y1689124I302J1D01*
G37*
G36*
G01X1276450D02*
X1280150D01*
G02X1280452Y1688821I-1J-303D01*
G01Y1678815D01*
G02X1280150Y1678512I-302J-1D01*
G01X1276450D01*
G02X1276148Y1678815I1J303D01*
G01Y1681219D01*
G02X1276134Y1681456I2002J237D01*
G02X1276148Y1681693I2016J0D01*
G01Y1685943D01*
G02X1276134Y1686180I2002J237D01*
G02X1276148Y1686417I2016J0D01*
G01Y1688821D01*
G02X1276450Y1689124I302J1D01*
G37*
G36*
G01X1292198D02*
X1295898D01*
G02X1296200Y1688821I-1J-303D01*
G01Y1678815D01*
G02X1295898Y1678512I-302J-1D01*
G01X1292198D01*
G02X1291896Y1678815I1J303D01*
G01Y1681219D01*
G02X1291882Y1681456I2002J237D01*
G02X1291896Y1681693I2016J0D01*
G01Y1685943D01*
G02X1291882Y1686180I2002J237D01*
G02X1291896Y1686417I2016J0D01*
G01Y1688821D01*
G02X1292198Y1689124I302J1D01*
G37*
G36*
G01X1311883D02*
X1315583D01*
G02X1315886Y1688821I0J-303D01*
G01Y1678815D01*
G02X1315583Y1678512I-303J0D01*
G01X1311883D01*
G02X1311580Y1678815I0J303D01*
G01Y1681227D01*
G02X1311567Y1681456I2003J229D01*
G02X1311580Y1681685I2016J0D01*
G01Y1685951D01*
G02X1311567Y1686180I2003J229D01*
G02X1311580Y1686409I2016J0D01*
G01Y1688821D01*
G02X1311883Y1689124I303J0D01*
G37*
G36*
G01X1327631D02*
X1331331D01*
G02X1331634Y1688821I0J-303D01*
G01Y1678815D01*
G02X1331331Y1678512I-303J0D01*
G01X1327631D01*
G02X1327328Y1678815I0J303D01*
G01Y1681227D01*
G02X1327315Y1681456I2003J229D01*
G02X1327328Y1681685I2016J0D01*
G01Y1685951D01*
G02X1327315Y1686180I2003J229D01*
G02X1327328Y1686409I2016J0D01*
G01Y1688821D01*
G02X1327631Y1689124I303J0D01*
G37*
G36*
G01X1343379D02*
X1347079D01*
G02X1347382Y1688821I0J-303D01*
G01Y1678815D01*
G02X1347079Y1678512I-303J0D01*
G01X1343379D01*
G02X1343076Y1678815I0J303D01*
G01Y1681227D01*
G02X1343063Y1681456I2003J229D01*
G02X1343076Y1681685I2016J0D01*
G01Y1685951D01*
G02X1343063Y1686180I2003J229D01*
G02X1343076Y1686409I2016J0D01*
G01Y1688821D01*
G02X1343379Y1689124I303J0D01*
G37*
G36*
G01X1359127D02*
X1362827D01*
G02X1363130Y1688821I0J-303D01*
G01Y1678815D01*
G02X1362827Y1678512I-303J0D01*
G01X1359127D01*
G02X1358824Y1678815I0J303D01*
G01Y1681227D01*
G02X1358811Y1681456I2003J229D01*
G02X1358824Y1681685I2016J0D01*
G01Y1685951D01*
G02X1358811Y1686180I2003J229D01*
G02X1358824Y1686409I2016J0D01*
G01Y1688821D01*
G02X1359127Y1689124I303J0D01*
G37*
G36*
G01X1509127D02*
X1512827D01*
G02X1513130Y1688821I0J-303D01*
G01Y1678815D01*
G02X1512827Y1678512I-303J0D01*
G01X1509127D01*
G02X1508824Y1678815I0J303D01*
G01Y1681227D01*
G02X1508811Y1681456I2003J229D01*
G02X1508824Y1681685I2016J0D01*
G01Y1685951D01*
G02X1508811Y1686180I2003J229D01*
G02X1508824Y1686409I2016J0D01*
G01Y1688821D01*
G02X1509127Y1689124I303J0D01*
G37*
G36*
G01X1524875D02*
X1528575D01*
G02X1528878Y1688821I0J-303D01*
G01Y1678815D01*
G02X1528575Y1678512I-303J0D01*
G01X1524875D01*
G02X1524572Y1678815I0J303D01*
G01Y1681227D01*
G02X1524559Y1681456I2003J229D01*
G02X1524572Y1681685I2016J0D01*
G01Y1685951D01*
G02X1524559Y1686180I2003J229D01*
G02X1524572Y1686409I2016J0D01*
G01Y1688821D01*
G02X1524875Y1689124I303J0D01*
G37*
G36*
G01X1540623D02*
X1544323D01*
G02X1544626Y1688821I0J-303D01*
G01Y1678815D01*
G02X1544323Y1678512I-303J0D01*
G01X1540623D01*
G02X1540320Y1678815I0J303D01*
G01Y1681227D01*
G02X1540307Y1681456I2003J229D01*
G02X1540320Y1681685I2016J0D01*
G01Y1685951D01*
G02X1540307Y1686180I2003J229D01*
G02X1540320Y1686409I2016J0D01*
G01Y1688821D01*
G02X1540623Y1689124I303J0D01*
G37*
G36*
G01X1556371D02*
X1560071D01*
G02X1560374Y1688821I0J-303D01*
G01Y1678815D01*
G02X1560071Y1678512I-303J0D01*
G01X1556371D01*
G02X1556068Y1678815I0J303D01*
G01Y1681227D01*
G02X1556055Y1681456I2003J229D01*
G02X1556068Y1681685I2016J0D01*
G01Y1685951D01*
G02X1556055Y1686180I2003J229D01*
G02X1556068Y1686409I2016J0D01*
G01Y1688821D01*
G02X1556371Y1689124I303J0D01*
G37*
G36*
G01X1576056D02*
X1579756D01*
G02X1580058Y1688821I-1J-303D01*
G01Y1678815D01*
G02X1579756Y1678512I-302J-1D01*
G01X1576056D01*
G02X1575754Y1678815I1J303D01*
G01Y1681219D01*
G02X1575740Y1681456I2002J237D01*
G02X1575754Y1681693I2016J0D01*
G01Y1685943D01*
G02X1575740Y1686180I2002J237D01*
G02X1575754Y1686417I2016J0D01*
G01Y1688821D01*
G02X1576056Y1689124I302J1D01*
G37*
G36*
G01X1591804D02*
X1595504D01*
G02X1595806Y1688821I-1J-303D01*
G01Y1678815D01*
G02X1595504Y1678512I-302J-1D01*
G01X1591804D01*
G02X1591502Y1678815I1J303D01*
G01Y1681219D01*
G02X1591488Y1681456I2002J237D01*
G02X1591502Y1681693I2016J0D01*
G01Y1685943D01*
G02X1591488Y1686180I2002J237D01*
G02X1591502Y1686417I2016J0D01*
G01Y1688821D01*
G02X1591804Y1689124I302J1D01*
G37*
G36*
G01X1607552D02*
X1611252D01*
G02X1611554Y1688821I-1J-303D01*
G01Y1678815D01*
G02X1611252Y1678512I-302J-1D01*
G01X1607552D01*
G02X1607250Y1678815I1J303D01*
G01Y1681219D01*
G02X1607236Y1681456I2002J237D01*
G02X1607250Y1681693I2016J0D01*
G01Y1685943D01*
G02X1607236Y1686180I2002J237D01*
G02X1607250Y1686417I2016J0D01*
G01Y1688821D01*
G02X1607552Y1689124I302J1D01*
G37*
G36*
G01X1623300D02*
X1627000D01*
G02X1627302Y1688821I-1J-303D01*
G01Y1678815D01*
G02X1627000Y1678512I-302J-1D01*
G01X1623300D01*
G02X1622998Y1678815I1J303D01*
G01Y1681219D01*
G02X1622984Y1681456I2002J237D01*
G02X1622998Y1681693I2016J0D01*
G01Y1685943D01*
G02X1622984Y1686180I2002J237D01*
G02X1622998Y1686417I2016J0D01*
G01Y1688821D01*
G02X1623300Y1689124I302J1D01*
G37*
G36*
G01X229206Y1699360D02*
X232906D01*
G02X233208Y1699057I-1J-303D01*
G01Y1689051D01*
G02X232906Y1688748I-302J-1D01*
G01X229206D01*
G02X228904Y1689051I1J303D01*
G01Y1691455D01*
G02X228890Y1691692I2002J237D01*
G02X228904Y1691929I2016J0D01*
G01Y1696180D01*
G02X228890Y1696417I2002J237D01*
G02X228904Y1696654I2016J0D01*
G01Y1699057D01*
G02X229206Y1699360I302J1D01*
G37*
G36*
G01X244954D02*
X248654D01*
G02X248956Y1699057I-1J-303D01*
G01Y1689051D01*
G02X248654Y1688748I-302J-1D01*
G01X244954D01*
G02X244652Y1689051I1J303D01*
G01Y1691455D01*
G02X244638Y1691692I2002J237D01*
G02X244652Y1691929I2016J0D01*
G01Y1696180D01*
G02X244638Y1696417I2002J237D01*
G02X244652Y1696654I2016J0D01*
G01Y1699057D01*
G02X244954Y1699360I302J1D01*
G37*
G36*
G01X260702D02*
X264402D01*
G02X264704Y1699057I-1J-303D01*
G01Y1689051D01*
G02X264402Y1688748I-302J-1D01*
G01X260702D01*
G02X260400Y1689051I1J303D01*
G01Y1691455D01*
G02X260386Y1691692I2002J237D01*
G02X260400Y1691929I2016J0D01*
G01Y1696180D01*
G02X260386Y1696417I2002J237D01*
G02X260400Y1696654I2016J0D01*
G01Y1699057D01*
G02X260702Y1699360I302J1D01*
G37*
G36*
G01X276450D02*
X280150D01*
G02X280452Y1699057I-1J-303D01*
G01Y1689051D01*
G02X280150Y1688748I-302J-1D01*
G01X276450D01*
G02X276148Y1689051I1J303D01*
G01Y1691455D01*
G02X276134Y1691692I2002J237D01*
G02X276148Y1691929I2016J0D01*
G01Y1696180D01*
G02X276134Y1696417I2002J237D01*
G02X276148Y1696654I2016J0D01*
G01Y1699057D01*
G02X276450Y1699360I302J1D01*
G37*
G36*
G01X296135D02*
X299835D01*
G02X300138Y1699057I0J-303D01*
G01Y1689051D01*
G02X299835Y1688748I-303J0D01*
G01X296135D01*
G02X295832Y1689051I0J303D01*
G01Y1691463D01*
G02X295819Y1691692I2003J229D01*
G02X295832Y1691921I2016J0D01*
G01Y1696188D01*
G02X295819Y1696417I2003J229D01*
G02X295832Y1696646I2016J0D01*
G01Y1699057D01*
G02X296135Y1699360I303J0D01*
G37*
G36*
G01X311883D02*
X315583D01*
G02X315886Y1699057I0J-303D01*
G01Y1689051D01*
G02X315583Y1688748I-303J0D01*
G01X311883D01*
G02X311580Y1689051I0J303D01*
G01Y1691463D01*
G02X311567Y1691692I2003J229D01*
G02X311580Y1691921I2016J0D01*
G01Y1696188D01*
G02X311567Y1696417I2003J229D01*
G02X311580Y1696646I2016J0D01*
G01Y1699057D01*
G02X311883Y1699360I303J0D01*
G37*
G36*
G01X327631D02*
X331331D01*
G02X331634Y1699057I0J-303D01*
G01Y1689051D01*
G02X331331Y1688748I-303J0D01*
G01X327631D01*
G02X327328Y1689051I0J303D01*
G01Y1691463D01*
G02X327315Y1691692I2003J229D01*
G02X327328Y1691921I2016J0D01*
G01Y1696188D01*
G02X327315Y1696417I2003J229D01*
G02X327328Y1696646I2016J0D01*
G01Y1699057D01*
G02X327631Y1699360I303J0D01*
G37*
G36*
G01X343379D02*
X347079D01*
G02X347382Y1699057I0J-303D01*
G01Y1689051D01*
G02X347079Y1688748I-303J0D01*
G01X343379D01*
G02X343076Y1689051I0J303D01*
G01Y1691463D01*
G02X343063Y1691692I2003J229D01*
G02X343076Y1691921I2016J0D01*
G01Y1696188D01*
G02X343063Y1696417I2003J229D01*
G02X343076Y1696646I2016J0D01*
G01Y1699057D01*
G02X343379Y1699360I303J0D01*
G37*
G36*
G01X493379D02*
X497079D01*
G02X497382Y1699057I0J-303D01*
G01Y1689051D01*
G02X497079Y1688748I-303J0D01*
G01X493379D01*
G02X493076Y1689051I0J303D01*
G01Y1691463D01*
G02X493063Y1691692I2003J229D01*
G02X493076Y1691921I2016J0D01*
G01Y1696188D01*
G02X493063Y1696417I2003J229D01*
G02X493076Y1696646I2016J0D01*
G01Y1699057D01*
G02X493379Y1699360I303J0D01*
G37*
G36*
G01X509127D02*
X512827D01*
G02X513130Y1699057I0J-303D01*
G01Y1689051D01*
G02X512827Y1688748I-303J0D01*
G01X509127D01*
G02X508824Y1689051I0J303D01*
G01Y1691463D01*
G02X508811Y1691692I2003J229D01*
G02X508824Y1691921I2016J0D01*
G01Y1696188D01*
G02X508811Y1696417I2003J229D01*
G02X508824Y1696646I2016J0D01*
G01Y1699057D01*
G02X509127Y1699360I303J0D01*
G37*
G36*
G01X524875D02*
X528575D01*
G02X528878Y1699057I0J-303D01*
G01Y1689051D01*
G02X528575Y1688748I-303J0D01*
G01X524875D01*
G02X524572Y1689051I0J303D01*
G01Y1691463D01*
G02X524559Y1691692I2003J229D01*
G02X524572Y1691921I2016J0D01*
G01Y1696188D01*
G02X524559Y1696417I2003J229D01*
G02X524572Y1696646I2016J0D01*
G01Y1699057D01*
G02X524875Y1699360I303J0D01*
G37*
G36*
G01X540623D02*
X544323D01*
G02X544626Y1699057I0J-303D01*
G01Y1689051D01*
G02X544323Y1688748I-303J0D01*
G01X540623D01*
G02X540320Y1689051I0J303D01*
G01Y1691463D01*
G02X540307Y1691692I2003J229D01*
G02X540320Y1691921I2016J0D01*
G01Y1696188D01*
G02X540307Y1696417I2003J229D01*
G02X540320Y1696646I2016J0D01*
G01Y1699057D01*
G02X540623Y1699360I303J0D01*
G37*
G36*
G01X560308D02*
X564008D01*
G02X564310Y1699057I-1J-303D01*
G01Y1689051D01*
G02X564008Y1688748I-302J-1D01*
G01X560308D01*
G02X560006Y1689051I1J303D01*
G01Y1691455D01*
G02X559992Y1691692I2002J237D01*
G02X560006Y1691929I2016J0D01*
G01Y1696180D01*
G02X559992Y1696417I2002J237D01*
G02X560006Y1696654I2016J0D01*
G01Y1699057D01*
G02X560308Y1699360I302J1D01*
G37*
G36*
G01X576056D02*
X579756D01*
G02X580058Y1699057I-1J-303D01*
G01Y1689051D01*
G02X579756Y1688748I-302J-1D01*
G01X576056D01*
G02X575754Y1689051I1J303D01*
G01Y1691455D01*
G02X575740Y1691692I2002J237D01*
G02X575754Y1691929I2016J0D01*
G01Y1696180D01*
G02X575740Y1696417I2002J237D01*
G02X575754Y1696654I2016J0D01*
G01Y1699057D01*
G02X576056Y1699360I302J1D01*
G37*
G36*
G01X591804D02*
X595504D01*
G02X595806Y1699057I-1J-303D01*
G01Y1689051D01*
G02X595504Y1688748I-302J-1D01*
G01X591804D01*
G02X591502Y1689051I1J303D01*
G01Y1691455D01*
G02X591488Y1691692I2002J237D01*
G02X591502Y1691929I2016J0D01*
G01Y1696180D01*
G02X591488Y1696417I2002J237D01*
G02X591502Y1696654I2016J0D01*
G01Y1699057D01*
G02X591804Y1699360I302J1D01*
G37*
G36*
G01X607552D02*
X611252D01*
G02X611554Y1699057I-1J-303D01*
G01Y1689051D01*
G02X611252Y1688748I-302J-1D01*
G01X607552D01*
G02X607250Y1689051I1J303D01*
G01Y1691455D01*
G02X607236Y1691692I2002J237D01*
G02X607250Y1691929I2016J0D01*
G01Y1696180D01*
G02X607236Y1696417I2002J237D01*
G02X607250Y1696654I2016J0D01*
G01Y1699057D01*
G02X607552Y1699360I302J1D01*
G37*
G36*
G01X1237080D02*
X1240780D01*
G02X1241082Y1699057I-1J-303D01*
G01Y1689051D01*
G02X1240780Y1688748I-302J-1D01*
G01X1237080D01*
G02X1236778Y1689051I1J303D01*
G01Y1691455D01*
G02X1236764Y1691692I2002J237D01*
G02X1236778Y1691929I2016J0D01*
G01Y1696180D01*
G02X1236764Y1696417I2002J237D01*
G02X1236778Y1696654I2016J0D01*
G01Y1699057D01*
G02X1237080Y1699360I302J1D01*
G37*
G36*
G01X1252828D02*
X1256528D01*
G02X1256830Y1699057I-1J-303D01*
G01Y1689051D01*
G02X1256528Y1688748I-302J-1D01*
G01X1252828D01*
G02X1252526Y1689051I1J303D01*
G01Y1691455D01*
G02X1252512Y1691692I2002J237D01*
G02X1252526Y1691929I2016J0D01*
G01Y1696180D01*
G02X1252512Y1696417I2002J237D01*
G02X1252526Y1696654I2016J0D01*
G01Y1699057D01*
G02X1252828Y1699360I302J1D01*
G37*
G36*
G01X1268576D02*
X1272276D01*
G02X1272578Y1699057I-1J-303D01*
G01Y1689051D01*
G02X1272276Y1688748I-302J-1D01*
G01X1268576D01*
G02X1268274Y1689051I1J303D01*
G01Y1691455D01*
G02X1268260Y1691692I2002J237D01*
G02X1268274Y1691929I2016J0D01*
G01Y1696180D01*
G02X1268260Y1696417I2002J237D01*
G02X1268274Y1696654I2016J0D01*
G01Y1699057D01*
G02X1268576Y1699360I302J1D01*
G37*
G36*
G01X1284324D02*
X1288024D01*
G02X1288326Y1699057I-1J-303D01*
G01Y1689051D01*
G02X1288024Y1688748I-302J-1D01*
G01X1284324D01*
G02X1284022Y1689051I1J303D01*
G01Y1691455D01*
G02X1284008Y1691692I2002J237D01*
G02X1284022Y1691929I2016J0D01*
G01Y1696180D01*
G02X1284008Y1696417I2002J237D01*
G02X1284022Y1696654I2016J0D01*
G01Y1699057D01*
G02X1284324Y1699360I302J1D01*
G37*
G36*
G01X1304009D02*
X1307709D01*
G02X1308012Y1699057I0J-303D01*
G01Y1689051D01*
G02X1307709Y1688748I-303J0D01*
G01X1304009D01*
G02X1303706Y1689051I0J303D01*
G01Y1691463D01*
G02X1303693Y1691692I2003J229D01*
G02X1303706Y1691921I2016J0D01*
G01Y1696188D01*
G02X1303693Y1696417I2003J229D01*
G02X1303706Y1696646I2016J0D01*
G01Y1699057D01*
G02X1304009Y1699360I303J0D01*
G37*
G36*
G01X1319757D02*
X1323457D01*
G02X1323760Y1699057I0J-303D01*
G01Y1689051D01*
G02X1323457Y1688748I-303J0D01*
G01X1319757D01*
G02X1319454Y1689051I0J303D01*
G01Y1691463D01*
G02X1319441Y1691692I2003J229D01*
G02X1319454Y1691921I2016J0D01*
G01Y1696188D01*
G02X1319441Y1696417I2003J229D01*
G02X1319454Y1696646I2016J0D01*
G01Y1699057D01*
G02X1319757Y1699360I303J0D01*
G37*
G36*
G01X1335505D02*
X1339205D01*
G02X1339508Y1699057I0J-303D01*
G01Y1689051D01*
G02X1339205Y1688748I-303J0D01*
G01X1335505D01*
G02X1335202Y1689051I0J303D01*
G01Y1691463D01*
G02X1335189Y1691692I2003J229D01*
G02X1335202Y1691921I2016J0D01*
G01Y1696188D01*
G02X1335189Y1696417I2003J229D01*
G02X1335202Y1696646I2016J0D01*
G01Y1699057D01*
G02X1335505Y1699360I303J0D01*
G37*
G36*
G01X1351253D02*
X1354953D01*
G02X1355256Y1699057I0J-303D01*
G01Y1689051D01*
G02X1354953Y1688748I-303J0D01*
G01X1351253D01*
G02X1350950Y1689051I0J303D01*
G01Y1691463D01*
G02X1350937Y1691692I2003J229D01*
G02X1350950Y1691921I2016J0D01*
G01Y1696188D01*
G02X1350937Y1696417I2003J229D01*
G02X1350950Y1696646I2016J0D01*
G01Y1699057D01*
G02X1351253Y1699360I303J0D01*
G37*
G36*
G01X1501253D02*
X1504953D01*
G02X1505256Y1699057I0J-303D01*
G01Y1689051D01*
G02X1504953Y1688748I-303J0D01*
G01X1501253D01*
G02X1500950Y1689051I0J303D01*
G01Y1691463D01*
G02X1500937Y1691692I2003J229D01*
G02X1500950Y1691921I2016J0D01*
G01Y1696188D01*
G02X1500937Y1696417I2003J229D01*
G02X1500950Y1696646I2016J0D01*
G01Y1699057D01*
G02X1501253Y1699360I303J0D01*
G37*
G36*
G01X1517001D02*
X1520701D01*
G02X1521004Y1699057I0J-303D01*
G01Y1689051D01*
G02X1520701Y1688748I-303J0D01*
G01X1517001D01*
G02X1516698Y1689051I0J303D01*
G01Y1691463D01*
G02X1516685Y1691692I2003J229D01*
G02X1516698Y1691921I2016J0D01*
G01Y1696188D01*
G02X1516685Y1696417I2003J229D01*
G02X1516698Y1696646I2016J0D01*
G01Y1699057D01*
G02X1517001Y1699360I303J0D01*
G37*
G36*
G01X1532749D02*
X1536449D01*
G02X1536752Y1699057I0J-303D01*
G01Y1689051D01*
G02X1536449Y1688748I-303J0D01*
G01X1532749D01*
G02X1532446Y1689051I0J303D01*
G01Y1691463D01*
G02X1532433Y1691692I2003J229D01*
G02X1532446Y1691921I2016J0D01*
G01Y1696188D01*
G02X1532433Y1696417I2003J229D01*
G02X1532446Y1696646I2016J0D01*
G01Y1699057D01*
G02X1532749Y1699360I303J0D01*
G37*
G36*
G01X1548497D02*
X1552197D01*
G02X1552500Y1699057I0J-303D01*
G01Y1689051D01*
G02X1552197Y1688748I-303J0D01*
G01X1548497D01*
G02X1548194Y1689051I0J303D01*
G01Y1691463D01*
G02X1548181Y1691692I2003J229D01*
G02X1548194Y1691921I2016J0D01*
G01Y1696188D01*
G02X1548181Y1696417I2003J229D01*
G02X1548194Y1696646I2016J0D01*
G01Y1699057D01*
G02X1548497Y1699360I303J0D01*
G37*
G36*
G01X1568182D02*
X1571882D01*
G02X1572184Y1699057I-1J-303D01*
G01Y1689051D01*
G02X1571882Y1688748I-302J-1D01*
G01X1568182D01*
G02X1567880Y1689051I1J303D01*
G01Y1691455D01*
G02X1567866Y1691692I2002J237D01*
G02X1567880Y1691929I2016J0D01*
G01Y1696180D01*
G02X1567866Y1696417I2002J237D01*
G02X1567880Y1696654I2016J0D01*
G01Y1699057D01*
G02X1568182Y1699360I302J1D01*
G37*
G36*
G01X1583930D02*
X1587630D01*
G02X1587932Y1699057I-1J-303D01*
G01Y1689051D01*
G02X1587630Y1688748I-302J-1D01*
G01X1583930D01*
G02X1583628Y1689051I1J303D01*
G01Y1691455D01*
G02X1583614Y1691692I2002J237D01*
G02X1583628Y1691929I2016J0D01*
G01Y1696180D01*
G02X1583614Y1696417I2002J237D01*
G02X1583628Y1696654I2016J0D01*
G01Y1699057D01*
G02X1583930Y1699360I302J1D01*
G37*
G36*
G01X1599678D02*
X1603378D01*
G02X1603680Y1699057I-1J-303D01*
G01Y1689051D01*
G02X1603378Y1688748I-302J-1D01*
G01X1599678D01*
G02X1599376Y1689051I1J303D01*
G01Y1691455D01*
G02X1599362Y1691692I2002J237D01*
G02X1599376Y1691929I2016J0D01*
G01Y1696180D01*
G02X1599362Y1696417I2002J237D01*
G02X1599376Y1696654I2016J0D01*
G01Y1699057D01*
G02X1599678Y1699360I302J1D01*
G37*
G36*
G01X1615426D02*
X1619126D01*
G02X1619428Y1699057I-1J-303D01*
G01Y1689051D01*
G02X1619126Y1688748I-302J-1D01*
G01X1615426D01*
G02X1615124Y1689051I1J303D01*
G01Y1691455D01*
G02X1615110Y1691692I2002J237D01*
G02X1615124Y1691929I2016J0D01*
G01Y1696180D01*
G02X1615110Y1696417I2002J237D01*
G02X1615124Y1696654I2016J0D01*
G01Y1699057D01*
G02X1615426Y1699360I302J1D01*
G37*
G36*
G01X237080Y1703296D02*
X240780D01*
G02X241082Y1702994I0J-302D01*
G01Y1692988D01*
G02X240780Y1692686I-302J0D01*
G01X237080D01*
G02X236778Y1692988I0J302D01*
G01Y1695392D01*
G02X236764Y1695629I2002J237D01*
G02X236778Y1695866I2016J0D01*
G01Y1700117D01*
G02X236764Y1700354I2002J237D01*
G02X236778Y1700591I2016J0D01*
G01Y1702994D01*
G02X237080Y1703296I302J0D01*
G37*
G36*
G01X252828D02*
X256528D01*
G02X256830Y1702994I0J-302D01*
G01Y1692988D01*
G02X256528Y1692686I-302J0D01*
G01X252828D01*
G02X252526Y1692988I0J302D01*
G01Y1695392D01*
G02X252512Y1695629I2002J237D01*
G02X252526Y1695866I2016J0D01*
G01Y1700117D01*
G02X252512Y1700354I2002J237D01*
G02X252526Y1700591I2016J0D01*
G01Y1702994D01*
G02X252828Y1703296I302J0D01*
G37*
G36*
G01X268576D02*
X272276D01*
G02X272578Y1702994I0J-302D01*
G01Y1692988D01*
G02X272276Y1692686I-302J0D01*
G01X268576D01*
G02X268274Y1692988I0J302D01*
G01Y1695392D01*
G02X268260Y1695629I2002J237D01*
G02X268274Y1695866I2016J0D01*
G01Y1700117D01*
G02X268260Y1700354I2002J237D01*
G02X268274Y1700591I2016J0D01*
G01Y1702994D01*
G02X268576Y1703296I302J0D01*
G37*
G36*
G01X284324D02*
X288024D01*
G02X288326Y1702994I0J-302D01*
G01Y1692988D01*
G02X288024Y1692686I-302J0D01*
G01X284324D01*
G02X284022Y1692988I0J302D01*
G01Y1695392D01*
G02X284008Y1695629I2002J237D01*
G02X284022Y1695866I2016J0D01*
G01Y1700117D01*
G02X284008Y1700354I2002J237D01*
G02X284022Y1700591I2016J0D01*
G01Y1702994D01*
G02X284324Y1703296I302J0D01*
G37*
G36*
G01X568182D02*
X571882D01*
G02X572184Y1702994I0J-302D01*
G01Y1692988D01*
G02X571882Y1692686I-302J0D01*
G01X568182D01*
G02X567880Y1692988I0J302D01*
G01Y1695392D01*
G02X567866Y1695629I2002J237D01*
G02X567880Y1695866I2016J0D01*
G01Y1700117D01*
G02X567866Y1700354I2002J237D01*
G02X567880Y1700591I2016J0D01*
G01Y1702994D01*
G02X568182Y1703296I302J0D01*
G37*
G36*
G01X583930D02*
X587630D01*
G02X587932Y1702994I0J-302D01*
G01Y1692988D01*
G02X587630Y1692686I-302J0D01*
G01X583930D01*
G02X583628Y1692988I0J302D01*
G01Y1695392D01*
G02X583614Y1695629I2002J237D01*
G02X583628Y1695866I2016J0D01*
G01Y1700117D01*
G02X583614Y1700354I2002J237D01*
G02X583628Y1700591I2016J0D01*
G01Y1702994D01*
G02X583930Y1703296I302J0D01*
G37*
G36*
G01X599678D02*
X603378D01*
G02X603680Y1702994I0J-302D01*
G01Y1692988D01*
G02X603378Y1692686I-302J0D01*
G01X599678D01*
G02X599376Y1692988I0J302D01*
G01Y1695392D01*
G02X599362Y1695629I2002J237D01*
G02X599376Y1695866I2016J0D01*
G01Y1700117D01*
G02X599362Y1700354I2002J237D01*
G02X599376Y1700591I2016J0D01*
G01Y1702994D01*
G02X599678Y1703296I302J0D01*
G37*
G36*
G01X615426D02*
X619126D01*
G02X619428Y1702994I0J-302D01*
G01Y1692988D01*
G02X619126Y1692686I-302J0D01*
G01X615426D01*
G02X615124Y1692988I0J302D01*
G01Y1695392D01*
G02X615110Y1695629I2002J237D01*
G02X615124Y1695866I2016J0D01*
G01Y1700117D01*
G02X615110Y1700354I2002J237D01*
G02X615124Y1700591I2016J0D01*
G01Y1702994D01*
G02X615426Y1703296I302J0D01*
G37*
G36*
G01X1244954D02*
X1248654D01*
G02X1248956Y1702994I0J-302D01*
G01Y1692988D01*
G02X1248654Y1692686I-302J0D01*
G01X1244954D01*
G02X1244652Y1692988I0J302D01*
G01Y1695392D01*
G02X1244638Y1695629I2002J237D01*
G02X1244652Y1695866I2016J0D01*
G01Y1700117D01*
G02X1244638Y1700354I2002J237D01*
G02X1244652Y1700591I2016J0D01*
G01Y1702994D01*
G02X1244954Y1703296I302J0D01*
G37*
G36*
G01X1260702D02*
X1264402D01*
G02X1264704Y1702994I0J-302D01*
G01Y1692988D01*
G02X1264402Y1692686I-302J0D01*
G01X1260702D01*
G02X1260400Y1692988I0J302D01*
G01Y1695392D01*
G02X1260386Y1695629I2002J237D01*
G02X1260400Y1695866I2016J0D01*
G01Y1700117D01*
G02X1260386Y1700354I2002J237D01*
G02X1260400Y1700591I2016J0D01*
G01Y1702994D01*
G02X1260702Y1703296I302J0D01*
G37*
G36*
G01X1276450D02*
X1280150D01*
G02X1280452Y1702994I0J-302D01*
G01Y1692988D01*
G02X1280150Y1692686I-302J0D01*
G01X1276450D01*
G02X1276148Y1692988I0J302D01*
G01Y1695392D01*
G02X1276134Y1695629I2002J237D01*
G02X1276148Y1695866I2016J0D01*
G01Y1700117D01*
G02X1276134Y1700354I2002J237D01*
G02X1276148Y1700591I2016J0D01*
G01Y1702994D01*
G02X1276450Y1703296I302J0D01*
G37*
G36*
G01X1292198D02*
X1295898D01*
G02X1296200Y1702994I0J-302D01*
G01Y1692988D01*
G02X1295898Y1692686I-302J0D01*
G01X1292198D01*
G02X1291896Y1692988I0J302D01*
G01Y1695392D01*
G02X1291882Y1695629I2002J237D01*
G02X1291896Y1695866I2016J0D01*
G01Y1700117D01*
G02X1291882Y1700354I2002J237D01*
G02X1291896Y1700591I2016J0D01*
G01Y1702994D01*
G02X1292198Y1703296I302J0D01*
G37*
G36*
G01X1576056D02*
X1579756D01*
G02X1580058Y1702994I0J-302D01*
G01Y1692988D01*
G02X1579756Y1692686I-302J0D01*
G01X1576056D01*
G02X1575754Y1692988I0J302D01*
G01Y1695392D01*
G02X1575740Y1695629I2002J237D01*
G02X1575754Y1695866I2016J0D01*
G01Y1700117D01*
G02X1575740Y1700354I2002J237D01*
G02X1575754Y1700591I2016J0D01*
G01Y1702994D01*
G02X1576056Y1703296I302J0D01*
G37*
G36*
G01X1591804D02*
X1595504D01*
G02X1595806Y1702994I0J-302D01*
G01Y1692988D01*
G02X1595504Y1692686I-302J0D01*
G01X1591804D01*
G02X1591502Y1692988I0J302D01*
G01Y1695392D01*
G02X1591488Y1695629I2002J237D01*
G02X1591502Y1695866I2016J0D01*
G01Y1700117D01*
G02X1591488Y1700354I2002J237D01*
G02X1591502Y1700591I2016J0D01*
G01Y1702994D01*
G02X1591804Y1703296I302J0D01*
G37*
G36*
G01X1607552D02*
X1611252D01*
G02X1611554Y1702994I0J-302D01*
G01Y1692988D01*
G02X1611252Y1692686I-302J0D01*
G01X1607552D01*
G02X1607250Y1692988I0J302D01*
G01Y1695392D01*
G02X1607236Y1695629I2002J237D01*
G02X1607250Y1695866I2016J0D01*
G01Y1700117D01*
G02X1607236Y1700354I2002J237D01*
G02X1607250Y1700591I2016J0D01*
G01Y1702994D01*
G02X1607552Y1703296I302J0D01*
G37*
G36*
G01X1623300D02*
X1627000D01*
G02X1627302Y1702994I0J-302D01*
G01Y1692988D01*
G02X1627000Y1692686I-302J0D01*
G01X1623300D01*
G02X1622998Y1692988I0J302D01*
G01Y1695392D01*
G02X1622984Y1695629I2002J237D01*
G02X1622998Y1695866I2016J0D01*
G01Y1700117D01*
G02X1622984Y1700354I2002J237D01*
G02X1622998Y1700591I2016J0D01*
G01Y1702994D01*
G02X1623300Y1703296I302J0D01*
G37*
G36*
G01X304009D02*
X307709D01*
G02X308012Y1702994I1J-302D01*
G01Y1692988D01*
G02X307709Y1692686I-303J1D01*
G01X304009D01*
G02X303706Y1692988I-1J302D01*
G01Y1695400D01*
G02X303693Y1695629I2003J229D01*
G02X303706Y1695858I2016J0D01*
G01Y1700125D01*
G02X303693Y1700354I2003J229D01*
G02X303706Y1700583I2016J0D01*
G01Y1702994D01*
G02X304009Y1703296I303J-1D01*
G37*
G36*
G01X319757D02*
X323457D01*
G02X323760Y1702994I1J-302D01*
G01Y1692988D01*
G02X323457Y1692686I-303J1D01*
G01X319757D01*
G02X319454Y1692988I-1J302D01*
G01Y1695400D01*
G02X319441Y1695629I2003J229D01*
G02X319454Y1695858I2016J0D01*
G01Y1700125D01*
G02X319441Y1700354I2003J229D01*
G02X319454Y1700583I2016J0D01*
G01Y1702994D01*
G02X319757Y1703296I303J-1D01*
G37*
G36*
G01X335505D02*
X339205D01*
G02X339508Y1702994I1J-302D01*
G01Y1692988D01*
G02X339205Y1692686I-303J1D01*
G01X335505D01*
G02X335202Y1692988I-1J302D01*
G01Y1695400D01*
G02X335189Y1695629I2003J229D01*
G02X335202Y1695858I2016J0D01*
G01Y1700125D01*
G02X335189Y1700354I2003J229D01*
G02X335202Y1700583I2016J0D01*
G01Y1702994D01*
G02X335505Y1703296I303J-1D01*
G37*
G36*
G01X351253D02*
X354953D01*
G02X355256Y1702994I1J-302D01*
G01Y1692988D01*
G02X354953Y1692686I-303J1D01*
G01X351253D01*
G02X350950Y1692988I-1J302D01*
G01Y1695400D01*
G02X350937Y1695629I2003J229D01*
G02X350950Y1695858I2016J0D01*
G01Y1700125D01*
G02X350937Y1700354I2003J229D01*
G02X350950Y1700583I2016J0D01*
G01Y1702994D01*
G02X351253Y1703296I303J-1D01*
G37*
G36*
G01X501253D02*
X504953D01*
G02X505256Y1702994I1J-302D01*
G01Y1692988D01*
G02X504953Y1692686I-303J1D01*
G01X501253D01*
G02X500950Y1692988I-1J302D01*
G01Y1695400D01*
G02X500937Y1695629I2003J229D01*
G02X500950Y1695858I2016J0D01*
G01Y1700125D01*
G02X500937Y1700354I2003J229D01*
G02X500950Y1700583I2016J0D01*
G01Y1702994D01*
G02X501253Y1703296I303J-1D01*
G37*
G36*
G01X517001D02*
X520701D01*
G02X521004Y1702994I1J-302D01*
G01Y1692988D01*
G02X520701Y1692686I-303J1D01*
G01X517001D01*
G02X516698Y1692988I-1J302D01*
G01Y1695400D01*
G02X516685Y1695629I2003J229D01*
G02X516698Y1695858I2016J0D01*
G01Y1700125D01*
G02X516685Y1700354I2003J229D01*
G02X516698Y1700583I2016J0D01*
G01Y1702994D01*
G02X517001Y1703296I303J-1D01*
G37*
G36*
G01X532749D02*
X536449D01*
G02X536752Y1702994I1J-302D01*
G01Y1692988D01*
G02X536449Y1692686I-303J1D01*
G01X532749D01*
G02X532446Y1692988I-1J302D01*
G01Y1695400D01*
G02X532433Y1695629I2003J229D01*
G02X532446Y1695858I2016J0D01*
G01Y1700125D01*
G02X532433Y1700354I2003J229D01*
G02X532446Y1700583I2016J0D01*
G01Y1702994D01*
G02X532749Y1703296I303J-1D01*
G37*
G36*
G01X548497D02*
X552197D01*
G02X552500Y1702994I1J-302D01*
G01Y1692988D01*
G02X552197Y1692686I-303J1D01*
G01X548497D01*
G02X548194Y1692988I-1J302D01*
G01Y1695400D01*
G02X548181Y1695629I2003J229D01*
G02X548194Y1695858I2016J0D01*
G01Y1700125D01*
G02X548181Y1700354I2003J229D01*
G02X548194Y1700583I2016J0D01*
G01Y1702994D01*
G02X548497Y1703296I303J-1D01*
G37*
G36*
G01X1311883D02*
X1315583D01*
G02X1315886Y1702994I1J-302D01*
G01Y1692988D01*
G02X1315583Y1692686I-303J1D01*
G01X1311883D01*
G02X1311580Y1692988I-1J302D01*
G01Y1695400D01*
G02X1311567Y1695629I2003J229D01*
G02X1311580Y1695858I2016J0D01*
G01Y1700125D01*
G02X1311567Y1700354I2003J229D01*
G02X1311580Y1700583I2016J0D01*
G01Y1702994D01*
G02X1311883Y1703296I303J-1D01*
G37*
G36*
G01X1327631D02*
X1331331D01*
G02X1331634Y1702994I1J-302D01*
G01Y1692988D01*
G02X1331331Y1692686I-303J1D01*
G01X1327631D01*
G02X1327328Y1692988I-1J302D01*
G01Y1695400D01*
G02X1327315Y1695629I2003J229D01*
G02X1327328Y1695858I2016J0D01*
G01Y1700125D01*
G02X1327315Y1700354I2003J229D01*
G02X1327328Y1700583I2016J0D01*
G01Y1702994D01*
G02X1327631Y1703296I303J-1D01*
G37*
G36*
G01X1343379D02*
X1347079D01*
G02X1347382Y1702994I1J-302D01*
G01Y1692988D01*
G02X1347079Y1692686I-303J1D01*
G01X1343379D01*
G02X1343076Y1692988I-1J302D01*
G01Y1695400D01*
G02X1343063Y1695629I2003J229D01*
G02X1343076Y1695858I2016J0D01*
G01Y1700125D01*
G02X1343063Y1700354I2003J229D01*
G02X1343076Y1700583I2016J0D01*
G01Y1702994D01*
G02X1343379Y1703296I303J-1D01*
G37*
G36*
G01X1359127D02*
X1362827D01*
G02X1363130Y1702994I1J-302D01*
G01Y1692988D01*
G02X1362827Y1692686I-303J1D01*
G01X1359127D01*
G02X1358824Y1692988I-1J302D01*
G01Y1695400D01*
G02X1358811Y1695629I2003J229D01*
G02X1358824Y1695858I2016J0D01*
G01Y1700125D01*
G02X1358811Y1700354I2003J229D01*
G02X1358824Y1700583I2016J0D01*
G01Y1702994D01*
G02X1359127Y1703296I303J-1D01*
G37*
G36*
G01X1509127D02*
X1512827D01*
G02X1513130Y1702994I1J-302D01*
G01Y1692988D01*
G02X1512827Y1692686I-303J1D01*
G01X1509127D01*
G02X1508824Y1692988I-1J302D01*
G01Y1695400D01*
G02X1508811Y1695629I2003J229D01*
G02X1508824Y1695858I2016J0D01*
G01Y1700125D01*
G02X1508811Y1700354I2003J229D01*
G02X1508824Y1700583I2016J0D01*
G01Y1702994D01*
G02X1509127Y1703296I303J-1D01*
G37*
G36*
G01X1524875D02*
X1528575D01*
G02X1528878Y1702994I1J-302D01*
G01Y1692988D01*
G02X1528575Y1692686I-303J1D01*
G01X1524875D01*
G02X1524572Y1692988I-1J302D01*
G01Y1695400D01*
G02X1524559Y1695629I2003J229D01*
G02X1524572Y1695858I2016J0D01*
G01Y1700125D01*
G02X1524559Y1700354I2003J229D01*
G02X1524572Y1700583I2016J0D01*
G01Y1702994D01*
G02X1524875Y1703296I303J-1D01*
G37*
G36*
G01X1540623D02*
X1544323D01*
G02X1544626Y1702994I1J-302D01*
G01Y1692988D01*
G02X1544323Y1692686I-303J1D01*
G01X1540623D01*
G02X1540320Y1692988I-1J302D01*
G01Y1695400D01*
G02X1540307Y1695629I2003J229D01*
G02X1540320Y1695858I2016J0D01*
G01Y1700125D01*
G02X1540307Y1700354I2003J229D01*
G02X1540320Y1700583I2016J0D01*
G01Y1702994D01*
G02X1540623Y1703296I303J-1D01*
G37*
G36*
G01X1556371D02*
X1560071D01*
G02X1560374Y1702994I1J-302D01*
G01Y1692988D01*
G02X1560071Y1692686I-303J1D01*
G01X1556371D01*
G02X1556068Y1692988I-1J302D01*
G01Y1695400D01*
G02X1556055Y1695629I2003J229D01*
G02X1556068Y1695858I2016J0D01*
G01Y1700125D01*
G02X1556055Y1700354I2003J229D01*
G02X1556068Y1700583I2016J0D01*
G01Y1702994D01*
G02X1556371Y1703296I303J-1D01*
G37*
G36*
G01X229206Y1713532D02*
X232906D01*
G02X233208Y1713230I0J-302D01*
G01Y1703224D01*
G02X232906Y1702922I-302J0D01*
G01X229206D01*
G02X228904Y1703224I0J302D01*
G01Y1705629D01*
G02X228890Y1705866I2002J237D01*
G02X228904Y1706103I2016J0D01*
G01Y1710353D01*
G02X228890Y1710590I2002J237D01*
G02X228904Y1710827I2016J0D01*
G01Y1713230D01*
G02X229206Y1713532I302J0D01*
G37*
G36*
G01X244954D02*
X248654D01*
G02X248956Y1713230I0J-302D01*
G01Y1703224D01*
G02X248654Y1702922I-302J0D01*
G01X244954D01*
G02X244652Y1703224I0J302D01*
G01Y1705629D01*
G02X244638Y1705866I2002J237D01*
G02X244652Y1706103I2016J0D01*
G01Y1710353D01*
G02X244638Y1710590I2002J237D01*
G02X244652Y1710827I2016J0D01*
G01Y1713230D01*
G02X244954Y1713532I302J0D01*
G37*
G36*
G01X260702D02*
X264402D01*
G02X264704Y1713230I0J-302D01*
G01Y1703224D01*
G02X264402Y1702922I-302J0D01*
G01X260702D01*
G02X260400Y1703224I0J302D01*
G01Y1705629D01*
G02X260386Y1705866I2002J237D01*
G02X260400Y1706103I2016J0D01*
G01Y1710353D01*
G02X260386Y1710590I2002J237D01*
G02X260400Y1710827I2016J0D01*
G01Y1713230D01*
G02X260702Y1713532I302J0D01*
G37*
G36*
G01X276450D02*
X280150D01*
G02X280452Y1713230I0J-302D01*
G01Y1703224D01*
G02X280150Y1702922I-302J0D01*
G01X276450D01*
G02X276148Y1703224I0J302D01*
G01Y1705629D01*
G02X276134Y1705866I2002J237D01*
G02X276148Y1706103I2016J0D01*
G01Y1710353D01*
G02X276134Y1710590I2002J237D01*
G02X276148Y1710827I2016J0D01*
G01Y1713230D01*
G02X276450Y1713532I302J0D01*
G37*
G36*
G01X560308D02*
X564008D01*
G02X564310Y1713230I0J-302D01*
G01Y1703224D01*
G02X564008Y1702922I-302J0D01*
G01X560308D01*
G02X560006Y1703224I0J302D01*
G01Y1705629D01*
G02X559992Y1705866I2002J237D01*
G02X560006Y1706103I2016J0D01*
G01Y1710353D01*
G02X559992Y1710590I2002J237D01*
G02X560006Y1710827I2016J0D01*
G01Y1713230D01*
G02X560308Y1713532I302J0D01*
G37*
G36*
G01X576056D02*
X579756D01*
G02X580058Y1713230I0J-302D01*
G01Y1703224D01*
G02X579756Y1702922I-302J0D01*
G01X576056D01*
G02X575754Y1703224I0J302D01*
G01Y1705629D01*
G02X575740Y1705866I2002J237D01*
G02X575754Y1706103I2016J0D01*
G01Y1710353D01*
G02X575740Y1710590I2002J237D01*
G02X575754Y1710827I2016J0D01*
G01Y1713230D01*
G02X576056Y1713532I302J0D01*
G37*
G36*
G01X591804D02*
X595504D01*
G02X595806Y1713230I0J-302D01*
G01Y1703224D01*
G02X595504Y1702922I-302J0D01*
G01X591804D01*
G02X591502Y1703224I0J302D01*
G01Y1705629D01*
G02X591488Y1705866I2002J237D01*
G02X591502Y1706103I2016J0D01*
G01Y1710353D01*
G02X591488Y1710590I2002J237D01*
G02X591502Y1710827I2016J0D01*
G01Y1713230D01*
G02X591804Y1713532I302J0D01*
G37*
G36*
G01X607552D02*
X611252D01*
G02X611554Y1713230I0J-302D01*
G01Y1703224D01*
G02X611252Y1702922I-302J0D01*
G01X607552D01*
G02X607250Y1703224I0J302D01*
G01Y1705629D01*
G02X607236Y1705866I2002J237D01*
G02X607250Y1706103I2016J0D01*
G01Y1710353D01*
G02X607236Y1710590I2002J237D01*
G02X607250Y1710827I2016J0D01*
G01Y1713230D01*
G02X607552Y1713532I302J0D01*
G37*
G36*
G01X1237080D02*
X1240780D01*
G02X1241082Y1713230I0J-302D01*
G01Y1703224D01*
G02X1240780Y1702922I-302J0D01*
G01X1237080D01*
G02X1236778Y1703224I0J302D01*
G01Y1705629D01*
G02X1236764Y1705866I2002J237D01*
G02X1236778Y1706103I2016J0D01*
G01Y1710353D01*
G02X1236764Y1710590I2002J237D01*
G02X1236778Y1710827I2016J0D01*
G01Y1713230D01*
G02X1237080Y1713532I302J0D01*
G37*
G36*
G01X1252828D02*
X1256528D01*
G02X1256830Y1713230I0J-302D01*
G01Y1703224D01*
G02X1256528Y1702922I-302J0D01*
G01X1252828D01*
G02X1252526Y1703224I0J302D01*
G01Y1705629D01*
G02X1252512Y1705866I2002J237D01*
G02X1252526Y1706103I2016J0D01*
G01Y1710353D01*
G02X1252512Y1710590I2002J237D01*
G02X1252526Y1710827I2016J0D01*
G01Y1713230D01*
G02X1252828Y1713532I302J0D01*
G37*
G36*
G01X1268576D02*
X1272276D01*
G02X1272578Y1713230I0J-302D01*
G01Y1703224D01*
G02X1272276Y1702922I-302J0D01*
G01X1268576D01*
G02X1268274Y1703224I0J302D01*
G01Y1705629D01*
G02X1268260Y1705866I2002J237D01*
G02X1268274Y1706103I2016J0D01*
G01Y1710353D01*
G02X1268260Y1710590I2002J237D01*
G02X1268274Y1710827I2016J0D01*
G01Y1713230D01*
G02X1268576Y1713532I302J0D01*
G37*
G36*
G01X1284324D02*
X1288024D01*
G02X1288326Y1713230I0J-302D01*
G01Y1703224D01*
G02X1288024Y1702922I-302J0D01*
G01X1284324D01*
G02X1284022Y1703224I0J302D01*
G01Y1705629D01*
G02X1284008Y1705866I2002J237D01*
G02X1284022Y1706103I2016J0D01*
G01Y1710353D01*
G02X1284008Y1710590I2002J237D01*
G02X1284022Y1710827I2016J0D01*
G01Y1713230D01*
G02X1284324Y1713532I302J0D01*
G37*
G36*
G01X1568182D02*
X1571882D01*
G02X1572184Y1713230I0J-302D01*
G01Y1703224D01*
G02X1571882Y1702922I-302J0D01*
G01X1568182D01*
G02X1567880Y1703224I0J302D01*
G01Y1705629D01*
G02X1567866Y1705866I2002J237D01*
G02X1567880Y1706103I2016J0D01*
G01Y1710353D01*
G02X1567866Y1710590I2002J237D01*
G02X1567880Y1710827I2016J0D01*
G01Y1713230D01*
G02X1568182Y1713532I302J0D01*
G37*
G36*
G01X1583930D02*
X1587630D01*
G02X1587932Y1713230I0J-302D01*
G01Y1703224D01*
G02X1587630Y1702922I-302J0D01*
G01X1583930D01*
G02X1583628Y1703224I0J302D01*
G01Y1705629D01*
G02X1583614Y1705866I2002J237D01*
G02X1583628Y1706103I2016J0D01*
G01Y1710353D01*
G02X1583614Y1710590I2002J237D01*
G02X1583628Y1710827I2016J0D01*
G01Y1713230D01*
G02X1583930Y1713532I302J0D01*
G37*
G36*
G01X1599678D02*
X1603378D01*
G02X1603680Y1713230I0J-302D01*
G01Y1703224D01*
G02X1603378Y1702922I-302J0D01*
G01X1599678D01*
G02X1599376Y1703224I0J302D01*
G01Y1705629D01*
G02X1599362Y1705866I2002J237D01*
G02X1599376Y1706103I2016J0D01*
G01Y1710353D01*
G02X1599362Y1710590I2002J237D01*
G02X1599376Y1710827I2016J0D01*
G01Y1713230D01*
G02X1599678Y1713532I302J0D01*
G37*
G36*
G01X1615426D02*
X1619126D01*
G02X1619428Y1713230I0J-302D01*
G01Y1703224D01*
G02X1619126Y1702922I-302J0D01*
G01X1615426D01*
G02X1615124Y1703224I0J302D01*
G01Y1705629D01*
G02X1615110Y1705866I2002J237D01*
G02X1615124Y1706103I2016J0D01*
G01Y1710353D01*
G02X1615110Y1710590I2002J237D01*
G02X1615124Y1710827I2016J0D01*
G01Y1713230D01*
G02X1615426Y1713532I302J0D01*
G37*
G36*
G01X296135D02*
X299835D01*
G02X300138Y1713230I1J-302D01*
G01Y1703224D01*
G02X299835Y1702922I-303J1D01*
G01X296135D01*
G02X295832Y1703224I-1J302D01*
G01Y1705637D01*
G02X295819Y1705866I2003J229D01*
G02X295832Y1706095I2016J0D01*
G01Y1710361D01*
G02X295819Y1710590I2003J229D01*
G02X295832Y1710819I2016J0D01*
G01Y1713230D01*
G02X296135Y1713532I303J-1D01*
G37*
G36*
G01X311883D02*
X315583D01*
G02X315886Y1713230I1J-302D01*
G01Y1703224D01*
G02X315583Y1702922I-303J1D01*
G01X311883D01*
G02X311580Y1703224I-1J302D01*
G01Y1705637D01*
G02X311567Y1705866I2003J229D01*
G02X311580Y1706095I2016J0D01*
G01Y1710361D01*
G02X311567Y1710590I2003J229D01*
G02X311580Y1710819I2016J0D01*
G01Y1713230D01*
G02X311883Y1713532I303J-1D01*
G37*
G36*
G01X327631D02*
X331331D01*
G02X331634Y1713230I1J-302D01*
G01Y1703224D01*
G02X331331Y1702922I-303J1D01*
G01X327631D01*
G02X327328Y1703224I-1J302D01*
G01Y1705637D01*
G02X327315Y1705866I2003J229D01*
G02X327328Y1706095I2016J0D01*
G01Y1710361D01*
G02X327315Y1710590I2003J229D01*
G02X327328Y1710819I2016J0D01*
G01Y1713230D01*
G02X327631Y1713532I303J-1D01*
G37*
G36*
G01X343379D02*
X347079D01*
G02X347382Y1713230I1J-302D01*
G01Y1703224D01*
G02X347079Y1702922I-303J1D01*
G01X343379D01*
G02X343076Y1703224I-1J302D01*
G01Y1705637D01*
G02X343063Y1705866I2003J229D01*
G02X343076Y1706095I2016J0D01*
G01Y1710361D01*
G02X343063Y1710590I2003J229D01*
G02X343076Y1710819I2016J0D01*
G01Y1713230D01*
G02X343379Y1713532I303J-1D01*
G37*
G36*
G01X493379D02*
X497079D01*
G02X497382Y1713230I1J-302D01*
G01Y1703224D01*
G02X497079Y1702922I-303J1D01*
G01X493379D01*
G02X493076Y1703224I-1J302D01*
G01Y1705637D01*
G02X493063Y1705866I2003J229D01*
G02X493076Y1706095I2016J0D01*
G01Y1710361D01*
G02X493063Y1710590I2003J229D01*
G02X493076Y1710819I2016J0D01*
G01Y1713230D01*
G02X493379Y1713532I303J-1D01*
G37*
G36*
G01X509127D02*
X512827D01*
G02X513130Y1713230I1J-302D01*
G01Y1703224D01*
G02X512827Y1702922I-303J1D01*
G01X509127D01*
G02X508824Y1703224I-1J302D01*
G01Y1705637D01*
G02X508811Y1705866I2003J229D01*
G02X508824Y1706095I2016J0D01*
G01Y1710361D01*
G02X508811Y1710590I2003J229D01*
G02X508824Y1710819I2016J0D01*
G01Y1713230D01*
G02X509127Y1713532I303J-1D01*
G37*
G36*
G01X524875D02*
X528575D01*
G02X528878Y1713230I1J-302D01*
G01Y1703224D01*
G02X528575Y1702922I-303J1D01*
G01X524875D01*
G02X524572Y1703224I-1J302D01*
G01Y1705637D01*
G02X524559Y1705866I2003J229D01*
G02X524572Y1706095I2016J0D01*
G01Y1710361D01*
G02X524559Y1710590I2003J229D01*
G02X524572Y1710819I2016J0D01*
G01Y1713230D01*
G02X524875Y1713532I303J-1D01*
G37*
G36*
G01X540623D02*
X544323D01*
G02X544626Y1713230I1J-302D01*
G01Y1703224D01*
G02X544323Y1702922I-303J1D01*
G01X540623D01*
G02X540320Y1703224I-1J302D01*
G01Y1705637D01*
G02X540307Y1705866I2003J229D01*
G02X540320Y1706095I2016J0D01*
G01Y1710361D01*
G02X540307Y1710590I2003J229D01*
G02X540320Y1710819I2016J0D01*
G01Y1713230D01*
G02X540623Y1713532I303J-1D01*
G37*
G36*
G01X1304009D02*
X1307709D01*
G02X1308012Y1713230I1J-302D01*
G01Y1703224D01*
G02X1307709Y1702922I-303J1D01*
G01X1304009D01*
G02X1303706Y1703224I-1J302D01*
G01Y1705637D01*
G02X1303693Y1705866I2003J229D01*
G02X1303706Y1706095I2016J0D01*
G01Y1710361D01*
G02X1303693Y1710590I2003J229D01*
G02X1303706Y1710819I2016J0D01*
G01Y1713230D01*
G02X1304009Y1713532I303J-1D01*
G37*
G36*
G01X1319757D02*
X1323457D01*
G02X1323760Y1713230I1J-302D01*
G01Y1703224D01*
G02X1323457Y1702922I-303J1D01*
G01X1319757D01*
G02X1319454Y1703224I-1J302D01*
G01Y1705637D01*
G02X1319441Y1705866I2003J229D01*
G02X1319454Y1706095I2016J0D01*
G01Y1710361D01*
G02X1319441Y1710590I2003J229D01*
G02X1319454Y1710819I2016J0D01*
G01Y1713230D01*
G02X1319757Y1713532I303J-1D01*
G37*
G36*
G01X1335505D02*
X1339205D01*
G02X1339508Y1713230I1J-302D01*
G01Y1703224D01*
G02X1339205Y1702922I-303J1D01*
G01X1335505D01*
G02X1335202Y1703224I-1J302D01*
G01Y1705637D01*
G02X1335189Y1705866I2003J229D01*
G02X1335202Y1706095I2016J0D01*
G01Y1710361D01*
G02X1335189Y1710590I2003J229D01*
G02X1335202Y1710819I2016J0D01*
G01Y1713230D01*
G02X1335505Y1713532I303J-1D01*
G37*
G36*
G01X1351253D02*
X1354953D01*
G02X1355256Y1713230I1J-302D01*
G01Y1703224D01*
G02X1354953Y1702922I-303J1D01*
G01X1351253D01*
G02X1350950Y1703224I-1J302D01*
G01Y1705637D01*
G02X1350937Y1705866I2003J229D01*
G02X1350950Y1706095I2016J0D01*
G01Y1710361D01*
G02X1350937Y1710590I2003J229D01*
G02X1350950Y1710819I2016J0D01*
G01Y1713230D01*
G02X1351253Y1713532I303J-1D01*
G37*
G36*
G01X1501253D02*
X1504953D01*
G02X1505256Y1713230I1J-302D01*
G01Y1703224D01*
G02X1504953Y1702922I-303J1D01*
G01X1501253D01*
G02X1500950Y1703224I-1J302D01*
G01Y1705637D01*
G02X1500937Y1705866I2003J229D01*
G02X1500950Y1706095I2016J0D01*
G01Y1710361D01*
G02X1500937Y1710590I2003J229D01*
G02X1500950Y1710819I2016J0D01*
G01Y1713230D01*
G02X1501253Y1713532I303J-1D01*
G37*
G36*
G01X1517001D02*
X1520701D01*
G02X1521004Y1713230I1J-302D01*
G01Y1703224D01*
G02X1520701Y1702922I-303J1D01*
G01X1517001D01*
G02X1516698Y1703224I-1J302D01*
G01Y1705637D01*
G02X1516685Y1705866I2003J229D01*
G02X1516698Y1706095I2016J0D01*
G01Y1710361D01*
G02X1516685Y1710590I2003J229D01*
G02X1516698Y1710819I2016J0D01*
G01Y1713230D01*
G02X1517001Y1713532I303J-1D01*
G37*
G36*
G01X1532749D02*
X1536449D01*
G02X1536752Y1713230I1J-302D01*
G01Y1703224D01*
G02X1536449Y1702922I-303J1D01*
G01X1532749D01*
G02X1532446Y1703224I-1J302D01*
G01Y1705637D01*
G02X1532433Y1705866I2003J229D01*
G02X1532446Y1706095I2016J0D01*
G01Y1710361D01*
G02X1532433Y1710590I2003J229D01*
G02X1532446Y1710819I2016J0D01*
G01Y1713230D01*
G02X1532749Y1713532I303J-1D01*
G37*
G36*
G01X1548497D02*
X1552197D01*
G02X1552500Y1713230I1J-302D01*
G01Y1703224D01*
G02X1552197Y1702922I-303J1D01*
G01X1548497D01*
G02X1548194Y1703224I-1J302D01*
G01Y1705637D01*
G02X1548181Y1705866I2003J229D01*
G02X1548194Y1706095I2016J0D01*
G01Y1710361D01*
G02X1548181Y1710590I2003J229D01*
G02X1548194Y1710819I2016J0D01*
G01Y1713230D01*
G02X1548497Y1713532I303J-1D01*
G37*
G36*
G01X237080Y1717470D02*
X240780D01*
G02X241082Y1717167I-1J-303D01*
G01Y1707161D01*
G02X240780Y1706858I-302J-1D01*
G01X237080D01*
G02X236778Y1707161I1J303D01*
G01Y1709566D01*
G02X236764Y1709803I2002J237D01*
G02X236778Y1710040I2016J0D01*
G01Y1714290D01*
G02X236764Y1714527I2002J237D01*
G02X236778Y1714764I2016J0D01*
G01Y1717167D01*
G02X237080Y1717470I302J1D01*
G37*
G36*
G01X252828D02*
X256528D01*
G02X256830Y1717167I-1J-303D01*
G01Y1707161D01*
G02X256528Y1706858I-302J-1D01*
G01X252828D01*
G02X252526Y1707161I1J303D01*
G01Y1709566D01*
G02X252512Y1709803I2002J237D01*
G02X252526Y1710040I2016J0D01*
G01Y1714290D01*
G02X252512Y1714527I2002J237D01*
G02X252526Y1714764I2016J0D01*
G01Y1717167D01*
G02X252828Y1717470I302J1D01*
G37*
G36*
G01X268576D02*
X272276D01*
G02X272578Y1717167I-1J-303D01*
G01Y1707161D01*
G02X272276Y1706858I-302J-1D01*
G01X268576D01*
G02X268274Y1707161I1J303D01*
G01Y1709566D01*
G02X268260Y1709803I2002J237D01*
G02X268274Y1710040I2016J0D01*
G01Y1714290D01*
G02X268260Y1714527I2002J237D01*
G02X268274Y1714764I2016J0D01*
G01Y1717167D01*
G02X268576Y1717470I302J1D01*
G37*
G36*
G01X284324D02*
X288024D01*
G02X288326Y1717167I-1J-303D01*
G01Y1707161D01*
G02X288024Y1706858I-302J-1D01*
G01X284324D01*
G02X284022Y1707161I1J303D01*
G01Y1709566D01*
G02X284008Y1709803I2002J237D01*
G02X284022Y1710040I2016J0D01*
G01Y1714290D01*
G02X284008Y1714527I2002J237D01*
G02X284022Y1714764I2016J0D01*
G01Y1717167D01*
G02X284324Y1717470I302J1D01*
G37*
G36*
G01X304009D02*
X307709D01*
G02X308012Y1717167I0J-303D01*
G01Y1707161D01*
G02X307709Y1706858I-303J0D01*
G01X304009D01*
G02X303706Y1707161I0J303D01*
G01Y1709574D01*
G02X303693Y1709803I2003J229D01*
G02X303706Y1710032I2016J0D01*
G01Y1714298D01*
G02X303693Y1714527I2003J229D01*
G02X303706Y1714756I2016J0D01*
G01Y1717167D01*
G02X304009Y1717470I303J0D01*
G37*
G36*
G01X319757D02*
X323457D01*
G02X323760Y1717167I0J-303D01*
G01Y1707161D01*
G02X323457Y1706858I-303J0D01*
G01X319757D01*
G02X319454Y1707161I0J303D01*
G01Y1709574D01*
G02X319441Y1709803I2003J229D01*
G02X319454Y1710032I2016J0D01*
G01Y1714298D01*
G02X319441Y1714527I2003J229D01*
G02X319454Y1714756I2016J0D01*
G01Y1717167D01*
G02X319757Y1717470I303J0D01*
G37*
G36*
G01X335505D02*
X339205D01*
G02X339508Y1717167I0J-303D01*
G01Y1707161D01*
G02X339205Y1706858I-303J0D01*
G01X335505D01*
G02X335202Y1707161I0J303D01*
G01Y1709574D01*
G02X335189Y1709803I2003J229D01*
G02X335202Y1710032I2016J0D01*
G01Y1714298D01*
G02X335189Y1714527I2003J229D01*
G02X335202Y1714756I2016J0D01*
G01Y1717167D01*
G02X335505Y1717470I303J0D01*
G37*
G36*
G01X351253D02*
X354953D01*
G02X355256Y1717167I0J-303D01*
G01Y1707161D01*
G02X354953Y1706858I-303J0D01*
G01X351253D01*
G02X350950Y1707161I0J303D01*
G01Y1709574D01*
G02X350937Y1709803I2003J229D01*
G02X350950Y1710032I2016J0D01*
G01Y1714298D01*
G02X350937Y1714527I2003J229D01*
G02X350950Y1714756I2016J0D01*
G01Y1717167D01*
G02X351253Y1717470I303J0D01*
G37*
G36*
G01X501253D02*
X504953D01*
G02X505256Y1717167I0J-303D01*
G01Y1707161D01*
G02X504953Y1706858I-303J0D01*
G01X501253D01*
G02X500950Y1707161I0J303D01*
G01Y1709574D01*
G02X500937Y1709803I2003J229D01*
G02X500950Y1710032I2016J0D01*
G01Y1714298D01*
G02X500937Y1714527I2003J229D01*
G02X500950Y1714756I2016J0D01*
G01Y1717167D01*
G02X501253Y1717470I303J0D01*
G37*
G36*
G01X517001D02*
X520701D01*
G02X521004Y1717167I0J-303D01*
G01Y1707161D01*
G02X520701Y1706858I-303J0D01*
G01X517001D01*
G02X516698Y1707161I0J303D01*
G01Y1709574D01*
G02X516685Y1709803I2003J229D01*
G02X516698Y1710032I2016J0D01*
G01Y1714298D01*
G02X516685Y1714527I2003J229D01*
G02X516698Y1714756I2016J0D01*
G01Y1717167D01*
G02X517001Y1717470I303J0D01*
G37*
G36*
G01X532749D02*
X536449D01*
G02X536752Y1717167I0J-303D01*
G01Y1707161D01*
G02X536449Y1706858I-303J0D01*
G01X532749D01*
G02X532446Y1707161I0J303D01*
G01Y1709574D01*
G02X532433Y1709803I2003J229D01*
G02X532446Y1710032I2016J0D01*
G01Y1714298D01*
G02X532433Y1714527I2003J229D01*
G02X532446Y1714756I2016J0D01*
G01Y1717167D01*
G02X532749Y1717470I303J0D01*
G37*
G36*
G01X548497D02*
X552197D01*
G02X552500Y1717167I0J-303D01*
G01Y1707161D01*
G02X552197Y1706858I-303J0D01*
G01X548497D01*
G02X548194Y1707161I0J303D01*
G01Y1709574D01*
G02X548181Y1709803I2003J229D01*
G02X548194Y1710032I2016J0D01*
G01Y1714298D01*
G02X548181Y1714527I2003J229D01*
G02X548194Y1714756I2016J0D01*
G01Y1717167D01*
G02X548497Y1717470I303J0D01*
G37*
G36*
G01X568182D02*
X571882D01*
G02X572184Y1717167I-1J-303D01*
G01Y1707161D01*
G02X571882Y1706858I-302J-1D01*
G01X568182D01*
G02X567880Y1707161I1J303D01*
G01Y1709566D01*
G02X567866Y1709803I2002J237D01*
G02X567880Y1710040I2016J0D01*
G01Y1714290D01*
G02X567866Y1714527I2002J237D01*
G02X567880Y1714764I2016J0D01*
G01Y1717167D01*
G02X568182Y1717470I302J1D01*
G37*
G36*
G01X583930D02*
X587630D01*
G02X587932Y1717167I-1J-303D01*
G01Y1707161D01*
G02X587630Y1706858I-302J-1D01*
G01X583930D01*
G02X583628Y1707161I1J303D01*
G01Y1709566D01*
G02X583614Y1709803I2002J237D01*
G02X583628Y1710040I2016J0D01*
G01Y1714290D01*
G02X583614Y1714527I2002J237D01*
G02X583628Y1714764I2016J0D01*
G01Y1717167D01*
G02X583930Y1717470I302J1D01*
G37*
G36*
G01X599678D02*
X603378D01*
G02X603680Y1717167I-1J-303D01*
G01Y1707161D01*
G02X603378Y1706858I-302J-1D01*
G01X599678D01*
G02X599376Y1707161I1J303D01*
G01Y1709566D01*
G02X599362Y1709803I2002J237D01*
G02X599376Y1710040I2016J0D01*
G01Y1714290D01*
G02X599362Y1714527I2002J237D01*
G02X599376Y1714764I2016J0D01*
G01Y1717167D01*
G02X599678Y1717470I302J1D01*
G37*
G36*
G01X615426D02*
X619126D01*
G02X619428Y1717167I-1J-303D01*
G01Y1707161D01*
G02X619126Y1706858I-302J-1D01*
G01X615426D01*
G02X615124Y1707161I1J303D01*
G01Y1709566D01*
G02X615110Y1709803I2002J237D01*
G02X615124Y1710040I2016J0D01*
G01Y1714290D01*
G02X615110Y1714527I2002J237D01*
G02X615124Y1714764I2016J0D01*
G01Y1717167D01*
G02X615426Y1717470I302J1D01*
G37*
G36*
G01X1244954D02*
X1248654D01*
G02X1248956Y1717167I-1J-303D01*
G01Y1707161D01*
G02X1248654Y1706858I-302J-1D01*
G01X1244954D01*
G02X1244652Y1707161I1J303D01*
G01Y1709566D01*
G02X1244638Y1709803I2002J237D01*
G02X1244652Y1710040I2016J0D01*
G01Y1714290D01*
G02X1244638Y1714527I2002J237D01*
G02X1244652Y1714764I2016J0D01*
G01Y1717167D01*
G02X1244954Y1717470I302J1D01*
G37*
G36*
G01X1260702D02*
X1264402D01*
G02X1264704Y1717167I-1J-303D01*
G01Y1707161D01*
G02X1264402Y1706858I-302J-1D01*
G01X1260702D01*
G02X1260400Y1707161I1J303D01*
G01Y1709566D01*
G02X1260386Y1709803I2002J237D01*
G02X1260400Y1710040I2016J0D01*
G01Y1714290D01*
G02X1260386Y1714527I2002J237D01*
G02X1260400Y1714764I2016J0D01*
G01Y1717167D01*
G02X1260702Y1717470I302J1D01*
G37*
G36*
G01X1276450D02*
X1280150D01*
G02X1280452Y1717167I-1J-303D01*
G01Y1707161D01*
G02X1280150Y1706858I-302J-1D01*
G01X1276450D01*
G02X1276148Y1707161I1J303D01*
G01Y1709566D01*
G02X1276134Y1709803I2002J237D01*
G02X1276148Y1710040I2016J0D01*
G01Y1714290D01*
G02X1276134Y1714527I2002J237D01*
G02X1276148Y1714764I2016J0D01*
G01Y1717167D01*
G02X1276450Y1717470I302J1D01*
G37*
G36*
G01X1292198D02*
X1295898D01*
G02X1296200Y1717167I-1J-303D01*
G01Y1707161D01*
G02X1295898Y1706858I-302J-1D01*
G01X1292198D01*
G02X1291896Y1707161I1J303D01*
G01Y1709566D01*
G02X1291882Y1709803I2002J237D01*
G02X1291896Y1710040I2016J0D01*
G01Y1714290D01*
G02X1291882Y1714527I2002J237D01*
G02X1291896Y1714764I2016J0D01*
G01Y1717167D01*
G02X1292198Y1717470I302J1D01*
G37*
G36*
G01X1311883D02*
X1315583D01*
G02X1315886Y1717167I0J-303D01*
G01Y1707161D01*
G02X1315583Y1706858I-303J0D01*
G01X1311883D01*
G02X1311580Y1707161I0J303D01*
G01Y1709574D01*
G02X1311567Y1709803I2003J229D01*
G02X1311580Y1710032I2016J0D01*
G01Y1714298D01*
G02X1311567Y1714527I2003J229D01*
G02X1311580Y1714756I2016J0D01*
G01Y1717167D01*
G02X1311883Y1717470I303J0D01*
G37*
G36*
G01X1327631D02*
X1331331D01*
G02X1331634Y1717167I0J-303D01*
G01Y1707161D01*
G02X1331331Y1706858I-303J0D01*
G01X1327631D01*
G02X1327328Y1707161I0J303D01*
G01Y1709574D01*
G02X1327315Y1709803I2003J229D01*
G02X1327328Y1710032I2016J0D01*
G01Y1714298D01*
G02X1327315Y1714527I2003J229D01*
G02X1327328Y1714756I2016J0D01*
G01Y1717167D01*
G02X1327631Y1717470I303J0D01*
G37*
G36*
G01X1343379D02*
X1347079D01*
G02X1347382Y1717167I0J-303D01*
G01Y1707161D01*
G02X1347079Y1706858I-303J0D01*
G01X1343379D01*
G02X1343076Y1707161I0J303D01*
G01Y1709574D01*
G02X1343063Y1709803I2003J229D01*
G02X1343076Y1710032I2016J0D01*
G01Y1714298D01*
G02X1343063Y1714527I2003J229D01*
G02X1343076Y1714756I2016J0D01*
G01Y1717167D01*
G02X1343379Y1717470I303J0D01*
G37*
G36*
G01X1359127D02*
X1362827D01*
G02X1363130Y1717167I0J-303D01*
G01Y1707161D01*
G02X1362827Y1706858I-303J0D01*
G01X1359127D01*
G02X1358824Y1707161I0J303D01*
G01Y1709574D01*
G02X1358811Y1709803I2003J229D01*
G02X1358824Y1710032I2016J0D01*
G01Y1714298D01*
G02X1358811Y1714527I2003J229D01*
G02X1358824Y1714756I2016J0D01*
G01Y1717167D01*
G02X1359127Y1717470I303J0D01*
G37*
G36*
G01X1509127D02*
X1512827D01*
G02X1513130Y1717167I0J-303D01*
G01Y1707161D01*
G02X1512827Y1706858I-303J0D01*
G01X1509127D01*
G02X1508824Y1707161I0J303D01*
G01Y1709574D01*
G02X1508811Y1709803I2003J229D01*
G02X1508824Y1710032I2016J0D01*
G01Y1714298D01*
G02X1508811Y1714527I2003J229D01*
G02X1508824Y1714756I2016J0D01*
G01Y1717167D01*
G02X1509127Y1717470I303J0D01*
G37*
G36*
G01X1524875D02*
X1528575D01*
G02X1528878Y1717167I0J-303D01*
G01Y1707161D01*
G02X1528575Y1706858I-303J0D01*
G01X1524875D01*
G02X1524572Y1707161I0J303D01*
G01Y1709574D01*
G02X1524559Y1709803I2003J229D01*
G02X1524572Y1710032I2016J0D01*
G01Y1714298D01*
G02X1524559Y1714527I2003J229D01*
G02X1524572Y1714756I2016J0D01*
G01Y1717167D01*
G02X1524875Y1717470I303J0D01*
G37*
G36*
G01X1540623D02*
X1544323D01*
G02X1544626Y1717167I0J-303D01*
G01Y1707161D01*
G02X1544323Y1706858I-303J0D01*
G01X1540623D01*
G02X1540320Y1707161I0J303D01*
G01Y1709574D01*
G02X1540307Y1709803I2003J229D01*
G02X1540320Y1710032I2016J0D01*
G01Y1714298D01*
G02X1540307Y1714527I2003J229D01*
G02X1540320Y1714756I2016J0D01*
G01Y1717167D01*
G02X1540623Y1717470I303J0D01*
G37*
G36*
G01X1556371D02*
X1560071D01*
G02X1560374Y1717167I0J-303D01*
G01Y1707161D01*
G02X1560071Y1706858I-303J0D01*
G01X1556371D01*
G02X1556068Y1707161I0J303D01*
G01Y1709574D01*
G02X1556055Y1709803I2003J229D01*
G02X1556068Y1710032I2016J0D01*
G01Y1714298D01*
G02X1556055Y1714527I2003J229D01*
G02X1556068Y1714756I2016J0D01*
G01Y1717167D01*
G02X1556371Y1717470I303J0D01*
G37*
G36*
G01X1576056D02*
X1579756D01*
G02X1580058Y1717167I-1J-303D01*
G01Y1707161D01*
G02X1579756Y1706858I-302J-1D01*
G01X1576056D01*
G02X1575754Y1707161I1J303D01*
G01Y1709566D01*
G02X1575740Y1709803I2002J237D01*
G02X1575754Y1710040I2016J0D01*
G01Y1714290D01*
G02X1575740Y1714527I2002J237D01*
G02X1575754Y1714764I2016J0D01*
G01Y1717167D01*
G02X1576056Y1717470I302J1D01*
G37*
G36*
G01X1591804D02*
X1595504D01*
G02X1595806Y1717167I-1J-303D01*
G01Y1707161D01*
G02X1595504Y1706858I-302J-1D01*
G01X1591804D01*
G02X1591502Y1707161I1J303D01*
G01Y1709566D01*
G02X1591488Y1709803I2002J237D01*
G02X1591502Y1710040I2016J0D01*
G01Y1714290D01*
G02X1591488Y1714527I2002J237D01*
G02X1591502Y1714764I2016J0D01*
G01Y1717167D01*
G02X1591804Y1717470I302J1D01*
G37*
G36*
G01X1607552D02*
X1611252D01*
G02X1611554Y1717167I-1J-303D01*
G01Y1707161D01*
G02X1611252Y1706858I-302J-1D01*
G01X1607552D01*
G02X1607250Y1707161I1J303D01*
G01Y1709566D01*
G02X1607236Y1709803I2002J237D01*
G02X1607250Y1710040I2016J0D01*
G01Y1714290D01*
G02X1607236Y1714527I2002J237D01*
G02X1607250Y1714764I2016J0D01*
G01Y1717167D01*
G02X1607552Y1717470I302J1D01*
G37*
G36*
G01X1623300D02*
X1627000D01*
G02X1627302Y1717167I-1J-303D01*
G01Y1707161D01*
G02X1627000Y1706858I-302J-1D01*
G01X1623300D01*
G02X1622998Y1707161I1J303D01*
G01Y1709566D01*
G02X1622984Y1709803I2002J237D01*
G02X1622998Y1710040I2016J0D01*
G01Y1714290D01*
G02X1622984Y1714527I2002J237D01*
G02X1622998Y1714764I2016J0D01*
G01Y1717167D01*
G02X1623300Y1717470I302J1D01*
G37*
G36*
G01X229206Y1727706D02*
X232906D01*
G02X233208Y1727404I0J-302D01*
G01Y1717398D01*
G02X232906Y1717096I-302J0D01*
G01X229206D01*
G02X228904Y1717398I0J302D01*
G01Y1719802D01*
G02X228890Y1720039I2002J237D01*
G02X228904Y1720276I2016J0D01*
G01Y1724526D01*
G02X228890Y1724763I2002J237D01*
G02X228904Y1725000I2016J0D01*
G01Y1727404D01*
G02X229206Y1727706I302J0D01*
G37*
G36*
G01X244954D02*
X248654D01*
G02X248956Y1727404I0J-302D01*
G01Y1717398D01*
G02X248654Y1717096I-302J0D01*
G01X244954D01*
G02X244652Y1717398I0J302D01*
G01Y1719802D01*
G02X244638Y1720039I2002J237D01*
G02X244652Y1720276I2016J0D01*
G01Y1724526D01*
G02X244638Y1724763I2002J237D01*
G02X244652Y1725000I2016J0D01*
G01Y1727404D01*
G02X244954Y1727706I302J0D01*
G37*
G36*
G01X260702D02*
X264402D01*
G02X264704Y1727404I0J-302D01*
G01Y1717398D01*
G02X264402Y1717096I-302J0D01*
G01X260702D01*
G02X260400Y1717398I0J302D01*
G01Y1719802D01*
G02X260386Y1720039I2002J237D01*
G02X260400Y1720276I2016J0D01*
G01Y1724526D01*
G02X260386Y1724763I2002J237D01*
G02X260400Y1725000I2016J0D01*
G01Y1727404D01*
G02X260702Y1727706I302J0D01*
G37*
G36*
G01X276450D02*
X280150D01*
G02X280452Y1727404I0J-302D01*
G01Y1717398D01*
G02X280150Y1717096I-302J0D01*
G01X276450D01*
G02X276148Y1717398I0J302D01*
G01Y1719802D01*
G02X276134Y1720039I2002J237D01*
G02X276148Y1720276I2016J0D01*
G01Y1724526D01*
G02X276134Y1724763I2002J237D01*
G02X276148Y1725000I2016J0D01*
G01Y1727404D01*
G02X276450Y1727706I302J0D01*
G37*
G36*
G01X560308D02*
X564008D01*
G02X564310Y1727404I0J-302D01*
G01Y1717398D01*
G02X564008Y1717096I-302J0D01*
G01X560308D01*
G02X560006Y1717398I0J302D01*
G01Y1719802D01*
G02X559992Y1720039I2002J237D01*
G02X560006Y1720276I2016J0D01*
G01Y1724526D01*
G02X559992Y1724763I2002J237D01*
G02X560006Y1725000I2016J0D01*
G01Y1727404D01*
G02X560308Y1727706I302J0D01*
G37*
G36*
G01X576056D02*
X579756D01*
G02X580058Y1727404I0J-302D01*
G01Y1717398D01*
G02X579756Y1717096I-302J0D01*
G01X576056D01*
G02X575754Y1717398I0J302D01*
G01Y1719802D01*
G02X575740Y1720039I2002J237D01*
G02X575754Y1720276I2016J0D01*
G01Y1724526D01*
G02X575740Y1724763I2002J237D01*
G02X575754Y1725000I2016J0D01*
G01Y1727404D01*
G02X576056Y1727706I302J0D01*
G37*
G36*
G01X591804D02*
X595504D01*
G02X595806Y1727404I0J-302D01*
G01Y1717398D01*
G02X595504Y1717096I-302J0D01*
G01X591804D01*
G02X591502Y1717398I0J302D01*
G01Y1719802D01*
G02X591488Y1720039I2002J237D01*
G02X591502Y1720276I2016J0D01*
G01Y1724526D01*
G02X591488Y1724763I2002J237D01*
G02X591502Y1725000I2016J0D01*
G01Y1727404D01*
G02X591804Y1727706I302J0D01*
G37*
G36*
G01X607552D02*
X611252D01*
G02X611554Y1727404I0J-302D01*
G01Y1717398D01*
G02X611252Y1717096I-302J0D01*
G01X607552D01*
G02X607250Y1717398I0J302D01*
G01Y1719802D01*
G02X607236Y1720039I2002J237D01*
G02X607250Y1720276I2016J0D01*
G01Y1724526D01*
G02X607236Y1724763I2002J237D01*
G02X607250Y1725000I2016J0D01*
G01Y1727404D01*
G02X607552Y1727706I302J0D01*
G37*
G36*
G01X1237080D02*
X1240780D01*
G02X1241082Y1727404I0J-302D01*
G01Y1717398D01*
G02X1240780Y1717096I-302J0D01*
G01X1237080D01*
G02X1236778Y1717398I0J302D01*
G01Y1719802D01*
G02X1236764Y1720039I2002J237D01*
G02X1236778Y1720276I2016J0D01*
G01Y1724526D01*
G02X1236764Y1724763I2002J237D01*
G02X1236778Y1725000I2016J0D01*
G01Y1727404D01*
G02X1237080Y1727706I302J0D01*
G37*
G36*
G01X1252828D02*
X1256528D01*
G02X1256830Y1727404I0J-302D01*
G01Y1717398D01*
G02X1256528Y1717096I-302J0D01*
G01X1252828D01*
G02X1252526Y1717398I0J302D01*
G01Y1719802D01*
G02X1252512Y1720039I2002J237D01*
G02X1252526Y1720276I2016J0D01*
G01Y1724526D01*
G02X1252512Y1724763I2002J237D01*
G02X1252526Y1725000I2016J0D01*
G01Y1727404D01*
G02X1252828Y1727706I302J0D01*
G37*
G36*
G01X1268576D02*
X1272276D01*
G02X1272578Y1727404I0J-302D01*
G01Y1717398D01*
G02X1272276Y1717096I-302J0D01*
G01X1268576D01*
G02X1268274Y1717398I0J302D01*
G01Y1719802D01*
G02X1268260Y1720039I2002J237D01*
G02X1268274Y1720276I2016J0D01*
G01Y1724526D01*
G02X1268260Y1724763I2002J237D01*
G02X1268274Y1725000I2016J0D01*
G01Y1727404D01*
G02X1268576Y1727706I302J0D01*
G37*
G36*
G01X1284324D02*
X1288024D01*
G02X1288326Y1727404I0J-302D01*
G01Y1717398D01*
G02X1288024Y1717096I-302J0D01*
G01X1284324D01*
G02X1284022Y1717398I0J302D01*
G01Y1719802D01*
G02X1284008Y1720039I2002J237D01*
G02X1284022Y1720276I2016J0D01*
G01Y1724526D01*
G02X1284008Y1724763I2002J237D01*
G02X1284022Y1725000I2016J0D01*
G01Y1727404D01*
G02X1284324Y1727706I302J0D01*
G37*
G36*
G01X1568182D02*
X1571882D01*
G02X1572184Y1727404I0J-302D01*
G01Y1717398D01*
G02X1571882Y1717096I-302J0D01*
G01X1568182D01*
G02X1567880Y1717398I0J302D01*
G01Y1719802D01*
G02X1567866Y1720039I2002J237D01*
G02X1567880Y1720276I2016J0D01*
G01Y1724526D01*
G02X1567866Y1724763I2002J237D01*
G02X1567880Y1725000I2016J0D01*
G01Y1727404D01*
G02X1568182Y1727706I302J0D01*
G37*
G36*
G01X1583930D02*
X1587630D01*
G02X1587932Y1727404I0J-302D01*
G01Y1717398D01*
G02X1587630Y1717096I-302J0D01*
G01X1583930D01*
G02X1583628Y1717398I0J302D01*
G01Y1719802D01*
G02X1583614Y1720039I2002J237D01*
G02X1583628Y1720276I2016J0D01*
G01Y1724526D01*
G02X1583614Y1724763I2002J237D01*
G02X1583628Y1725000I2016J0D01*
G01Y1727404D01*
G02X1583930Y1727706I302J0D01*
G37*
G36*
G01X1599678D02*
X1603378D01*
G02X1603680Y1727404I0J-302D01*
G01Y1717398D01*
G02X1603378Y1717096I-302J0D01*
G01X1599678D01*
G02X1599376Y1717398I0J302D01*
G01Y1719802D01*
G02X1599362Y1720039I2002J237D01*
G02X1599376Y1720276I2016J0D01*
G01Y1724526D01*
G02X1599362Y1724763I2002J237D01*
G02X1599376Y1725000I2016J0D01*
G01Y1727404D01*
G02X1599678Y1727706I302J0D01*
G37*
G36*
G01X1615426D02*
X1619126D01*
G02X1619428Y1727404I0J-302D01*
G01Y1717398D01*
G02X1619126Y1717096I-302J0D01*
G01X1615426D01*
G02X1615124Y1717398I0J302D01*
G01Y1719802D01*
G02X1615110Y1720039I2002J237D01*
G02X1615124Y1720276I2016J0D01*
G01Y1724526D01*
G02X1615110Y1724763I2002J237D01*
G02X1615124Y1725000I2016J0D01*
G01Y1727404D01*
G02X1615426Y1727706I302J0D01*
G37*
G36*
G01X296135D02*
X299835D01*
G02X300138Y1727404I1J-302D01*
G01Y1717398D01*
G02X299835Y1717096I-303J1D01*
G01X296135D01*
G02X295832Y1717398I-1J302D01*
G01Y1719810D01*
G02X295819Y1720039I2003J229D01*
G02X295832Y1720268I2016J0D01*
G01Y1724534D01*
G02X295819Y1724763I2003J229D01*
G02X295832Y1724992I2016J0D01*
G01Y1727404D01*
G02X296135Y1727706I303J-1D01*
G37*
G36*
G01X311883D02*
X315583D01*
G02X315886Y1727404I1J-302D01*
G01Y1717398D01*
G02X315583Y1717096I-303J1D01*
G01X311883D01*
G02X311580Y1717398I-1J302D01*
G01Y1719810D01*
G02X311567Y1720039I2003J229D01*
G02X311580Y1720268I2016J0D01*
G01Y1724534D01*
G02X311567Y1724763I2003J229D01*
G02X311580Y1724992I2016J0D01*
G01Y1727404D01*
G02X311883Y1727706I303J-1D01*
G37*
G36*
G01X327631D02*
X331331D01*
G02X331634Y1727404I1J-302D01*
G01Y1717398D01*
G02X331331Y1717096I-303J1D01*
G01X327631D01*
G02X327328Y1717398I-1J302D01*
G01Y1719810D01*
G02X327315Y1720039I2003J229D01*
G02X327328Y1720268I2016J0D01*
G01Y1724534D01*
G02X327315Y1724763I2003J229D01*
G02X327328Y1724992I2016J0D01*
G01Y1727404D01*
G02X327631Y1727706I303J-1D01*
G37*
G36*
G01X343379D02*
X347079D01*
G02X347382Y1727404I1J-302D01*
G01Y1717398D01*
G02X347079Y1717096I-303J1D01*
G01X343379D01*
G02X343076Y1717398I-1J302D01*
G01Y1719810D01*
G02X343063Y1720039I2003J229D01*
G02X343076Y1720268I2016J0D01*
G01Y1724534D01*
G02X343063Y1724763I2003J229D01*
G02X343076Y1724992I2016J0D01*
G01Y1727404D01*
G02X343379Y1727706I303J-1D01*
G37*
G36*
G01X493379D02*
X497079D01*
G02X497382Y1727404I1J-302D01*
G01Y1717398D01*
G02X497079Y1717096I-303J1D01*
G01X493379D01*
G02X493076Y1717398I-1J302D01*
G01Y1719810D01*
G02X493063Y1720039I2003J229D01*
G02X493076Y1720268I2016J0D01*
G01Y1724534D01*
G02X493063Y1724763I2003J229D01*
G02X493076Y1724992I2016J0D01*
G01Y1727404D01*
G02X493379Y1727706I303J-1D01*
G37*
G36*
G01X509127D02*
X512827D01*
G02X513130Y1727404I1J-302D01*
G01Y1717398D01*
G02X512827Y1717096I-303J1D01*
G01X509127D01*
G02X508824Y1717398I-1J302D01*
G01Y1719810D01*
G02X508811Y1720039I2003J229D01*
G02X508824Y1720268I2016J0D01*
G01Y1724534D01*
G02X508811Y1724763I2003J229D01*
G02X508824Y1724992I2016J0D01*
G01Y1727404D01*
G02X509127Y1727706I303J-1D01*
G37*
G36*
G01X524875D02*
X528575D01*
G02X528878Y1727404I1J-302D01*
G01Y1717398D01*
G02X528575Y1717096I-303J1D01*
G01X524875D01*
G02X524572Y1717398I-1J302D01*
G01Y1719810D01*
G02X524559Y1720039I2003J229D01*
G02X524572Y1720268I2016J0D01*
G01Y1724534D01*
G02X524559Y1724763I2003J229D01*
G02X524572Y1724992I2016J0D01*
G01Y1727404D01*
G02X524875Y1727706I303J-1D01*
G37*
G36*
G01X540623D02*
X544323D01*
G02X544626Y1727404I1J-302D01*
G01Y1717398D01*
G02X544323Y1717096I-303J1D01*
G01X540623D01*
G02X540320Y1717398I-1J302D01*
G01Y1719810D01*
G02X540307Y1720039I2003J229D01*
G02X540320Y1720268I2016J0D01*
G01Y1724534D01*
G02X540307Y1724763I2003J229D01*
G02X540320Y1724992I2016J0D01*
G01Y1727404D01*
G02X540623Y1727706I303J-1D01*
G37*
G36*
G01X1304009D02*
X1307709D01*
G02X1308012Y1727404I1J-302D01*
G01Y1717398D01*
G02X1307709Y1717096I-303J1D01*
G01X1304009D01*
G02X1303706Y1717398I-1J302D01*
G01Y1719810D01*
G02X1303693Y1720039I2003J229D01*
G02X1303706Y1720268I2016J0D01*
G01Y1724534D01*
G02X1303693Y1724763I2003J229D01*
G02X1303706Y1724992I2016J0D01*
G01Y1727404D01*
G02X1304009Y1727706I303J-1D01*
G37*
G36*
G01X1319757D02*
X1323457D01*
G02X1323760Y1727404I1J-302D01*
G01Y1717398D01*
G02X1323457Y1717096I-303J1D01*
G01X1319757D01*
G02X1319454Y1717398I-1J302D01*
G01Y1719810D01*
G02X1319441Y1720039I2003J229D01*
G02X1319454Y1720268I2016J0D01*
G01Y1724534D01*
G02X1319441Y1724763I2003J229D01*
G02X1319454Y1724992I2016J0D01*
G01Y1727404D01*
G02X1319757Y1727706I303J-1D01*
G37*
G36*
G01X1335505D02*
X1339205D01*
G02X1339508Y1727404I1J-302D01*
G01Y1717398D01*
G02X1339205Y1717096I-303J1D01*
G01X1335505D01*
G02X1335202Y1717398I-1J302D01*
G01Y1719810D01*
G02X1335189Y1720039I2003J229D01*
G02X1335202Y1720268I2016J0D01*
G01Y1724534D01*
G02X1335189Y1724763I2003J229D01*
G02X1335202Y1724992I2016J0D01*
G01Y1727404D01*
G02X1335505Y1727706I303J-1D01*
G37*
G36*
G01X1351253D02*
X1354953D01*
G02X1355256Y1727404I1J-302D01*
G01Y1717398D01*
G02X1354953Y1717096I-303J1D01*
G01X1351253D01*
G02X1350950Y1717398I-1J302D01*
G01Y1719810D01*
G02X1350937Y1720039I2003J229D01*
G02X1350950Y1720268I2016J0D01*
G01Y1724534D01*
G02X1350937Y1724763I2003J229D01*
G02X1350950Y1724992I2016J0D01*
G01Y1727404D01*
G02X1351253Y1727706I303J-1D01*
G37*
G36*
G01X1501253D02*
X1504953D01*
G02X1505256Y1727404I1J-302D01*
G01Y1717398D01*
G02X1504953Y1717096I-303J1D01*
G01X1501253D01*
G02X1500950Y1717398I-1J302D01*
G01Y1719810D01*
G02X1500937Y1720039I2003J229D01*
G02X1500950Y1720268I2016J0D01*
G01Y1724534D01*
G02X1500937Y1724763I2003J229D01*
G02X1500950Y1724992I2016J0D01*
G01Y1727404D01*
G02X1501253Y1727706I303J-1D01*
G37*
G36*
G01X1517001D02*
X1520701D01*
G02X1521004Y1727404I1J-302D01*
G01Y1717398D01*
G02X1520701Y1717096I-303J1D01*
G01X1517001D01*
G02X1516698Y1717398I-1J302D01*
G01Y1719810D01*
G02X1516685Y1720039I2003J229D01*
G02X1516698Y1720268I2016J0D01*
G01Y1724534D01*
G02X1516685Y1724763I2003J229D01*
G02X1516698Y1724992I2016J0D01*
G01Y1727404D01*
G02X1517001Y1727706I303J-1D01*
G37*
G36*
G01X1532749D02*
X1536449D01*
G02X1536752Y1727404I1J-302D01*
G01Y1717398D01*
G02X1536449Y1717096I-303J1D01*
G01X1532749D01*
G02X1532446Y1717398I-1J302D01*
G01Y1719810D01*
G02X1532433Y1720039I2003J229D01*
G02X1532446Y1720268I2016J0D01*
G01Y1724534D01*
G02X1532433Y1724763I2003J229D01*
G02X1532446Y1724992I2016J0D01*
G01Y1727404D01*
G02X1532749Y1727706I303J-1D01*
G37*
G36*
G01X1548497D02*
X1552197D01*
G02X1552500Y1727404I1J-302D01*
G01Y1717398D01*
G02X1552197Y1717096I-303J1D01*
G01X1548497D01*
G02X1548194Y1717398I-1J302D01*
G01Y1719810D01*
G02X1548181Y1720039I2003J229D01*
G02X1548194Y1720268I2016J0D01*
G01Y1724534D01*
G02X1548181Y1724763I2003J229D01*
G02X1548194Y1724992I2016J0D01*
G01Y1727404D01*
G02X1548497Y1727706I303J-1D01*
G37*
G36*
G01X237080Y1731644D02*
X240780D01*
G02X241082Y1731341I-1J-303D01*
G01Y1721335D01*
G02X240780Y1721032I-302J-1D01*
G01X237080D01*
G02X236778Y1721335I1J303D01*
G01Y1723739D01*
G02X236764Y1723976I2002J237D01*
G02X236778Y1724213I2016J0D01*
G01Y1728463D01*
G02X236764Y1728700I2002J237D01*
G02X236778Y1728937I2016J0D01*
G01Y1731341D01*
G02X237080Y1731644I302J1D01*
G37*
G36*
G01X252828D02*
X256528D01*
G02X256830Y1731341I-1J-303D01*
G01Y1721335D01*
G02X256528Y1721032I-302J-1D01*
G01X252828D01*
G02X252526Y1721335I1J303D01*
G01Y1723739D01*
G02X252512Y1723976I2002J237D01*
G02X252526Y1724213I2016J0D01*
G01Y1728463D01*
G02X252512Y1728700I2002J237D01*
G02X252526Y1728937I2016J0D01*
G01Y1731341D01*
G02X252828Y1731644I302J1D01*
G37*
G36*
G01X268576D02*
X272276D01*
G02X272578Y1731341I-1J-303D01*
G01Y1721335D01*
G02X272276Y1721032I-302J-1D01*
G01X268576D01*
G02X268274Y1721335I1J303D01*
G01Y1723739D01*
G02X268260Y1723976I2002J237D01*
G02X268274Y1724213I2016J0D01*
G01Y1728463D01*
G02X268260Y1728700I2002J237D01*
G02X268274Y1728937I2016J0D01*
G01Y1731341D01*
G02X268576Y1731644I302J1D01*
G37*
G36*
G01X284324D02*
X288024D01*
G02X288326Y1731341I-1J-303D01*
G01Y1721335D01*
G02X288024Y1721032I-302J-1D01*
G01X284324D01*
G02X284022Y1721335I1J303D01*
G01Y1723739D01*
G02X284008Y1723976I2002J237D01*
G02X284022Y1724213I2016J0D01*
G01Y1728463D01*
G02X284008Y1728700I2002J237D01*
G02X284022Y1728937I2016J0D01*
G01Y1731341D01*
G02X284324Y1731644I302J1D01*
G37*
G36*
G01X304009D02*
X307709D01*
G02X308012Y1731341I0J-303D01*
G01Y1721335D01*
G02X307709Y1721032I-303J0D01*
G01X304009D01*
G02X303706Y1721335I0J303D01*
G01Y1723747D01*
G02X303693Y1723976I2003J229D01*
G02X303706Y1724205I2016J0D01*
G01Y1728471D01*
G02X303693Y1728700I2003J229D01*
G02X303706Y1728929I2016J0D01*
G01Y1731341D01*
G02X304009Y1731644I303J0D01*
G37*
G36*
G01X319757D02*
X323457D01*
G02X323760Y1731341I0J-303D01*
G01Y1721335D01*
G02X323457Y1721032I-303J0D01*
G01X319757D01*
G02X319454Y1721335I0J303D01*
G01Y1723747D01*
G02X319441Y1723976I2003J229D01*
G02X319454Y1724205I2016J0D01*
G01Y1728471D01*
G02X319441Y1728700I2003J229D01*
G02X319454Y1728929I2016J0D01*
G01Y1731341D01*
G02X319757Y1731644I303J0D01*
G37*
G36*
G01X335505D02*
X339205D01*
G02X339508Y1731341I0J-303D01*
G01Y1721335D01*
G02X339205Y1721032I-303J0D01*
G01X335505D01*
G02X335202Y1721335I0J303D01*
G01Y1723747D01*
G02X335189Y1723976I2003J229D01*
G02X335202Y1724205I2016J0D01*
G01Y1728471D01*
G02X335189Y1728700I2003J229D01*
G02X335202Y1728929I2016J0D01*
G01Y1731341D01*
G02X335505Y1731644I303J0D01*
G37*
G36*
G01X351253D02*
X354953D01*
G02X355256Y1731341I0J-303D01*
G01Y1721335D01*
G02X354953Y1721032I-303J0D01*
G01X351253D01*
G02X350950Y1721335I0J303D01*
G01Y1723747D01*
G02X350937Y1723976I2003J229D01*
G02X350950Y1724205I2016J0D01*
G01Y1728471D01*
G02X350937Y1728700I2003J229D01*
G02X350950Y1728929I2016J0D01*
G01Y1731341D01*
G02X351253Y1731644I303J0D01*
G37*
G36*
G01X501253D02*
X504953D01*
G02X505256Y1731341I0J-303D01*
G01Y1721335D01*
G02X504953Y1721032I-303J0D01*
G01X501253D01*
G02X500950Y1721335I0J303D01*
G01Y1723747D01*
G02X500937Y1723976I2003J229D01*
G02X500950Y1724205I2016J0D01*
G01Y1728471D01*
G02X500937Y1728700I2003J229D01*
G02X500950Y1728929I2016J0D01*
G01Y1731341D01*
G02X501253Y1731644I303J0D01*
G37*
G36*
G01X517001D02*
X520701D01*
G02X521004Y1731341I0J-303D01*
G01Y1721335D01*
G02X520701Y1721032I-303J0D01*
G01X517001D01*
G02X516698Y1721335I0J303D01*
G01Y1723747D01*
G02X516685Y1723976I2003J229D01*
G02X516698Y1724205I2016J0D01*
G01Y1728471D01*
G02X516685Y1728700I2003J229D01*
G02X516698Y1728929I2016J0D01*
G01Y1731341D01*
G02X517001Y1731644I303J0D01*
G37*
G36*
G01X532749D02*
X536449D01*
G02X536752Y1731341I0J-303D01*
G01Y1721335D01*
G02X536449Y1721032I-303J0D01*
G01X532749D01*
G02X532446Y1721335I0J303D01*
G01Y1723747D01*
G02X532433Y1723976I2003J229D01*
G02X532446Y1724205I2016J0D01*
G01Y1728471D01*
G02X532433Y1728700I2003J229D01*
G02X532446Y1728929I2016J0D01*
G01Y1731341D01*
G02X532749Y1731644I303J0D01*
G37*
G36*
G01X548497D02*
X552197D01*
G02X552500Y1731341I0J-303D01*
G01Y1721335D01*
G02X552197Y1721032I-303J0D01*
G01X548497D01*
G02X548194Y1721335I0J303D01*
G01Y1723747D01*
G02X548181Y1723976I2003J229D01*
G02X548194Y1724205I2016J0D01*
G01Y1728471D01*
G02X548181Y1728700I2003J229D01*
G02X548194Y1728929I2016J0D01*
G01Y1731341D01*
G02X548497Y1731644I303J0D01*
G37*
G36*
G01X568182D02*
X571882D01*
G02X572184Y1731341I-1J-303D01*
G01Y1721335D01*
G02X571882Y1721032I-302J-1D01*
G01X568182D01*
G02X567880Y1721335I1J303D01*
G01Y1723739D01*
G02X567866Y1723976I2002J237D01*
G02X567880Y1724213I2016J0D01*
G01Y1728463D01*
G02X567866Y1728700I2002J237D01*
G02X567880Y1728937I2016J0D01*
G01Y1731341D01*
G02X568182Y1731644I302J1D01*
G37*
G36*
G01X583930D02*
X587630D01*
G02X587932Y1731341I-1J-303D01*
G01Y1721335D01*
G02X587630Y1721032I-302J-1D01*
G01X583930D01*
G02X583628Y1721335I1J303D01*
G01Y1723739D01*
G02X583614Y1723976I2002J237D01*
G02X583628Y1724213I2016J0D01*
G01Y1728463D01*
G02X583614Y1728700I2002J237D01*
G02X583628Y1728937I2016J0D01*
G01Y1731341D01*
G02X583930Y1731644I302J1D01*
G37*
G36*
G01X599678D02*
X603378D01*
G02X603680Y1731341I-1J-303D01*
G01Y1721335D01*
G02X603378Y1721032I-302J-1D01*
G01X599678D01*
G02X599376Y1721335I1J303D01*
G01Y1723739D01*
G02X599362Y1723976I2002J237D01*
G02X599376Y1724213I2016J0D01*
G01Y1728463D01*
G02X599362Y1728700I2002J237D01*
G02X599376Y1728937I2016J0D01*
G01Y1731341D01*
G02X599678Y1731644I302J1D01*
G37*
G36*
G01X615426D02*
X619126D01*
G02X619428Y1731341I-1J-303D01*
G01Y1721335D01*
G02X619126Y1721032I-302J-1D01*
G01X615426D01*
G02X615124Y1721335I1J303D01*
G01Y1723739D01*
G02X615110Y1723976I2002J237D01*
G02X615124Y1724213I2016J0D01*
G01Y1728463D01*
G02X615110Y1728700I2002J237D01*
G02X615124Y1728937I2016J0D01*
G01Y1731341D01*
G02X615426Y1731644I302J1D01*
G37*
G36*
G01X1244954D02*
X1248654D01*
G02X1248956Y1731341I-1J-303D01*
G01Y1721335D01*
G02X1248654Y1721032I-302J-1D01*
G01X1244954D01*
G02X1244652Y1721335I1J303D01*
G01Y1723739D01*
G02X1244638Y1723976I2002J237D01*
G02X1244652Y1724213I2016J0D01*
G01Y1728463D01*
G02X1244638Y1728700I2002J237D01*
G02X1244652Y1728937I2016J0D01*
G01Y1731341D01*
G02X1244954Y1731644I302J1D01*
G37*
G36*
G01X1260702D02*
X1264402D01*
G02X1264704Y1731341I-1J-303D01*
G01Y1721335D01*
G02X1264402Y1721032I-302J-1D01*
G01X1260702D01*
G02X1260400Y1721335I1J303D01*
G01Y1723739D01*
G02X1260386Y1723976I2002J237D01*
G02X1260400Y1724213I2016J0D01*
G01Y1728463D01*
G02X1260386Y1728700I2002J237D01*
G02X1260400Y1728937I2016J0D01*
G01Y1731341D01*
G02X1260702Y1731644I302J1D01*
G37*
G36*
G01X1276450D02*
X1280150D01*
G02X1280452Y1731341I-1J-303D01*
G01Y1721335D01*
G02X1280150Y1721032I-302J-1D01*
G01X1276450D01*
G02X1276148Y1721335I1J303D01*
G01Y1723739D01*
G02X1276134Y1723976I2002J237D01*
G02X1276148Y1724213I2016J0D01*
G01Y1728463D01*
G02X1276134Y1728700I2002J237D01*
G02X1276148Y1728937I2016J0D01*
G01Y1731341D01*
G02X1276450Y1731644I302J1D01*
G37*
G36*
G01X1292198D02*
X1295898D01*
G02X1296200Y1731341I-1J-303D01*
G01Y1721335D01*
G02X1295898Y1721032I-302J-1D01*
G01X1292198D01*
G02X1291896Y1721335I1J303D01*
G01Y1723739D01*
G02X1291882Y1723976I2002J237D01*
G02X1291896Y1724213I2016J0D01*
G01Y1728463D01*
G02X1291882Y1728700I2002J237D01*
G02X1291896Y1728937I2016J0D01*
G01Y1731341D01*
G02X1292198Y1731644I302J1D01*
G37*
G36*
G01X1311883D02*
X1315583D01*
G02X1315886Y1731341I0J-303D01*
G01Y1721335D01*
G02X1315583Y1721032I-303J0D01*
G01X1311883D01*
G02X1311580Y1721335I0J303D01*
G01Y1723747D01*
G02X1311567Y1723976I2003J229D01*
G02X1311580Y1724205I2016J0D01*
G01Y1728471D01*
G02X1311567Y1728700I2003J229D01*
G02X1311580Y1728929I2016J0D01*
G01Y1731341D01*
G02X1311883Y1731644I303J0D01*
G37*
G36*
G01X1327631D02*
X1331331D01*
G02X1331634Y1731341I0J-303D01*
G01Y1721335D01*
G02X1331331Y1721032I-303J0D01*
G01X1327631D01*
G02X1327328Y1721335I0J303D01*
G01Y1723747D01*
G02X1327315Y1723976I2003J229D01*
G02X1327328Y1724205I2016J0D01*
G01Y1728471D01*
G02X1327315Y1728700I2003J229D01*
G02X1327328Y1728929I2016J0D01*
G01Y1731341D01*
G02X1327631Y1731644I303J0D01*
G37*
G36*
G01X1343379D02*
X1347079D01*
G02X1347382Y1731341I0J-303D01*
G01Y1721335D01*
G02X1347079Y1721032I-303J0D01*
G01X1343379D01*
G02X1343076Y1721335I0J303D01*
G01Y1723747D01*
G02X1343063Y1723976I2003J229D01*
G02X1343076Y1724205I2016J0D01*
G01Y1728471D01*
G02X1343063Y1728700I2003J229D01*
G02X1343076Y1728929I2016J0D01*
G01Y1731341D01*
G02X1343379Y1731644I303J0D01*
G37*
G36*
G01X1359127D02*
X1362827D01*
G02X1363130Y1731341I0J-303D01*
G01Y1721335D01*
G02X1362827Y1721032I-303J0D01*
G01X1359127D01*
G02X1358824Y1721335I0J303D01*
G01Y1723747D01*
G02X1358811Y1723976I2003J229D01*
G02X1358824Y1724205I2016J0D01*
G01Y1728471D01*
G02X1358811Y1728700I2003J229D01*
G02X1358824Y1728929I2016J0D01*
G01Y1731341D01*
G02X1359127Y1731644I303J0D01*
G37*
G36*
G01X1509127D02*
X1512827D01*
G02X1513130Y1731341I0J-303D01*
G01Y1721335D01*
G02X1512827Y1721032I-303J0D01*
G01X1509127D01*
G02X1508824Y1721335I0J303D01*
G01Y1723747D01*
G02X1508811Y1723976I2003J229D01*
G02X1508824Y1724205I2016J0D01*
G01Y1728471D01*
G02X1508811Y1728700I2003J229D01*
G02X1508824Y1728929I2016J0D01*
G01Y1731341D01*
G02X1509127Y1731644I303J0D01*
G37*
G36*
G01X1524875D02*
X1528575D01*
G02X1528878Y1731341I0J-303D01*
G01Y1721335D01*
G02X1528575Y1721032I-303J0D01*
G01X1524875D01*
G02X1524572Y1721335I0J303D01*
G01Y1723747D01*
G02X1524559Y1723976I2003J229D01*
G02X1524572Y1724205I2016J0D01*
G01Y1728471D01*
G02X1524559Y1728700I2003J229D01*
G02X1524572Y1728929I2016J0D01*
G01Y1731341D01*
G02X1524875Y1731644I303J0D01*
G37*
G36*
G01X1540623D02*
X1544323D01*
G02X1544626Y1731341I0J-303D01*
G01Y1721335D01*
G02X1544323Y1721032I-303J0D01*
G01X1540623D01*
G02X1540320Y1721335I0J303D01*
G01Y1723747D01*
G02X1540307Y1723976I2003J229D01*
G02X1540320Y1724205I2016J0D01*
G01Y1728471D01*
G02X1540307Y1728700I2003J229D01*
G02X1540320Y1728929I2016J0D01*
G01Y1731341D01*
G02X1540623Y1731644I303J0D01*
G37*
G36*
G01X1556371D02*
X1560071D01*
G02X1560374Y1731341I0J-303D01*
G01Y1721335D01*
G02X1560071Y1721032I-303J0D01*
G01X1556371D01*
G02X1556068Y1721335I0J303D01*
G01Y1723747D01*
G02X1556055Y1723976I2003J229D01*
G02X1556068Y1724205I2016J0D01*
G01Y1728471D01*
G02X1556055Y1728700I2003J229D01*
G02X1556068Y1728929I2016J0D01*
G01Y1731341D01*
G02X1556371Y1731644I303J0D01*
G37*
G36*
G01X1576056D02*
X1579756D01*
G02X1580058Y1731341I-1J-303D01*
G01Y1721335D01*
G02X1579756Y1721032I-302J-1D01*
G01X1576056D01*
G02X1575754Y1721335I1J303D01*
G01Y1723739D01*
G02X1575740Y1723976I2002J237D01*
G02X1575754Y1724213I2016J0D01*
G01Y1728463D01*
G02X1575740Y1728700I2002J237D01*
G02X1575754Y1728937I2016J0D01*
G01Y1731341D01*
G02X1576056Y1731644I302J1D01*
G37*
G36*
G01X1591804D02*
X1595504D01*
G02X1595806Y1731341I-1J-303D01*
G01Y1721335D01*
G02X1595504Y1721032I-302J-1D01*
G01X1591804D01*
G02X1591502Y1721335I1J303D01*
G01Y1723739D01*
G02X1591488Y1723976I2002J237D01*
G02X1591502Y1724213I2016J0D01*
G01Y1728463D01*
G02X1591488Y1728700I2002J237D01*
G02X1591502Y1728937I2016J0D01*
G01Y1731341D01*
G02X1591804Y1731644I302J1D01*
G37*
G36*
G01X1607552D02*
X1611252D01*
G02X1611554Y1731341I-1J-303D01*
G01Y1721335D01*
G02X1611252Y1721032I-302J-1D01*
G01X1607552D01*
G02X1607250Y1721335I1J303D01*
G01Y1723739D01*
G02X1607236Y1723976I2002J237D01*
G02X1607250Y1724213I2016J0D01*
G01Y1728463D01*
G02X1607236Y1728700I2002J237D01*
G02X1607250Y1728937I2016J0D01*
G01Y1731341D01*
G02X1607552Y1731644I302J1D01*
G37*
G36*
G01X1623300D02*
X1627000D01*
G02X1627302Y1731341I-1J-303D01*
G01Y1721335D01*
G02X1627000Y1721032I-302J-1D01*
G01X1623300D01*
G02X1622998Y1721335I1J303D01*
G01Y1723739D01*
G02X1622984Y1723976I2002J237D01*
G02X1622998Y1724213I2016J0D01*
G01Y1728463D01*
G02X1622984Y1728700I2002J237D01*
G02X1622998Y1728937I2016J0D01*
G01Y1731341D01*
G02X1623300Y1731644I302J1D01*
G37*
G36*
G01X105651Y1575002D02*
X102251D01*
G02Y1578006I0J1502D01*
G01X105651D01*
G02Y1575002I0J-1502D01*
G37*
G36*
G01X74218Y1574006D02*
X77618D01*
G02Y1571002I0J-1502D01*
G01X74218D01*
G02Y1574006I0J1502D01*
G37*
G36*
G01X76369Y1508958D02*
X79769D01*
G02Y1505954I0J-1502D01*
G01X76369D01*
G02Y1508958I0J1502D01*
G37*
G36*
G01X391330Y1583652D02*
X387930D01*
G02Y1586658I0J1503D01*
G01X391330D01*
G02Y1583652I0J-1503D01*
G37*
G36*
G01X148938Y1515872D02*
X145538D01*
G02Y1518876I0J1502D01*
G01X148938D01*
G02Y1515872I0J-1502D01*
G37*
G36*
G01X164710Y1519516D02*
X168110D01*
G02Y1516512I0J-1502D01*
G01X164710D01*
G02Y1519516I0J1502D01*
G37*
G36*
G01X89264Y1509114D02*
X92664D01*
G02Y1506108I0J-1503D01*
G01X89264D01*
G02Y1509114I0J1503D01*
G37*
G36*
G01X167266Y1571470D02*
X170666D01*
G02Y1568466I0J-1502D01*
G01X167266D01*
G02Y1571470I0J1502D01*
G37*
G36*
G01X1346792Y1615794D02*
X1350192D01*
G02Y1612790I0J-1502D01*
G01X1346792D01*
G02Y1615794I0J1502D01*
G37*
G36*
G01X1358852D02*
X1362252D01*
G02Y1612790I0J-1502D01*
G01X1358852D01*
G02Y1615794I0J1502D01*
G37*
G36*
G01X1365612Y1591596D02*
X1369012D01*
G02Y1588592I0J-1502D01*
G01X1365612D01*
G02Y1591596I0J1502D01*
G37*
G36*
G01Y1579684D02*
X1369012D01*
G02Y1576680I0J-1502D01*
G01X1365612D01*
G02Y1579684I0J1502D01*
G37*
G36*
G01X1305312D02*
X1308712D01*
G02Y1576680I0J-1502D01*
G01X1305312D01*
G02Y1579684I0J1502D01*
G37*
G36*
G01X1293252Y1591596D02*
X1296652D01*
G02Y1588592I0J-1502D01*
G01X1293252D01*
G02Y1591596I0J1502D01*
G37*
G36*
G01X1310612Y1615794D02*
X1314012D01*
G02Y1612790I0J-1502D01*
G01X1310612D01*
G02Y1615794I0J1502D01*
G37*
G36*
G01X1262372Y1603882D02*
X1265772D01*
G02Y1600878I0J-1502D01*
G01X1262372D01*
G02Y1603882I0J1502D01*
G37*
G36*
G01X1286492Y1615794D02*
X1289892D01*
G02Y1612790I0J-1502D01*
G01X1286492D01*
G02Y1615794I0J1502D01*
G37*
G36*
G01X1262372D02*
X1265772D01*
G02Y1612790I0J-1502D01*
G01X1262372D01*
G02Y1615794I0J1502D01*
G37*
G36*
G01X1334732Y1603882D02*
X1338132D01*
G02Y1600878I0J-1502D01*
G01X1334732D01*
G02Y1603882I0J1502D01*
G37*
G36*
G01X1220892Y1579684D02*
X1224292D01*
G02Y1576680I0J-1502D01*
G01X1220892D01*
G02Y1579684I0J1502D01*
G37*
G36*
G01X1334732Y1615794D02*
X1338132D01*
G02Y1612790I0J-1502D01*
G01X1334732D01*
G02Y1615794I0J1502D01*
G37*
G36*
G01X1370912Y1603882D02*
X1374312D01*
G02Y1600878I0J-1502D01*
G01X1370912D01*
G02Y1603882I0J1502D01*
G37*
G36*
G01X1214132D02*
X1217532D01*
G02Y1600878I0J-1502D01*
G01X1214132D01*
G02Y1603882I0J1502D01*
G37*
G36*
G01X1286492D02*
X1289892D01*
G02Y1600878I0J-1502D01*
G01X1286492D01*
G02Y1603882I0J1502D01*
G37*
G36*
G01X1298552D02*
X1301952D01*
G02Y1600878I0J-1502D01*
G01X1298552D01*
G02Y1603882I0J1502D01*
G37*
G36*
G01X1353552Y1579684D02*
X1356952D01*
G02Y1576680I0J-1502D01*
G01X1353552D01*
G02Y1579684I0J1502D01*
G37*
G36*
G01X1341492Y1591596D02*
X1344892D01*
G02Y1588592I0J-1502D01*
G01X1341492D01*
G02Y1591596I0J1502D01*
G37*
G36*
G01X1370912Y1615794D02*
X1374312D01*
G02Y1612790I0J-1502D01*
G01X1370912D01*
G02Y1615794I0J1502D01*
G37*
G36*
G01X1269132Y1591596D02*
X1272532D01*
G02Y1588592I0J-1502D01*
G01X1269132D01*
G02Y1591596I0J1502D01*
G37*
G36*
G01X1238252Y1603882D02*
X1241652D01*
G02Y1600878I0J-1502D01*
G01X1238252D01*
G02Y1603882I0J1502D01*
G37*
G36*
G01X1353552Y1591596D02*
X1356952D01*
G02Y1588592I0J-1502D01*
G01X1353552D01*
G02Y1591596I0J1502D01*
G37*
G36*
G01X1214132Y1615794D02*
X1217532D01*
G02Y1612790I0J-1502D01*
G01X1214132D01*
G02Y1615794I0J1502D01*
G37*
G36*
G01X1226192Y1603882D02*
X1229592D01*
G02Y1600878I0J-1502D01*
G01X1226192D01*
G02Y1603882I0J1502D01*
G37*
G36*
G01X1208832Y1579684D02*
X1212232D01*
G02Y1576680I0J-1502D01*
G01X1208832D01*
G02Y1579684I0J1502D01*
G37*
G36*
G01Y1591596D02*
X1212232D01*
G02Y1588592I0J-1502D01*
G01X1208832D01*
G02Y1591596I0J1502D01*
G37*
G36*
G01X1341492Y1579684D02*
X1344892D01*
G02Y1576680I0J-1502D01*
G01X1341492D01*
G02Y1579684I0J1502D01*
G37*
G36*
G01X1250312Y1615794D02*
X1253712D01*
G02Y1612790I0J-1502D01*
G01X1250312D01*
G02Y1615794I0J1502D01*
G37*
G36*
G01X1232952Y1579684D02*
X1236352D01*
G02Y1576680I0J-1502D01*
G01X1232952D01*
G02Y1579684I0J1502D01*
G37*
G36*
G01Y1591596D02*
X1236352D01*
G02Y1588592I0J-1502D01*
G01X1232952D01*
G02Y1591596I0J1502D01*
G37*
G36*
G01X1196772Y1579684D02*
X1200172D01*
G02Y1576680I0J-1502D01*
G01X1196772D01*
G02Y1579684I0J1502D01*
G37*
G36*
G01X1257072D02*
X1260472D01*
G02Y1576680I0J-1502D01*
G01X1257072D01*
G02Y1579684I0J1502D01*
G37*
G36*
G01X1220892Y1591596D02*
X1224292D01*
G02Y1588592I0J-1502D01*
G01X1220892D01*
G02Y1591596I0J1502D01*
G37*
G36*
G01X1269132Y1579684D02*
X1272532D01*
G02Y1576680I0J-1502D01*
G01X1269132D01*
G02Y1579684I0J1502D01*
G37*
G36*
G01X1305312Y1591596D02*
X1308712D01*
G02Y1588592I0J-1502D01*
G01X1305312D01*
G02Y1591596I0J1502D01*
G37*
G36*
G01X1245012D02*
X1248412D01*
G02Y1588592I0J-1502D01*
G01X1245012D01*
G02Y1591596I0J1502D01*
G37*
G36*
G01X1250312Y1603882D02*
X1253712D01*
G02Y1600878I0J-1502D01*
G01X1250312D01*
G02Y1603882I0J1502D01*
G37*
G36*
G01X1317372Y1579684D02*
X1320772D01*
G02Y1576680I0J-1502D01*
G01X1317372D01*
G02Y1579684I0J1502D01*
G37*
G36*
G01X1358852Y1603882D02*
X1362252D01*
G02Y1600878I0J-1502D01*
G01X1358852D01*
G02Y1603882I0J1502D01*
G37*
G36*
G01X1202072D02*
X1205472D01*
G02Y1600878I0J-1502D01*
G01X1202072D01*
G02Y1603882I0J1502D01*
G37*
G36*
G01Y1615794D02*
X1205472D01*
G02Y1612790I0J-1502D01*
G01X1202072D01*
G02Y1615794I0J1502D01*
G37*
G36*
G01X1322672Y1603882D02*
X1326072D01*
G02Y1600878I0J-1502D01*
G01X1322672D01*
G02Y1603882I0J1502D01*
G37*
G36*
G01X1310612D02*
X1314012D01*
G02Y1600878I0J-1502D01*
G01X1310612D01*
G02Y1603882I0J1502D01*
G37*
G36*
G01X1274432Y1615794D02*
X1277832D01*
G02Y1612790I0J-1502D01*
G01X1274432D01*
G02Y1615794I0J1502D01*
G37*
G36*
G01X1329432Y1579684D02*
X1332832D01*
G02Y1576680I0J-1502D01*
G01X1329432D01*
G02Y1579684I0J1502D01*
G37*
G36*
G01X1346792Y1603882D02*
X1350192D01*
G02Y1600878I0J-1502D01*
G01X1346792D01*
G02Y1603882I0J1502D01*
G37*
G36*
G01X1317372Y1591596D02*
X1320772D01*
G02Y1588592I0J-1502D01*
G01X1317372D01*
G02Y1591596I0J1502D01*
G37*
G36*
G01X1329432D02*
X1332832D01*
G02Y1588592I0J-1502D01*
G01X1329432D01*
G02Y1591596I0J1502D01*
G37*
G36*
G01X1322672Y1615794D02*
X1326072D01*
G02Y1612790I0J-1502D01*
G01X1322672D01*
G02Y1615794I0J1502D01*
G37*
G36*
G01X1281192Y1591596D02*
X1284592D01*
G02Y1588592I0J-1502D01*
G01X1281192D01*
G02Y1591596I0J1502D01*
G37*
G36*
G01X1196772D02*
X1200172D01*
G02Y1588592I0J-1502D01*
G01X1196772D01*
G02Y1591596I0J1502D01*
G37*
G36*
G01X1226192Y1615794D02*
X1229592D01*
G02Y1612790I0J-1502D01*
G01X1226192D01*
G02Y1615794I0J1502D01*
G37*
G36*
G01X1293252Y1579684D02*
X1296652D01*
G02Y1576680I0J-1502D01*
G01X1293252D01*
G02Y1579684I0J1502D01*
G37*
G36*
G01X1298552Y1615794D02*
X1301952D01*
G02Y1612790I0J-1502D01*
G01X1298552D01*
G02Y1615794I0J1502D01*
G37*
G36*
G01X1281192Y1579684D02*
X1284592D01*
G02Y1576680I0J-1502D01*
G01X1281192D01*
G02Y1579684I0J1502D01*
G37*
G36*
G01X1245012D02*
X1248412D01*
G02Y1576680I0J-1502D01*
G01X1245012D01*
G02Y1579684I0J1502D01*
G37*
G36*
G01X1257072Y1591596D02*
X1260472D01*
G02Y1588592I0J-1502D01*
G01X1257072D01*
G02Y1591596I0J1502D01*
G37*
G36*
G01X1274432Y1603882D02*
X1277832D01*
G02Y1600878I0J-1502D01*
G01X1274432D01*
G02Y1603882I0J1502D01*
G37*
G36*
G01X1238252Y1615794D02*
X1241652D01*
G02Y1612790I0J-1502D01*
G01X1238252D01*
G02Y1615794I0J1502D01*
G37*
G36*
G01X146312Y1571028D02*
X149712D01*
G02Y1568022I0J-1503D01*
G01X146312D01*
G02Y1571028I0J1503D01*
G37*
G36*
G01X1701934Y76800D02*
X1705334D01*
G02Y73794I0J-1503D01*
G01X1701934D01*
G02Y76800I0J1503D01*
G37*
G36*
G01X1690934Y70800D02*
X1694334D01*
G02Y67794I0J-1503D01*
G01X1690934D01*
G02Y70800I0J1503D01*
G37*
G36*
G01X1679934Y76800D02*
X1683334D01*
G02Y73794I0J-1503D01*
G01X1679934D01*
G02Y76800I0J1503D01*
G37*
G36*
G01X1657800D02*
X1661200D01*
G02Y73794I0J-1503D01*
G01X1657800D01*
G02Y76800I0J1503D01*
G37*
G36*
G01X1668800Y70800D02*
X1672200D01*
G02Y67794I0J-1503D01*
G01X1668800D01*
G02Y70800I0J1503D01*
G37*
G36*
G01X1646800D02*
X1650200D01*
G02Y67794I0J-1503D01*
G01X1646800D01*
G02Y70800I0J1503D01*
G37*
G36*
G01X1635800Y76800D02*
X1639200D01*
G02Y73794I0J-1503D01*
G01X1635800D01*
G02Y76800I0J1503D01*
G37*
G36*
G01X1612596D02*
X1615996D01*
G02Y73794I0J-1503D01*
G01X1612596D01*
G02Y76800I0J1503D01*
G37*
G36*
G01X1623596Y70800D02*
X1626996D01*
G02Y67794I0J-1503D01*
G01X1623596D01*
G02Y70800I0J1503D01*
G37*
G36*
G01X1601596D02*
X1604996D01*
G02Y67794I0J-1503D01*
G01X1601596D01*
G02Y70800I0J1503D01*
G37*
G36*
G01X1590596Y76800D02*
X1593996D01*
G02Y73794I0J-1503D01*
G01X1590596D01*
G02Y76800I0J1503D01*
G37*
G36*
G01X1579596Y70800D02*
X1582996D01*
G02Y67794I0J-1503D01*
G01X1579596D01*
G02Y70800I0J1503D01*
G37*
G36*
G01X1568596Y76800D02*
X1571996D01*
G02Y73794I0J-1503D01*
G01X1568596D01*
G02Y76800I0J1503D01*
G37*
G36*
G01X1546596D02*
X1549996D01*
G02Y73794I0J-1503D01*
G01X1546596D01*
G02Y76800I0J1503D01*
G37*
G36*
G01X1557596Y70800D02*
X1560996D01*
G02Y67794I0J-1503D01*
G01X1557596D01*
G02Y70800I0J1503D01*
G37*
G36*
G01X1535596D02*
X1538996D01*
G02Y67794I0J-1503D01*
G01X1535596D01*
G02Y70800I0J1503D01*
G37*
G36*
G01X230895Y73838D02*
X227495D01*
G02Y76842I0J1502D01*
G01X230895D01*
G02Y73838I0J-1502D01*
G37*
G36*
G01X219895Y67838D02*
X216495D01*
G02Y70842I0J1502D01*
G01X219895D01*
G02Y67838I0J-1502D01*
G37*
G36*
G01X208895Y73838D02*
X205495D01*
G02Y76842I0J1502D01*
G01X208895D01*
G02Y73838I0J-1502D01*
G37*
G36*
G01X194361Y70842D02*
X197761D01*
G02Y67838I0J-1502D01*
G01X194361D01*
G02Y70842I0J1502D01*
G37*
G36*
G01X183361Y76842D02*
X186761D01*
G02Y73838I0J-1502D01*
G01X183361D01*
G02Y76842I0J1502D01*
G37*
G36*
G01X161361D02*
X164761D01*
G02Y73838I0J-1502D01*
G01X161361D01*
G02Y76842I0J1502D01*
G37*
G36*
G01X172361Y70842D02*
X175761D01*
G02Y67838I0J-1502D01*
G01X172361D01*
G02Y70842I0J1502D01*
G37*
G36*
G01X149157D02*
X152557D01*
G02Y67838I0J-1502D01*
G01X149157D01*
G02Y70842I0J1502D01*
G37*
G36*
G01X138157Y76842D02*
X141557D01*
G02Y73838I0J-1502D01*
G01X138157D01*
G02Y76842I0J1502D01*
G37*
G36*
G01X116157D02*
X119557D01*
G02Y73838I0J-1502D01*
G01X116157D01*
G02Y76842I0J1502D01*
G37*
G36*
G01X127157Y70842D02*
X130557D01*
G02Y67838I0J-1502D01*
G01X127157D01*
G02Y70842I0J1502D01*
G37*
G36*
G01X105157D02*
X108557D01*
G02Y67838I0J-1502D01*
G01X105157D01*
G02Y70842I0J1502D01*
G37*
G36*
G01X94157Y76842D02*
X97557D01*
G02Y73838I0J-1502D01*
G01X94157D01*
G02Y76842I0J1502D01*
G37*
G36*
G01X83157Y70842D02*
X86557D01*
G02Y67838I0J-1502D01*
G01X83157D01*
G02Y70842I0J1502D01*
G37*
G36*
G01X72157Y76842D02*
X75557D01*
G02Y73838I0J-1502D01*
G01X72157D01*
G02Y76842I0J1502D01*
G37*
G36*
G01X61157Y70842D02*
X64557D01*
G02Y67838I0J-1502D01*
G01X61157D01*
G02Y70842I0J1502D01*
G37*
G36*
G01X1619075Y1579684D02*
X1622475D01*
G02Y1576680I0J-1502D01*
G01X1619075D01*
G02Y1579684I0J1502D01*
G37*
G36*
G01X326857Y1603882D02*
X330257D01*
G02Y1600878I0J-1502D01*
G01X326857D01*
G02Y1603882I0J1502D01*
G37*
G36*
G01X363037Y1615794D02*
X366437D01*
G02Y1612790I0J-1502D01*
G01X363037D01*
G02Y1615794I0J1502D01*
G37*
G36*
G01X545411Y1579684D02*
X548811D01*
G02Y1576680I0J-1502D01*
G01X545411D01*
G02Y1579684I0J1502D01*
G37*
G36*
G01Y1591596D02*
X548811D01*
G02Y1588592I0J-1502D01*
G01X545411D01*
G02Y1591596I0J1502D01*
G37*
G36*
G01X1377672D02*
X1381072D01*
G02Y1588592I0J-1502D01*
G01X1377672D01*
G02Y1591596I0J1502D01*
G37*
G36*
G01X533351D02*
X536751D01*
G02Y1588592I0J-1502D01*
G01X533351D01*
G02Y1591596I0J1502D01*
G37*
G36*
G01Y1579684D02*
X536751D01*
G02Y1576680I0J-1502D01*
G01X533351D01*
G02Y1579684I0J1502D01*
G37*
G36*
G01X1594955Y1591596D02*
X1598355D01*
G02Y1588592I0J-1502D01*
G01X1594955D01*
G02Y1591596I0J1502D01*
G37*
G36*
G01X581591D02*
X584991D01*
G02Y1588592I0J-1502D01*
G01X581591D01*
G02Y1591596I0J1502D01*
G37*
G36*
G01Y1579684D02*
X584991D01*
G02Y1576680I0J-1502D01*
G01X581591D01*
G02Y1579684I0J1502D01*
G37*
G36*
G01X1594955D02*
X1598355D01*
G02Y1576680I0J-1502D01*
G01X1594955D01*
G02Y1579684I0J1502D01*
G37*
G36*
G01X605711Y1591596D02*
X609111D01*
G02Y1588592I0J-1502D01*
G01X605711D01*
G02Y1591596I0J1502D01*
G37*
G36*
G01X333617Y1579684D02*
X337017D01*
G02Y1576680I0J-1502D01*
G01X333617D01*
G02Y1579684I0J1502D01*
G37*
G36*
G01X345677D02*
X349077D01*
G02Y1576680I0J-1502D01*
G01X345677D01*
G02Y1579684I0J1502D01*
G37*
G36*
G01X617771D02*
X621171D01*
G02Y1576680I0J-1502D01*
G01X617771D01*
G02Y1579684I0J1502D01*
G37*
G36*
G01Y1591596D02*
X621171D01*
G02Y1588592I0J-1502D01*
G01X617771D01*
G02Y1591596I0J1502D01*
G37*
G36*
G01X629831Y1579684D02*
X633231D01*
G02Y1576680I0J-1502D01*
G01X629831D01*
G02Y1579684I0J1502D01*
G37*
G36*
G01X1582895D02*
X1586295D01*
G02Y1576680I0J-1502D01*
G01X1582895D01*
G02Y1579684I0J1502D01*
G37*
G36*
G01X1570835D02*
X1574235D01*
G02Y1576680I0J-1502D01*
G01X1570835D01*
G02Y1579684I0J1502D01*
G37*
G36*
G01X1558775D02*
X1562175D01*
G02Y1576680I0J-1502D01*
G01X1558775D01*
G02Y1579684I0J1502D01*
G37*
G36*
G01X321557D02*
X324957D01*
G02Y1576680I0J-1502D01*
G01X321557D01*
G02Y1579684I0J1502D01*
G37*
G36*
G01X278617Y1603882D02*
X282017D01*
G02Y1600878I0J-1502D01*
G01X278617D01*
G02Y1603882I0J1502D01*
G37*
G36*
G01X1534655Y1591596D02*
X1538055D01*
G02Y1588592I0J-1502D01*
G01X1534655D01*
G02Y1591596I0J1502D01*
G37*
G36*
G01Y1579684D02*
X1538055D01*
G02Y1576680I0J-1502D01*
G01X1534655D01*
G02Y1579684I0J1502D01*
G37*
G36*
G01X1510535Y1591596D02*
X1513935D01*
G02Y1588592I0J-1502D01*
G01X1510535D01*
G02Y1591596I0J1502D01*
G37*
G36*
G01X1522595D02*
X1525995D01*
G02Y1588592I0J-1502D01*
G01X1522595D01*
G02Y1591596I0J1502D01*
G37*
G36*
G01X309497Y1579684D02*
X312897D01*
G02Y1576680I0J-1502D01*
G01X309497D01*
G02Y1579684I0J1502D01*
G37*
G36*
G01X302737Y1603882D02*
X306137D01*
G02Y1600878I0J-1502D01*
G01X302737D01*
G02Y1603882I0J1502D01*
G37*
G36*
G01X1498475Y1579684D02*
X1501875D01*
G02Y1576680I0J-1502D01*
G01X1498475D01*
G02Y1579684I0J1502D01*
G37*
G36*
G01X314797Y1615794D02*
X318197D01*
G02Y1612790I0J-1502D01*
G01X314797D01*
G02Y1615794I0J1502D01*
G37*
G36*
G01X278617D02*
X282017D01*
G02Y1612790I0J-1502D01*
G01X278617D01*
G02Y1615794I0J1502D01*
G37*
G36*
G01X497171Y1591596D02*
X500571D01*
G02Y1588592I0J-1502D01*
G01X497171D01*
G02Y1591596I0J1502D01*
G37*
G36*
G01X509231D02*
X512631D01*
G02Y1588592I0J-1502D01*
G01X509231D01*
G02Y1591596I0J1502D01*
G37*
G36*
G01Y1579684D02*
X512631D01*
G02Y1576680I0J-1502D01*
G01X509231D01*
G02Y1579684I0J1502D01*
G37*
G36*
G01X1486415Y1591596D02*
X1489815D01*
G02Y1588592I0J-1502D01*
G01X1486415D01*
G02Y1591596I0J1502D01*
G37*
G36*
G01Y1579684D02*
X1489815D01*
G02Y1576680I0J-1502D01*
G01X1486415D01*
G02Y1579684I0J1502D01*
G37*
G36*
G01X321557Y1591596D02*
X324957D01*
G02Y1588592I0J-1502D01*
G01X321557D01*
G02Y1591596I0J1502D01*
G37*
G36*
G01X1462295D02*
X1465695D01*
G02Y1588592I0J-1502D01*
G01X1462295D01*
G02Y1591596I0J1502D01*
G37*
G36*
G01X1474355D02*
X1477755D01*
G02Y1588592I0J-1502D01*
G01X1474355D01*
G02Y1591596I0J1502D01*
G37*
G36*
G01X641891Y1579684D02*
X645291D01*
G02Y1576680I0J-1502D01*
G01X641891D01*
G02Y1579684I0J1502D01*
G37*
G36*
G01Y1591596D02*
X645291D01*
G02Y1588592I0J-1502D01*
G01X641891D01*
G02Y1591596I0J1502D01*
G37*
G36*
G01X285377Y1579684D02*
X288777D01*
G02Y1576680I0J-1502D01*
G01X285377D01*
G02Y1579684I0J1502D01*
G37*
G36*
G01X1462295D02*
X1465695D01*
G02Y1576680I0J-1502D01*
G01X1462295D01*
G02Y1579684I0J1502D01*
G37*
G36*
G01X206257Y1615794D02*
X209657D01*
G02Y1612790I0J-1502D01*
G01X206257D01*
G02Y1615794I0J1502D01*
G37*
G36*
G01X338917D02*
X342317D01*
G02Y1612790I0J-1502D01*
G01X338917D01*
G02Y1615794I0J1502D01*
G37*
G36*
G01X1474355Y1579684D02*
X1477755D01*
G02Y1576680I0J-1502D01*
G01X1474355D01*
G02Y1579684I0J1502D01*
G37*
G36*
G01X261257D02*
X264657D01*
G02Y1576680I0J-1502D01*
G01X261257D01*
G02Y1579684I0J1502D01*
G37*
G36*
G01X485111D02*
X488511D01*
G02Y1576680I0J-1502D01*
G01X485111D01*
G02Y1579684I0J1502D01*
G37*
G36*
G01Y1591596D02*
X488511D01*
G02Y1588592I0J-1502D01*
G01X485111D01*
G02Y1591596I0J1502D01*
G37*
G36*
G01X338917Y1603882D02*
X342317D01*
G02Y1600878I0J-1502D01*
G01X338917D01*
G02Y1603882I0J1502D01*
G37*
G36*
G01X1648495Y1615794D02*
X1651895D01*
G02Y1612790I0J-1502D01*
G01X1648495D01*
G02Y1615794I0J1502D01*
G37*
G36*
G01Y1603882D02*
X1651895D01*
G02Y1600878I0J-1502D01*
G01X1648495D01*
G02Y1603882I0J1502D01*
G37*
G36*
G01X1624375Y1615794D02*
X1627775D01*
G02Y1612790I0J-1502D01*
G01X1624375D01*
G02Y1615794I0J1502D01*
G37*
G36*
G01X266557D02*
X269957D01*
G02Y1612790I0J-1502D01*
G01X266557D01*
G02Y1615794I0J1502D01*
G37*
G36*
G01X254497Y1603882D02*
X257897D01*
G02Y1600878I0J-1502D01*
G01X254497D01*
G02Y1603882I0J1502D01*
G37*
G36*
G01X653951Y1591596D02*
X657351D01*
G02Y1588592I0J-1502D01*
G01X653951D01*
G02Y1591596I0J1502D01*
G37*
G36*
G01Y1579684D02*
X657351D01*
G02Y1576680I0J-1502D01*
G01X653951D01*
G02Y1579684I0J1502D01*
G37*
G36*
G01X369797Y1591596D02*
X373197D01*
G02Y1588592I0J-1502D01*
G01X369797D01*
G02Y1591596I0J1502D01*
G37*
G36*
G01X1636435Y1603882D02*
X1639835D01*
G02Y1600878I0J-1502D01*
G01X1636435D01*
G02Y1603882I0J1502D01*
G37*
G36*
G01X266557D02*
X269957D01*
G02Y1600878I0J-1502D01*
G01X266557D01*
G02Y1603882I0J1502D01*
G37*
G36*
G01X1624375D02*
X1627775D01*
G02Y1600878I0J-1502D01*
G01X1624375D01*
G02Y1603882I0J1502D01*
G37*
G36*
G01X254497Y1615794D02*
X257897D01*
G02Y1612790I0J-1502D01*
G01X254497D01*
G02Y1615794I0J1502D01*
G37*
G36*
G01X194197Y1603882D02*
X197597D01*
G02Y1600878I0J-1502D01*
G01X194197D01*
G02Y1603882I0J1502D01*
G37*
G36*
G01X242437D02*
X245837D01*
G02Y1600878I0J-1502D01*
G01X242437D01*
G02Y1603882I0J1502D01*
G37*
G36*
G01X1612315D02*
X1615715D01*
G02Y1600878I0J-1502D01*
G01X1612315D01*
G02Y1603882I0J1502D01*
G37*
G36*
G01Y1615794D02*
X1615715D01*
G02Y1612790I0J-1502D01*
G01X1612315D01*
G02Y1615794I0J1502D01*
G37*
G36*
G01X230377D02*
X233777D01*
G02Y1612790I0J-1502D01*
G01X230377D01*
G02Y1615794I0J1502D01*
G37*
G36*
G01X521291Y1579684D02*
X524691D01*
G02Y1576680I0J-1502D01*
G01X521291D01*
G02Y1579684I0J1502D01*
G37*
G36*
G01Y1591596D02*
X524691D01*
G02Y1588592I0J-1502D01*
G01X521291D01*
G02Y1591596I0J1502D01*
G37*
G36*
G01X497171Y1579684D02*
X500571D01*
G02Y1576680I0J-1502D01*
G01X497171D01*
G02Y1579684I0J1502D01*
G37*
G36*
G01X593651D02*
X597051D01*
G02Y1576680I0J-1502D01*
G01X593651D01*
G02Y1579684I0J1502D01*
G37*
G36*
G01Y1591596D02*
X597051D01*
G02Y1588592I0J-1502D01*
G01X593651D01*
G02Y1591596I0J1502D01*
G37*
G36*
G01X1600255Y1603882D02*
X1603655D01*
G02Y1600878I0J-1502D01*
G01X1600255D01*
G02Y1603882I0J1502D01*
G37*
G36*
G01Y1615794D02*
X1603655D01*
G02Y1612790I0J-1502D01*
G01X1600255D01*
G02Y1615794I0J1502D01*
G37*
G36*
G01X557471Y1579684D02*
X560871D01*
G02Y1576680I0J-1502D01*
G01X557471D01*
G02Y1579684I0J1502D01*
G37*
G36*
G01X569531D02*
X572931D01*
G02Y1576680I0J-1502D01*
G01X569531D01*
G02Y1579684I0J1502D01*
G37*
G36*
G01Y1591596D02*
X572931D01*
G02Y1588592I0J-1502D01*
G01X569531D01*
G02Y1591596I0J1502D01*
G37*
G36*
G01X557471D02*
X560871D01*
G02Y1588592I0J-1502D01*
G01X557471D01*
G02Y1591596I0J1502D01*
G37*
G36*
G01X333617D02*
X337017D01*
G02Y1588592I0J-1502D01*
G01X333617D01*
G02Y1591596I0J1502D01*
G37*
G36*
G01X345677D02*
X349077D01*
G02Y1588592I0J-1502D01*
G01X345677D01*
G02Y1591596I0J1502D01*
G37*
G36*
G01X1607015Y1579684D02*
X1610415D01*
G02Y1576680I0J-1502D01*
G01X1607015D01*
G02Y1579684I0J1502D01*
G37*
G36*
G01X1576135Y1615794D02*
X1579535D01*
G02Y1612790I0J-1502D01*
G01X1576135D01*
G02Y1615794I0J1502D01*
G37*
G36*
G01X314797Y1603882D02*
X318197D01*
G02Y1600878I0J-1502D01*
G01X314797D01*
G02Y1603882I0J1502D01*
G37*
G36*
G01X1576135D02*
X1579535D01*
G02Y1600878I0J-1502D01*
G01X1576135D01*
G02Y1603882I0J1502D01*
G37*
G36*
G01X261257Y1591596D02*
X264657D01*
G02Y1588592I0J-1502D01*
G01X261257D01*
G02Y1591596I0J1502D01*
G37*
G36*
G01X357737Y1579684D02*
X361137D01*
G02Y1576680I0J-1502D01*
G01X357737D01*
G02Y1579684I0J1502D01*
G37*
G36*
G01X1546715Y1591596D02*
X1550115D01*
G02Y1588592I0J-1502D01*
G01X1546715D01*
G02Y1591596I0J1502D01*
G37*
G36*
G01Y1579684D02*
X1550115D01*
G02Y1576680I0J-1502D01*
G01X1546715D01*
G02Y1579684I0J1502D01*
G37*
G36*
G01X326857Y1615794D02*
X330257D01*
G02Y1612790I0J-1502D01*
G01X326857D01*
G02Y1615794I0J1502D01*
G37*
G36*
G01X249197Y1591596D02*
X252597D01*
G02Y1588592I0J-1502D01*
G01X249197D01*
G02Y1591596I0J1502D01*
G37*
G36*
G01X309497D02*
X312897D01*
G02Y1588592I0J-1502D01*
G01X309497D01*
G02Y1591596I0J1502D01*
G37*
G36*
G01X1564075Y1603882D02*
X1567475D01*
G02Y1600878I0J-1502D01*
G01X1564075D01*
G02Y1603882I0J1502D01*
G37*
G36*
G01Y1615794D02*
X1567475D01*
G02Y1612790I0J-1502D01*
G01X1564075D01*
G02Y1615794I0J1502D01*
G37*
G36*
G01X1552015D02*
X1555415D01*
G02Y1612790I0J-1502D01*
G01X1552015D01*
G02Y1615794I0J1502D01*
G37*
G36*
G01X1503775D02*
X1507175D01*
G02Y1612790I0J-1502D01*
G01X1503775D01*
G02Y1615794I0J1502D01*
G37*
G36*
G01X1552015Y1603882D02*
X1555415D01*
G02Y1600878I0J-1502D01*
G01X1552015D01*
G02Y1603882I0J1502D01*
G37*
G36*
G01X629831Y1591596D02*
X633231D01*
G02Y1588592I0J-1502D01*
G01X629831D01*
G02Y1591596I0J1502D01*
G37*
G36*
G01X1377672Y1579684D02*
X1381072D01*
G02Y1576680I0J-1502D01*
G01X1377672D01*
G02Y1579684I0J1502D01*
G37*
G36*
G01X218317Y1603882D02*
X221717D01*
G02Y1600878I0J-1502D01*
G01X218317D01*
G02Y1603882I0J1502D01*
G37*
G36*
G01X206257D02*
X209657D01*
G02Y1600878I0J-1502D01*
G01X206257D01*
G02Y1603882I0J1502D01*
G37*
G36*
G01X1527895Y1615794D02*
X1531295D01*
G02Y1612790I0J-1502D01*
G01X1527895D01*
G02Y1615794I0J1502D01*
G37*
G36*
G01X200957Y1591596D02*
X204357D01*
G02Y1588592I0J-1502D01*
G01X200957D01*
G02Y1591596I0J1502D01*
G37*
G36*
G01X1631135D02*
X1634535D01*
G02Y1588592I0J-1502D01*
G01X1631135D01*
G02Y1591596I0J1502D01*
G37*
G36*
G01X1539955Y1615794D02*
X1543355D01*
G02Y1612790I0J-1502D01*
G01X1539955D01*
G02Y1615794I0J1502D01*
G37*
G36*
G01Y1603882D02*
X1543355D01*
G02Y1600878I0J-1502D01*
G01X1539955D01*
G02Y1603882I0J1502D01*
G37*
G36*
G01X1527895D02*
X1531295D01*
G02Y1600878I0J-1502D01*
G01X1527895D01*
G02Y1603882I0J1502D01*
G37*
G36*
G01X302737Y1615794D02*
X306137D01*
G02Y1612790I0J-1502D01*
G01X302737D01*
G02Y1615794I0J1502D01*
G37*
G36*
G01X1522595Y1579684D02*
X1525995D01*
G02Y1576680I0J-1502D01*
G01X1522595D01*
G02Y1579684I0J1502D01*
G37*
G36*
G01X1515835Y1615794D02*
X1519235D01*
G02Y1612790I0J-1502D01*
G01X1515835D01*
G02Y1615794I0J1502D01*
G37*
G36*
G01X1636435D02*
X1639835D01*
G02Y1612790I0J-1502D01*
G01X1636435D01*
G02Y1615794I0J1502D01*
G37*
G36*
G01X1498475Y1591596D02*
X1501875D01*
G02Y1588592I0J-1502D01*
G01X1498475D01*
G02Y1591596I0J1502D01*
G37*
G36*
G01X1643195D02*
X1646595D01*
G02Y1588592I0J-1502D01*
G01X1643195D01*
G02Y1591596I0J1502D01*
G37*
G36*
G01X1515835Y1603882D02*
X1519235D01*
G02Y1600878I0J-1502D01*
G01X1515835D01*
G02Y1603882I0J1502D01*
G37*
G36*
G01X357737Y1591596D02*
X361137D01*
G02Y1588592I0J-1502D01*
G01X357737D01*
G02Y1591596I0J1502D01*
G37*
G36*
G01X194197Y1615794D02*
X197597D01*
G02Y1612790I0J-1502D01*
G01X194197D01*
G02Y1615794I0J1502D01*
G37*
G36*
G01X1510535Y1579684D02*
X1513935D01*
G02Y1576680I0J-1502D01*
G01X1510535D01*
G02Y1579684I0J1502D01*
G37*
G36*
G01X1570835Y1591596D02*
X1574235D01*
G02Y1588592I0J-1502D01*
G01X1570835D01*
G02Y1591596I0J1502D01*
G37*
G36*
G01X273317D02*
X276717D01*
G02Y1588592I0J-1502D01*
G01X273317D01*
G02Y1591596I0J1502D01*
G37*
G36*
G01Y1579684D02*
X276717D01*
G02Y1576680I0J-1502D01*
G01X273317D01*
G02Y1579684I0J1502D01*
G37*
G36*
G01X1491715Y1603882D02*
X1495115D01*
G02Y1600878I0J-1502D01*
G01X1491715D01*
G02Y1603882I0J1502D01*
G37*
G36*
G01Y1615794D02*
X1495115D01*
G02Y1612790I0J-1502D01*
G01X1491715D01*
G02Y1615794I0J1502D01*
G37*
G36*
G01X1631135Y1579684D02*
X1634535D01*
G02Y1576680I0J-1502D01*
G01X1631135D01*
G02Y1579684I0J1502D01*
G37*
G36*
G01X213017Y1591596D02*
X216417D01*
G02Y1588592I0J-1502D01*
G01X213017D01*
G02Y1591596I0J1502D01*
G37*
G36*
G01X188897Y1579684D02*
X192297D01*
G02Y1576680I0J-1502D01*
G01X188897D01*
G02Y1579684I0J1502D01*
G37*
G36*
G01X1503775Y1603882D02*
X1507175D01*
G02Y1600878I0J-1502D01*
G01X1503775D01*
G02Y1603882I0J1502D01*
G37*
G36*
G01X200957Y1579684D02*
X204357D01*
G02Y1576680I0J-1502D01*
G01X200957D01*
G02Y1579684I0J1502D01*
G37*
G36*
G01X605711D02*
X609111D01*
G02Y1576680I0J-1502D01*
G01X605711D01*
G02Y1579684I0J1502D01*
G37*
G36*
G01X1479655Y1603882D02*
X1483055D01*
G02Y1600878I0J-1502D01*
G01X1479655D01*
G02Y1603882I0J1502D01*
G37*
G36*
G01Y1615794D02*
X1483055D01*
G02Y1612790I0J-1502D01*
G01X1479655D01*
G02Y1615794I0J1502D01*
G37*
G36*
G01X249197Y1579684D02*
X252597D01*
G02Y1576680I0J-1502D01*
G01X249197D01*
G02Y1579684I0J1502D01*
G37*
G36*
G01X1467595Y1615794D02*
X1470995D01*
G02Y1612790I0J-1502D01*
G01X1467595D01*
G02Y1615794I0J1502D01*
G37*
G36*
G01Y1603882D02*
X1470995D01*
G02Y1600878I0J-1502D01*
G01X1467595D01*
G02Y1603882I0J1502D01*
G37*
G36*
G01X1558775Y1591596D02*
X1562175D01*
G02Y1588592I0J-1502D01*
G01X1558775D01*
G02Y1591596I0J1502D01*
G37*
G36*
G01X1643195Y1579684D02*
X1646595D01*
G02Y1576680I0J-1502D01*
G01X1643195D01*
G02Y1579684I0J1502D01*
G37*
G36*
G01X188897Y1591596D02*
X192297D01*
G02Y1588592I0J-1502D01*
G01X188897D01*
G02Y1591596I0J1502D01*
G37*
G36*
G01X1607015D02*
X1610415D01*
G02Y1588592I0J-1502D01*
G01X1607015D01*
G02Y1591596I0J1502D01*
G37*
G36*
G01X1582895D02*
X1586295D01*
G02Y1588592I0J-1502D01*
G01X1582895D01*
G02Y1591596I0J1502D01*
G37*
G36*
G01X225077Y1579684D02*
X228477D01*
G02Y1576680I0J-1502D01*
G01X225077D01*
G02Y1579684I0J1502D01*
G37*
G36*
G01Y1591596D02*
X228477D01*
G02Y1588592I0J-1502D01*
G01X225077D01*
G02Y1591596I0J1502D01*
G37*
G36*
G01X218317Y1615794D02*
X221717D01*
G02Y1612790I0J-1502D01*
G01X218317D01*
G02Y1615794I0J1502D01*
G37*
G36*
G01X290677Y1603882D02*
X294077D01*
G02Y1600878I0J-1502D01*
G01X290677D01*
G02Y1603882I0J1502D01*
G37*
G36*
G01Y1615794D02*
X294077D01*
G02Y1612790I0J-1502D01*
G01X290677D01*
G02Y1615794I0J1502D01*
G37*
G36*
G01X237137Y1579684D02*
X240537D01*
G02Y1576680I0J-1502D01*
G01X237137D01*
G02Y1579684I0J1502D01*
G37*
G36*
G01X213017D02*
X216417D01*
G02Y1576680I0J-1502D01*
G01X213017D01*
G02Y1579684I0J1502D01*
G37*
G36*
G01X230377Y1603882D02*
X233777D01*
G02Y1600878I0J-1502D01*
G01X230377D01*
G02Y1603882I0J1502D01*
G37*
G36*
G01X1619075Y1591596D02*
X1622475D01*
G02Y1588592I0J-1502D01*
G01X1619075D01*
G02Y1591596I0J1502D01*
G37*
G36*
G01X242437Y1615794D02*
X245837D01*
G02Y1612790I0J-1502D01*
G01X242437D01*
G02Y1615794I0J1502D01*
G37*
G36*
G01X369797Y1579684D02*
X373197D01*
G02Y1576680I0J-1502D01*
G01X369797D01*
G02Y1579684I0J1502D01*
G37*
G36*
G01X473051Y1591596D02*
X476451D01*
G02Y1588592I0J-1502D01*
G01X473051D01*
G02Y1591596I0J1502D01*
G37*
G36*
G01Y1579684D02*
X476451D01*
G02Y1576680I0J-1502D01*
G01X473051D01*
G02Y1579684I0J1502D01*
G37*
G36*
G01X1588195Y1603882D02*
X1591595D01*
G02Y1600878I0J-1502D01*
G01X1588195D01*
G02Y1603882I0J1502D01*
G37*
G36*
G01Y1615794D02*
X1591595D01*
G02Y1612790I0J-1502D01*
G01X1588195D01*
G02Y1615794I0J1502D01*
G37*
G36*
G01X61470Y86124D02*
X64870D01*
G02Y83120I0J-1502D01*
G01X61470D01*
G02Y86124I0J1502D01*
G37*
G36*
G01X297437Y1579684D02*
X300837D01*
G02Y1576680I0J-1502D01*
G01X297437D01*
G02Y1579684I0J1502D01*
G37*
G36*
G01X350977Y1615794D02*
X354377D01*
G02Y1612790I0J-1502D01*
G01X350977D01*
G02Y1615794I0J1502D01*
G37*
G36*
G01X375097Y1603882D02*
X378497D01*
G02Y1600878I0J-1502D01*
G01X375097D01*
G02Y1603882I0J1502D01*
G37*
G36*
G01Y1615794D02*
X378497D01*
G02Y1612790I0J-1502D01*
G01X375097D01*
G02Y1615794I0J1502D01*
G37*
G36*
G01X363037Y1603882D02*
X366437D01*
G02Y1600878I0J-1502D01*
G01X363037D01*
G02Y1603882I0J1502D01*
G37*
G36*
G01X1330101Y541552D02*
X1333143D01*
G02Y538546I0J-1503D01*
G01X1330101D01*
G02Y541552I0J1503D01*
G37*
G36*
G01X64571Y427304D02*
X61171D01*
G02Y430308I0J1502D01*
G01X64571D01*
G02Y427304I0J-1502D01*
G37*
G36*
G01X423180Y1601300D02*
X419780D01*
G02Y1604304I0J1502D01*
G01X423180D01*
G02Y1601300I0J-1502D01*
G37*
G36*
G01X49360Y427304D02*
X45960D01*
G02Y430308I0J1502D01*
G01X49360D01*
G02Y427304I0J-1502D01*
G37*
G36*
G01X930731Y531982D02*
X933773D01*
G02Y528976I0J-1503D01*
G01X930731D01*
G02Y531982I0J1503D01*
G37*
G36*
G01X285377Y1591596D02*
X288777D01*
G02Y1588592I0J-1502D01*
G01X285377D01*
G02Y1591596I0J1502D01*
G37*
G36*
G01X229131Y49144D02*
X225731D01*
G02Y52148I0J1502D01*
G01X229131D01*
G02Y49144I0J-1502D01*
G37*
G36*
G01X284230D02*
X280830D01*
G02Y52148I0J1502D01*
G01X284230D01*
G02Y49144I0J-1502D01*
G37*
G36*
G01X1755272Y27934D02*
X1758672D01*
G02Y24928I0J-1503D01*
G01X1755272D01*
G02Y27934I0J1503D01*
G37*
G36*
G01X1530660Y101664D02*
X1534060D01*
G02Y98660I0J-1502D01*
G01X1530660D01*
G02Y101664I0J1502D01*
G37*
G36*
G01X1549308Y27934D02*
X1552708D01*
G02Y24928I0J-1503D01*
G01X1549308D01*
G02Y27934I0J1503D01*
G37*
G36*
G01X1556413Y20998D02*
X1559813D01*
G02Y17992I0J-1503D01*
G01X1556413D01*
G02Y20998I0J1503D01*
G37*
G36*
G01X1563481Y27934D02*
X1566881D01*
G02Y24928I0J-1503D01*
G01X1563481D01*
G02Y27934I0J1503D01*
G37*
G36*
G01X1570586Y20998D02*
X1573986D01*
G02Y17992I0J-1503D01*
G01X1570586D01*
G02Y20998I0J1503D01*
G37*
G36*
G01X1577654Y27934D02*
X1581054D01*
G02Y24928I0J-1503D01*
G01X1577654D01*
G02Y27934I0J1503D01*
G37*
G36*
G01X1584759Y20998D02*
X1588159D01*
G02Y17992I0J-1503D01*
G01X1584759D01*
G02Y20998I0J1503D01*
G37*
G36*
G01X1591828Y27934D02*
X1595228D01*
G02Y24928I0J-1503D01*
G01X1591828D01*
G02Y27934I0J1503D01*
G37*
G36*
G01X1598933Y20998D02*
X1602333D01*
G02Y17992I0J-1503D01*
G01X1598933D01*
G02Y20998I0J1503D01*
G37*
G36*
G01X1627694Y27934D02*
X1631094D01*
G02Y24928I0J-1503D01*
G01X1627694D01*
G02Y27934I0J1503D01*
G37*
G36*
G01X1634799Y20998D02*
X1638199D01*
G02Y17992I0J-1503D01*
G01X1634799D01*
G02Y20998I0J1503D01*
G37*
G36*
G01X218667Y21040D02*
X222067D01*
G02Y18036I0J-1502D01*
G01X218667D01*
G02Y21040I0J1502D01*
G37*
G36*
G01X211562Y27976D02*
X214962D01*
G02Y24972I0J-1502D01*
G01X211562D01*
G02Y27976I0J1502D01*
G37*
G36*
G01X204494Y21040D02*
X207894D01*
G02Y18036I0J-1502D01*
G01X204494D01*
G02Y21040I0J1502D01*
G37*
G36*
G01X197389Y27976D02*
X200789D01*
G02Y24972I0J-1502D01*
G01X197389D01*
G02Y27976I0J1502D01*
G37*
G36*
G01X167428D02*
X170828D01*
G02Y24972I0J-1502D01*
G01X167428D01*
G02Y27976I0J1502D01*
G37*
G36*
G01X174533Y21040D02*
X177933D01*
G02Y18036I0J-1502D01*
G01X174533D01*
G02Y21040I0J1502D01*
G37*
G36*
G01X153255Y27976D02*
X156655D01*
G02Y24972I0J-1502D01*
G01X153255D01*
G02Y27976I0J1502D01*
G37*
G36*
G01X160360Y21040D02*
X163760D01*
G02Y18036I0J-1502D01*
G01X160360D01*
G02Y21040I0J1502D01*
G37*
G36*
G01X124494D02*
X127894D01*
G02Y18036I0J-1502D01*
G01X124494D01*
G02Y21040I0J1502D01*
G37*
G36*
G01X117389Y27976D02*
X120789D01*
G02Y24972I0J-1502D01*
G01X117389D01*
G02Y27976I0J1502D01*
G37*
G36*
G01X103215D02*
X106615D01*
G02Y24972I0J-1502D01*
G01X103215D01*
G02Y27976I0J1502D01*
G37*
G36*
G01X110320Y21040D02*
X113720D01*
G02Y18036I0J-1502D01*
G01X110320D01*
G02Y21040I0J1502D01*
G37*
G36*
G01X89042Y27976D02*
X92442D01*
G02Y24972I0J-1502D01*
G01X89042D01*
G02Y27976I0J1502D01*
G37*
G36*
G01X96147Y21040D02*
X99547D01*
G02Y18036I0J-1502D01*
G01X96147D01*
G02Y21040I0J1502D01*
G37*
G36*
G01X74869Y27976D02*
X78269D01*
G02Y24972I0J-1502D01*
G01X74869D01*
G02Y27976I0J1502D01*
G37*
G36*
G01X81974Y21040D02*
X85374D01*
G02Y18036I0J-1502D01*
G01X81974D01*
G02Y21040I0J1502D01*
G37*
G36*
G01X1641867Y27934D02*
X1645267D01*
G02Y24928I0J-1503D01*
G01X1641867D01*
G02Y27934I0J1503D01*
G37*
G36*
G01X1648972Y20998D02*
X1652372D01*
G02Y17992I0J-1503D01*
G01X1648972D01*
G02Y20998I0J1503D01*
G37*
G36*
G01X1671828Y27934D02*
X1675228D01*
G02Y24928I0J-1503D01*
G01X1671828D01*
G02Y27934I0J1503D01*
G37*
G36*
G01X1678933Y20998D02*
X1682333D01*
G02Y17992I0J-1503D01*
G01X1678933D01*
G02Y20998I0J1503D01*
G37*
G36*
G01X1686001Y27934D02*
X1689401D01*
G02Y24928I0J-1503D01*
G01X1686001D01*
G02Y27934I0J1503D01*
G37*
G36*
G01X1693106Y20998D02*
X1696506D01*
G02Y17992I0J-1503D01*
G01X1693106D01*
G02Y20998I0J1503D01*
G37*
G36*
G01X1700217Y27962D02*
X1703617D01*
G02Y24956I0J-1503D01*
G01X1700217D01*
G02Y27962I0J1503D01*
G37*
G36*
G01X1700170Y52152D02*
X1703570D01*
G02Y49146I0J-1503D01*
G01X1700170D01*
G02Y52152I0J1503D01*
G37*
G36*
G01X670612Y48766D02*
X674012D01*
G02Y45762I0J-1502D01*
G01X670612D01*
G02Y48766I0J1502D01*
G37*
G36*
G01X284233Y24972D02*
X280833D01*
G02Y27976I0J1502D01*
G01X284233D01*
G02Y24972I0J-1502D01*
G37*
G36*
G01X1382972Y1603882D02*
X1386372D01*
G02Y1600878I0J-1502D01*
G01X1382972D01*
G02Y1603882I0J1502D01*
G37*
G36*
G01Y1615794D02*
X1386372D01*
G02Y1612790I0J-1502D01*
G01X1382972D01*
G02Y1615794I0J1502D01*
G37*
G36*
G01X229135Y24972D02*
X225735D01*
G02Y27976I0J1502D01*
G01X229135D01*
G02Y24972I0J-1502D01*
G37*
G36*
G01X350977Y1603882D02*
X354377D01*
G02Y1600878I0J-1502D01*
G01X350977D01*
G02Y1603882I0J1502D01*
G37*
G36*
G01X405990Y1617450D02*
X402590D01*
G02Y1620454I0J1502D01*
G01X405990D01*
G02Y1617450I0J-1502D01*
G37*
G36*
G01X441740Y1650764D02*
X438340D01*
G02Y1653768I0J1502D01*
G01X441740D01*
G02Y1650764I0J-1502D01*
G37*
G36*
G01X49212Y450100D02*
X45812D01*
G02Y453104I0J1502D01*
G01X49212D01*
G02Y450100I0J-1502D01*
G37*
G36*
G01X862930Y71574D02*
X866330D01*
G02Y68570I0J-1502D01*
G01X862930D01*
G02Y71574I0J1502D01*
G37*
G36*
G01X1169820Y637554D02*
X1173220D01*
G02Y634550I0J-1502D01*
G01X1169820D01*
G02Y637554I0J1502D01*
G37*
G36*
G01X519764Y41830D02*
X523164D01*
G02Y38826I0J-1502D01*
G01X519764D01*
G02Y41830I0J1502D01*
G37*
G36*
G01X732793Y72938D02*
X736193D01*
G02Y69934I0J-1502D01*
G01X732793D01*
G02Y72938I0J1502D01*
G37*
G36*
G01X1161860Y643614D02*
X1165260D01*
G02Y640610I0J-1502D01*
G01X1161860D01*
G02Y643614I0J1502D01*
G37*
G36*
G01X663543Y44830D02*
X666943D01*
G02Y41826I0J-1502D01*
G01X663543D01*
G02Y44830I0J1502D01*
G37*
G36*
G01X656439Y48766D02*
X659839D01*
G02Y45762I0J-1502D01*
G01X656439D01*
G02Y48766I0J1502D01*
G37*
G36*
G01X562771Y1603882D02*
X566171D01*
G02Y1600878I0J-1502D01*
G01X562771D01*
G02Y1603882I0J1502D01*
G37*
G36*
G01X538651D02*
X542051D01*
G02Y1600878I0J-1502D01*
G01X538651D01*
G02Y1603882I0J1502D01*
G37*
G36*
G01X555175Y72938D02*
X558575D01*
G02Y69934I0J-1502D01*
G01X555175D01*
G02Y72938I0J1502D01*
G37*
G36*
G01X541002D02*
X544402D01*
G02Y69934I0J-1502D01*
G01X541002D01*
G02Y72938I0J1502D01*
G37*
G36*
G01X519742D02*
X523142D01*
G02Y69934I0J-1502D01*
G01X519742D01*
G02Y72938I0J1502D01*
G37*
G36*
G01X533915Y61324D02*
X537315D01*
G02Y58320I0J-1502D01*
G01X533915D01*
G02Y61324I0J1502D01*
G37*
G36*
G01X538651Y1615794D02*
X542051D01*
G02Y1612790I0J-1502D01*
G01X538651D01*
G02Y1615794I0J1502D01*
G37*
G36*
G01X526591Y1603882D02*
X529991D01*
G02Y1600878I0J-1502D01*
G01X526591D01*
G02Y1603882I0J1502D01*
G37*
G36*
G01X514531D02*
X517931D01*
G02Y1600878I0J-1502D01*
G01X514531D01*
G02Y1603882I0J1502D01*
G37*
G36*
G01X526591Y1615794D02*
X529991D01*
G02Y1612790I0J-1502D01*
G01X526591D01*
G02Y1615794I0J1502D01*
G37*
G36*
G01X514531D02*
X517931D01*
G02Y1612790I0J-1502D01*
G01X514531D01*
G02Y1615794I0J1502D01*
G37*
G36*
G01X490411Y1603882D02*
X493811D01*
G02Y1600878I0J-1502D01*
G01X490411D01*
G02Y1603882I0J1502D01*
G37*
G36*
G01X478351Y1615794D02*
X481751D01*
G02Y1612790I0J-1502D01*
G01X478351D01*
G02Y1615794I0J1502D01*
G37*
G36*
G01X502471D02*
X505871D01*
G02Y1612790I0J-1502D01*
G01X502471D01*
G02Y1615794I0J1502D01*
G37*
G36*
G01X478351Y1603882D02*
X481751D01*
G02Y1600878I0J-1502D01*
G01X478351D01*
G02Y1603882I0J1502D01*
G37*
G36*
G01X598951D02*
X602351D01*
G02Y1600878I0J-1502D01*
G01X598951D01*
G02Y1603882I0J1502D01*
G37*
G36*
G01Y1615794D02*
X602351D01*
G02Y1612790I0J-1502D01*
G01X598951D01*
G02Y1615794I0J1502D01*
G37*
G36*
G01X586891Y1603882D02*
X590291D01*
G02Y1600878I0J-1502D01*
G01X586891D01*
G02Y1603882I0J1502D01*
G37*
G36*
G01X647191D02*
X650591D01*
G02Y1600878I0J-1502D01*
G01X647191D01*
G02Y1603882I0J1502D01*
G37*
G36*
G01X635131Y1615794D02*
X638531D01*
G02Y1612790I0J-1502D01*
G01X635131D01*
G02Y1615794I0J1502D01*
G37*
G36*
G01X647191D02*
X650591D01*
G02Y1612790I0J-1502D01*
G01X647191D01*
G02Y1615794I0J1502D01*
G37*
G36*
G01X623071D02*
X626471D01*
G02Y1612790I0J-1502D01*
G01X623071D01*
G02Y1615794I0J1502D01*
G37*
G36*
G01X550711Y1603882D02*
X554111D01*
G02Y1600878I0J-1502D01*
G01X550711D01*
G02Y1603882I0J1502D01*
G37*
G36*
G01X502471D02*
X505871D01*
G02Y1600878I0J-1502D01*
G01X502471D01*
G02Y1603882I0J1502D01*
G37*
G36*
G01X490411Y1615794D02*
X493811D01*
G02Y1612790I0J-1502D01*
G01X490411D01*
G02Y1615794I0J1502D01*
G37*
G36*
G01X550711D02*
X554111D01*
G02Y1612790I0J-1502D01*
G01X550711D01*
G02Y1615794I0J1502D01*
G37*
G36*
G01X635131Y1603882D02*
X638531D01*
G02Y1600878I0J-1502D01*
G01X635131D01*
G02Y1603882I0J1502D01*
G37*
G36*
G01X913394Y523164D02*
X916794D01*
G02Y520160I0J-1502D01*
G01X913394D01*
G02Y523164I0J1502D01*
G37*
G36*
G01X574831Y1603882D02*
X578231D01*
G02Y1600878I0J-1502D01*
G01X574831D01*
G02Y1603882I0J1502D01*
G37*
G36*
G01X659251D02*
X662651D01*
G02Y1600878I0J-1502D01*
G01X659251D01*
G02Y1603882I0J1502D01*
G37*
G36*
G01X1153370Y639694D02*
X1156770D01*
G02Y636690I0J-1502D01*
G01X1153370D01*
G02Y639694I0J1502D01*
G37*
G36*
G01X611011Y1615794D02*
X614411D01*
G02Y1612790I0J-1502D01*
G01X611011D01*
G02Y1615794I0J1502D01*
G37*
G36*
G01Y1603882D02*
X614411D01*
G02Y1600878I0J-1502D01*
G01X611011D01*
G02Y1603882I0J1502D01*
G37*
G36*
G01X586891Y1615794D02*
X590291D01*
G02Y1612790I0J-1502D01*
G01X586891D01*
G02Y1615794I0J1502D01*
G37*
G36*
G01X659251D02*
X662651D01*
G02Y1612790I0J-1502D01*
G01X659251D01*
G02Y1615794I0J1502D01*
G37*
G36*
G01X574831D02*
X578231D01*
G02Y1612790I0J-1502D01*
G01X574831D01*
G02Y1615794I0J1502D01*
G37*
G36*
G01X1183360Y643564D02*
X1186760D01*
G02Y640560I0J-1502D01*
G01X1183360D01*
G02Y643564I0J1502D01*
G37*
G36*
G01X562771Y1615794D02*
X566171D01*
G02Y1612790I0J-1502D01*
G01X562771D01*
G02Y1615794I0J1502D01*
G37*
G36*
G01X901230Y533114D02*
X904630D01*
G02Y530110I0J-1502D01*
G01X901230D01*
G02Y533114I0J1502D01*
G37*
G36*
G01X954390Y529098D02*
X957790D01*
G02Y526094I0J-1502D01*
G01X954390D01*
G02Y529098I0J1502D01*
G37*
G36*
G01X963930Y534864D02*
X967330D01*
G02Y531860I0J-1502D01*
G01X963930D01*
G02Y534864I0J1502D01*
G37*
G36*
G01X548070Y80874D02*
X551470D01*
G02Y77870I0J-1502D01*
G01X548070D01*
G02Y80874I0J1502D01*
G37*
G36*
G01X623071Y1603882D02*
X626471D01*
G02Y1600878I0J-1502D01*
G01X623071D01*
G02Y1603882I0J1502D01*
G37*
G36*
G01X888130Y534114D02*
X891530D01*
G02Y531110I0J-1502D01*
G01X888130D01*
G02Y534114I0J1502D01*
G37*
G36*
G01X297437Y1591596D02*
X300837D01*
G02Y1588592I0J-1502D01*
G01X297437D01*
G02Y1591596I0J1502D01*
G37*
G36*
G01X237137D02*
X240537D01*
G02Y1588592I0J-1502D01*
G01X237137D01*
G02Y1591596I0J1502D01*
G37*
G36*
G01X50772Y120610D02*
X55372Y124913D01*
G02X66448Y113076I5538J-5919D01*
G01X61848Y108773D01*
G02X50772Y120610I-5538J5918D01*
G37*
G36*
G01X1077740Y219698D02*
X1071093Y226345D01*
G02X1070800Y227052I706J707D01*
G01Y300248D01*
X1069686Y301362D01*
X1015593D01*
G02X1015520Y301360I-78J1500D01*
G02X1015447Y301362I5J1502D01*
G01X933091D01*
G02X928739Y300900I-4355J20291D01*
G02X924387Y301362I3J20753D01*
G01X839354D01*
X831168Y293176D01*
X831190Y293070D01*
G02X831222Y292762I-1470J-308D01*
G02X830355Y291401I-1502J0D01*
G01X830240Y291347D01*
Y281713D01*
G02X831122Y280345I-620J-1368D01*
G02X830682Y279283I-1502J0D01*
G03X830703Y278698I283J-283D01*
G02X831222Y277562I-984J-1136D01*
G02X830884Y276613I-1501J0D01*
G03X830905Y276084I310J-253D01*
G02X831322Y275045I-1086J-1039D01*
G02X830367Y273646I-1502J0D01*
G01X830240Y273596D01*
Y273004D01*
X830365Y272954D01*
G02Y270170I-565J-1392D01*
G01X830240Y270120D01*
Y265979D01*
X830351Y265924D01*
G02Y263236I-671J-1344D01*
G01X830240Y263181D01*
Y241842D01*
G02X829947Y241135I-999J0D01*
G01X824867Y236055D01*
G02X824160Y235762I-707J706D01*
G01X649014D01*
X637500Y224248D01*
Y127862D01*
G02X637207Y127155I-999J0D01*
G01X632907Y122855D01*
G02X632200Y122562I-707J706D01*
G01X552738D01*
X552708Y122398D01*
G02X549754I-1477J273D01*
G01X549724Y122562D01*
X384310D01*
G02X383603Y122855I0J999D01*
G01X383579Y122879D01*
G02X383160Y122820I-417J1443D01*
G02X381658Y124322I0J1502D01*
G02X381691Y124637I1502J2D01*
G01X381714Y124744D01*
X359876Y146582D01*
X128360D01*
G02X127653Y146875I0J999D01*
G01X98533Y175995D01*
G02X98240Y176702I706J707D01*
G01Y499112D01*
G02X98533Y499819I999J0D01*
G01X117963Y519249D01*
G02X118670Y519542I707J-706D01*
G01X152944D01*
G02X153651Y519249I0J-999D01*
G01X159637Y513263D01*
X161455D01*
G02X164045I1295J-761D01*
G01X244188D01*
X244209Y513439D01*
G02X247191I1491J-176D01*
G01X247212Y513263D01*
X429984D01*
G02X432456I1236J-640D01*
G01X593504D01*
X593547Y513286D01*
G02X594240Y513455I692J-1333D01*
G02X594933Y513286I1J-1502D01*
G01X594976Y513263D01*
X610543D01*
G02X613197I1327J-702D01*
G01X782763D01*
X782801Y513280D01*
G02X783400Y513404I598J-1378D01*
G02X783999Y513280I1J-1502D01*
G01X784037Y513263D01*
X792219D01*
X792268Y513392D01*
G02X795078I1405J-529D01*
G01X795127Y513263D01*
X796124D01*
G02X798716I1296J-761D01*
G01X800092D01*
X800137Y513402D01*
G02X802997I1430J-460D01*
G01X803042Y513263D01*
X831129D01*
X831176Y513395D01*
G02X832590Y514390I1414J-507D01*
G02X834058Y513207I0J-1502D01*
G02X834436Y512970I-328J-944D01*
G01X878754Y468652D01*
X945333D01*
X1004990Y528309D01*
G02X1005697Y528602I707J-706D01*
G01X1171413D01*
G02X1174027I1307J-740D01*
G01X1314600D01*
G02X1315307Y528309I0J-999D01*
G01X1435374Y408242D01*
X1448090D01*
G02X1450502I1206J-895D01*
G01X1489367D01*
G02X1491401I1017J-949D01*
G01X1503340D01*
G02X1504047Y407949I0J-999D01*
G01X1539617Y372379D01*
G02X1539910Y371672I-706J-707D01*
G01Y308096D01*
X1562194Y285812D01*
X1658640D01*
Y294362D01*
G02X1702014I21687J0D01*
G01Y285812D01*
X1775460D01*
G02X1776167Y285519I0J-999D01*
G01X1781717Y279969D01*
G02X1782010Y279262I-706J-707D01*
G01Y161902D01*
G02X1781717Y161195I-999J0D01*
G01X1765087Y144565D01*
G02X1764380Y144272I-707J706D01*
G01X1692912D01*
G02X1686380I-3266J1397D01*
G01X1682912D01*
G02X1676380I-3266J1397D01*
G01X1520834D01*
X1469387Y92825D01*
G02X1468680Y92532I-707J706D01*
G01X1393821D01*
X1393784Y92517D01*
G02X1393250Y92410I-535J1285D01*
G02X1392716Y92517I1J1392D01*
G01X1392679Y92532D01*
X1317921D01*
X1317870Y92407D01*
G02X1315086I-1392J562D01*
G01X1315035Y92532D01*
X1314729D01*
X1314689Y92514D01*
G02X1314059Y92375I-631J1363D01*
G02X1313429Y92514I1J1502D01*
G01X1313389Y92532D01*
X1299933D01*
X1299877Y92424D01*
G02X1297403I-1237J638D01*
G01X1297347Y92532D01*
X1294121D01*
G02X1291639I-1241J630D01*
G01X1266118D01*
X1266082Y92378D01*
G02X1263158I-1462J347D01*
G01X1263122Y92532D01*
X1131400D01*
G02X1130693Y92825I0J999D01*
G01X1078033Y145485D01*
G02X1077740Y146192I706J707D01*
G01Y196975D01*
G03X1076968Y197122I-400J0D01*
G02X1057658Y183972I-19310J7603D01*
G02Y225476I0J20752D01*
G02X1076968Y212326I0J-20753D01*
G03X1077740Y212473I372J147D01*
G01Y219698D01*
G37*
G36*
G01X669778Y758427D02*
G02X669015Y758635I0J1502D01*
G01X601187D01*
X386910Y544358D01*
G02X386203Y544065I-707J706D01*
G01X196537D01*
G02X195830Y544358I0J999D01*
G01X192750Y547438D01*
G02X192457Y548145I706J707D01*
G01Y621189D01*
X188324Y625322D01*
X128223D01*
G03X128037Y624568I0J-400D01*
G02X139620Y605378I-10105J-19190D01*
G02X96246I-21687J0D01*
G02X107829Y624568I21688J0D01*
G03X107643Y625322I-186J354D01*
G01X70000D01*
G02X69293Y625615I0J999D01*
G01X62135Y632773D01*
G03X61452Y632479I-283J-283D01*
G02X61460Y631890I-20744J-576D01*
G02X40708Y652642I-20752J0D01*
G01X40711D01*
G02X49360Y650753I-2J-20752D01*
G03X49927Y651116I167J363D01*
G01Y695234D01*
X24266Y745309D01*
X24255Y745324D01*
G02X24069Y745726I792J611D01*
G02X24023Y746026I955J300D01*
G02X24043Y746225I1000J0D01*
G01X24047Y746245D01*
Y764247D01*
G02Y766953I654J1353D01*
G01Y1289920D01*
G02X24045Y1289977I998J64D01*
G01Y1318873D01*
G02X24338Y1319580I999J0D01*
G01X33930Y1329172D01*
G02X34637Y1329465I707J-706D01*
G01X87493D01*
X97697Y1339669D01*
Y1369764D01*
G02X97990Y1370471I999J0D01*
G01X144891Y1417372D01*
G02X145598Y1417665I707J-706D01*
G01X222743D01*
G02X225411I1334J-690D01*
G01X338257D01*
G02X338964Y1417372I0J-999D01*
G01X344544Y1411792D01*
G02X344837Y1411085I-706J-707D01*
G01Y1400759D01*
X347741Y1397855D01*
X391435D01*
X391459Y1398028D01*
G02X394435I1488J-200D01*
G01X394459Y1397855D01*
X399939D01*
X409734Y1407650D01*
X409703Y1407762D01*
G02X409648Y1408163I1447J403D01*
G02X411150Y1409665I1502J0D01*
G02X411888Y1409471I0J-1501D01*
G02X411973Y1409475I89J-995D01*
G01X454108D01*
X454155Y1409610D01*
G02X456997I1421J-484D01*
G01X457044Y1409475D01*
X506873D01*
G03X507273Y1409878I0J400D01*
G01Y1409889D01*
G02X508775Y1411391I1502J0D01*
G01X508776D01*
G02X509128Y1411349I-1J-1502D01*
G01X509237Y1411323D01*
X522203Y1424289D01*
G02X522910Y1424582I707J-706D01*
G01X570111D01*
X570140Y1424748D01*
G02X573100I1480J-256D01*
G01X573129Y1424582D01*
X574902D01*
G02X577538I1318J-720D01*
G01X653193D01*
X653243Y1424710D01*
G02X655837I1297J-505D01*
G01X655887Y1424582D01*
X690341D01*
G02X691129Y1424805I788J-1279D01*
G02X691917Y1424582I0J-1502D01*
G01X693341D01*
G02X694129Y1424805I788J-1279D01*
G02X694917Y1424582I0J-1502D01*
G01X820928D01*
G02X841240Y1441082I20312J-4252D01*
G02X861992Y1420330I0J-20752D01*
G01Y1420329D01*
G02X856135Y1405880I-20752J0D01*
G01X855998Y1405738D01*
X858164Y1403572D01*
G02X858457Y1402865I-706J-707D01*
G01Y765455D01*
G02X858164Y764748I-999J0D01*
G01X855936Y762520D01*
G02X856189Y761686I-1249J-834D01*
G01Y761685D01*
G02X854687Y760183I-1502J0D01*
G01X854686D01*
G02X853852Y760436I0J1502D01*
G01X852344Y758928D01*
G02X851637Y758635I-707J706D01*
G01X838484D01*
X838436Y758503D01*
G02X835818I-1309J473D01*
G01X835770Y758635D01*
X764106D01*
X764066Y758488D01*
G02X761168I-1449J398D01*
G01X761128Y758635D01*
X670541D01*
G02X669778Y758427I-763J1294D01*
G37*
G36*
G01X1004455Y1403249D02*
G02X995488Y1420330I11785J17081D01*
G02X1016240Y1441082I20752J0D01*
G02X1035543Y1427949I0J-20752D01*
G01X1133482D01*
G02X1135376I947J-1119D01*
G01X1136082D01*
G02X1137976I947J-1119D01*
G01X1144558D01*
G02X1146526I984J-1088D01*
G01X1171625D01*
G02X1173519I947J-1119D01*
G01X1174225D01*
G02X1176119I947J-1119D01*
G01X1182701D01*
G02X1184669I984J-1088D01*
G01X1304043D01*
G02X1304750Y1427656I0J-999D01*
G01X1330651Y1401755D01*
X1367884D01*
X1389137Y1423008D01*
G02X1388778Y1423940I1033J933D01*
G01Y1423942D01*
G02X1390170Y1425334I1392J0D01*
G01X1390172D01*
G02X1391104Y1424975I-1J-1392D01*
G01X1392204Y1426075D01*
X1392176Y1426186D01*
G02X1392128Y1426562I1454J377D01*
G02X1393630Y1428064I1502J0D01*
G02X1394006Y1428016I-1J-1502D01*
G01X1394117Y1427988D01*
X1394371Y1428242D01*
G02X1395078Y1428535I707J-706D01*
G01X1430517D01*
G02X1432917I1200J-903D01*
G01X1510870D01*
G02X1513484I1307J-740D01*
G01X1631275D01*
G02X1632516Y1429220I1241J-782D01*
G02X1633486Y1428853I-1J-1467D01*
G03X1634016I265J300D01*
G02X1634986Y1429220I971J-1100D01*
G02X1635941Y1428867I0J-1468D01*
G03X1636461I260J304D01*
G02X1637416Y1429220I955J-1115D01*
G02X1638657Y1428535I0J-1467D01*
G01X1669418D01*
G02X1670659Y1429220I1241J-782D01*
G02X1671629Y1428853I-1J-1467D01*
G03X1672159I265J300D01*
G02X1673129Y1429220I971J-1100D01*
G02X1674084Y1428867I0J-1468D01*
G03X1674604I260J304D01*
G02X1675559Y1429220I955J-1115D01*
G02X1676800Y1428535I0J-1467D01*
G01X1698090D01*
X1698123Y1428694D01*
G02X1701063I1470J-310D01*
G01X1701096Y1428535D01*
X1735227D01*
G02X1735934Y1428242I0J-999D01*
G01X1754194Y1409982D01*
G02X1754487Y1409275I-706J-707D01*
G01Y1322499D01*
X1756251Y1320735D01*
X1785747D01*
X1785757Y1320736D01*
G02X1785856Y1320741I100J-995D01*
G02X1786563Y1320448I0J-999D01*
G01X1788954Y1318057D01*
G02X1789247Y1317350I-706J-707D01*
G01Y1295535D01*
G02X1788954Y1294828I-999J0D01*
G01X1785267Y1291141D01*
Y1268455D01*
G02X1784974Y1267748I-999J0D01*
G01X1783664Y1266438D01*
G02X1782957Y1266145I-707J706D01*
G01X1691712D01*
X1690478Y1264911D01*
G02X1690414Y1264852I-709J705D01*
G01Y1234093D01*
X1690505Y1234033D01*
G02X1690668Y1233901I-544J-839D01*
G01X1691904Y1232665D01*
X1701074D01*
G02X1703492I1209J-710D01*
G01X1709774D01*
G02X1712192I1209J-710D01*
G01X1714762D01*
G02X1716920I1079J-709D01*
G01X1730774D01*
G02X1733192I1209J-710D01*
G01X1739474D01*
G02X1741892I1209J-710D01*
G01X1742447D01*
G02X1743154Y1232372I0J-999D01*
G01X1746164Y1229362D01*
G02X1746457Y1228655I-706J-707D01*
G01Y1226324D01*
G02Y1224202I-915J-1061D01*
G01Y1219631D01*
G02Y1217509I-915J-1061D01*
G01Y1212938D01*
G02Y1210816I-915J-1061D01*
G01Y1206245D01*
G02Y1204123I-915J-1061D01*
G01Y1199552D01*
G02Y1197430I-915J-1061D01*
G01Y1189513D01*
G02Y1187391I-915J-1061D01*
G01Y1182820D01*
G02Y1180698I-915J-1061D01*
G01Y1176127D01*
G02Y1174005I-915J-1061D01*
G01Y1169434D01*
G02Y1167312I-915J-1061D01*
G01Y1162741D01*
G02Y1160619I-915J-1061D01*
G01Y1152702D01*
G02Y1150580I-915J-1061D01*
G01Y1146009D01*
G02Y1143887I-915J-1061D01*
G01Y1139316D01*
G02Y1137194I-915J-1061D01*
G01Y1132623D01*
G02Y1130501I-915J-1061D01*
G01Y1125930D01*
G02Y1123808I-915J-1061D01*
G01Y1115890D01*
G02Y1113768I-915J-1061D01*
G01Y1109198D01*
G02Y1107076I-915J-1061D01*
G01Y1102505D01*
G02Y1100383I-915J-1061D01*
G01Y1095812D01*
G02Y1093690I-915J-1061D01*
G01Y1089119D01*
G02Y1086997I-915J-1061D01*
G01Y1079079D01*
G02Y1076957I-915J-1061D01*
G01Y1072387D01*
G02Y1070265I-915J-1061D01*
G01Y1065694D01*
G02Y1063572I-915J-1061D01*
G01Y1059001D01*
G02Y1056879I-915J-1061D01*
G01Y1055504D01*
G02Y1053682I-916J-911D01*
G01Y1052308D01*
G02Y1050186I-915J-1061D01*
G01Y1045615D01*
G02Y1043493I-915J-1061D01*
G01Y1038922D01*
G02Y1036800I-915J-1061D01*
G01Y1032229D01*
G02Y1030107I-915J-1061D01*
G01Y1025536D01*
G02Y1023414I-915J-1061D01*
G01Y1018843D01*
G02Y1016721I-915J-1061D01*
G01Y992072D01*
G02Y989950I-915J-1061D01*
G01Y985379D01*
G02Y983257I-915J-1061D01*
G01Y978686D01*
G02Y976564I-915J-1061D01*
G01Y971993D01*
G02Y969871I-915J-1061D01*
G01Y968496D01*
G02Y966674I-916J-911D01*
G01Y965300D01*
G02Y963178I-915J-1061D01*
G01Y961803D01*
G02Y959981I-916J-911D01*
G01Y958457D01*
G02Y956635I-916J-911D01*
G01Y955261D01*
G02Y953139I-915J-1061D01*
G01Y948568D01*
G02Y946446I-915J-1061D01*
G01Y941875D01*
G02Y939753I-915J-1061D01*
G01Y931835D01*
G02Y929713I-915J-1061D01*
G01Y925142D01*
G02Y923020I-915J-1061D01*
G01Y918450D01*
G02Y916328I-915J-1061D01*
G01Y911757D01*
G02Y909635I-915J-1061D01*
G01Y905064D01*
G02Y902942I-915J-1061D01*
G01Y895024D01*
G02Y892902I-915J-1061D01*
G01Y888331D01*
G02Y886209I-915J-1061D01*
G01Y881638D01*
G02Y879516I-915J-1061D01*
G01Y874946D01*
G02Y872824I-915J-1061D01*
G01Y868253D01*
G02Y866131I-915J-1061D01*
G01Y858213D01*
G02Y856091I-915J-1061D01*
G01Y851520D01*
G02Y849398I-915J-1061D01*
G01Y844827D01*
G02Y842705I-915J-1061D01*
G01Y838135D01*
G02Y836013I-915J-1061D01*
G01Y831442D01*
G02Y829320I-915J-1061D01*
G01Y821402D01*
G02Y819280I-915J-1061D01*
G01Y814709D01*
G02Y812587I-915J-1061D01*
G01Y808016D01*
G02Y805894I-915J-1061D01*
G01Y801324D01*
G02Y799202I-915J-1061D01*
G01Y794631D01*
G02Y792509I-915J-1061D01*
G01Y784591D01*
G02Y782469I-915J-1061D01*
G01Y777898D01*
G02Y775776I-915J-1061D01*
G01Y771205D01*
G02Y769083I-915J-1061D01*
G01Y767859D01*
G02Y765737I-915J-1061D01*
G01Y671405D01*
G02X1746164Y670698I-999J0D01*
G01X1743624Y668158D01*
G02X1742917Y667865I-707J706D01*
G01X1686156D01*
G02X1679608I-3274J1245D01*
G01X1659822D01*
X1658702Y666745D01*
Y640880D01*
G02Y638142I-616J-1369D01*
G01Y620907D01*
X1658704Y620892D01*
G02X1658722Y620662I-1484J-232D01*
G02X1658704Y620432I-1502J2D01*
G01X1658702Y620417D01*
Y592480D01*
G02X1658409Y591773I-999J0D01*
G01X1650028Y583392D01*
G02X1649321Y583099I-707J706D01*
G01X1616953D01*
G02X1614647I-1153J964D01*
G01X1608429D01*
G02X1605971I-1229J862D01*
G01X1562407D01*
G02X1560581I-913J1194D01*
G01X1401283D01*
G02X1400576Y583392I0J999D01*
G01X1252513Y731455D01*
G02X1252220Y732162I706J707D01*
G01Y763305D01*
X1002267D01*
G02X1001560Y763598I0J999D01*
G01X998500Y766658D01*
G02X998207Y767365I706J707D01*
G01Y1395919D01*
G02X998500Y1396626I999J0D01*
G01X1004511Y1402637D01*
G03X1004455Y1403249I-283J283D01*
G37*
G36*
G01X1143020Y1540382D02*
G03X1143411Y1540758I-8J400D01*
G02X1145410Y1542642I1999J-119D01*
G02X1147412Y1540640I0J-2002D01*
G02X1145450Y1538638I-2002J0D01*
G03X1145059Y1538262I8J-400D01*
G02X1143060Y1536378I-1999J119D01*
G02X1141058Y1538380I0J2002D01*
G02X1143020Y1540382I2002J0D01*
G37*
G36*
G01X1162980Y1551449D02*
G03X1163635I328J229D01*
G02X1166917I1641J-1147D01*
G03X1167572I327J229D01*
G02X1169213Y1552304I1641J-1147D01*
G02Y1548298I0J-2003D01*
G02X1167572Y1549153I0J2002D01*
G03X1166917I-328J-229D01*
G02X1163635I-1641J1147D01*
G03X1162980I-327J-229D01*
G02X1159698I-1641J1147D01*
G03X1159043I-328J-229D01*
G02X1155761I-1641J1147D01*
G03X1155106I-328J-229D01*
G02X1151824I-1641J1147D01*
G03X1151169I-328J-229D01*
G02X1149528Y1548298I-1641J1147D01*
G02Y1552304I0J2003D01*
G02X1151169Y1551449I0J-2002D01*
G03X1151824I327J229D01*
G02X1155106I1641J-1147D01*
G03X1155761I328J229D01*
G02X1159043I1641J-1147D01*
G03X1159698I327J229D01*
G02X1162980I1641J-1147D01*
G37*
G36*
G01X1139652Y1550301D02*
Y1550302D01*
G02X1140157Y1551631I2002J0D01*
G02X1139688Y1552918I1533J1288D01*
G01Y1552920D01*
G02X1143692I2002J0D01*
G01Y1552919D01*
G02X1143187Y1551590I-2002J0D01*
G02X1143656Y1550303I-1533J-1288D01*
G01Y1550301D01*
G02X1139652I-2002J0D01*
G37*
G36*
G01X1101405Y1550386D02*
G03X1101083Y1550900I-382J119D01*
G02X1098098Y1554364I517J3464D01*
G02X1105102I3502J0D01*
G02X1104945Y1553324I-3502J-3D01*
G03X1105267Y1552810I382J-119D01*
G02X1108252Y1549346I-517J-3464D01*
G02X1101248I-3502J0D01*
G02X1101405Y1550386I3502J3D01*
G37*
G36*
G01X1143823Y1573272D02*
G03X1143551I-136J-147D01*
G02X1142188Y1572736I-1363J1466D01*
G01X1142187D01*
G02Y1576740I0J2002D01*
G01X1142188D01*
G02X1143551Y1576204I0J-2002D01*
G03X1143823I136J147D01*
G02X1145186Y1576740I1363J-1466D01*
G01X1145187D01*
G02Y1572736I0J-2002D01*
G01X1145186D01*
G02X1143823Y1573272I0J2002D01*
G37*
G36*
G01X1153823D02*
G03X1153551I-136J-147D01*
G02X1152188Y1572736I-1363J1466D01*
G01X1152187D01*
G02Y1576740I0J2002D01*
G01X1152188D01*
G02X1153551Y1576204I0J-2002D01*
G03X1153823I136J147D01*
G02X1155186Y1576740I1363J-1466D01*
G01X1155187D01*
G02Y1572736I0J-2002D01*
G01X1155186D01*
G02X1153823Y1573272I0J2002D01*
G37*
G36*
G01X1163231D02*
G03X1162959I-136J-147D01*
G02X1161596Y1572736I-1363J1466D01*
G01X1161595D01*
G02Y1576740I0J2002D01*
G01X1161596D01*
G02X1162959Y1576204I0J-2002D01*
G03X1163231I136J147D01*
G02X1164594Y1576740I1363J-1466D01*
G01X1164595D01*
G02Y1572736I0J-2002D01*
G01X1164594D01*
G02X1163231Y1573272I0J2002D01*
G37*
G36*
G01X1173231D02*
G03X1172959I-136J-147D01*
G02X1171596Y1572736I-1363J1466D01*
G01X1171595D01*
G02Y1576740I0J2002D01*
G01X1171596D01*
G02X1172959Y1576204I0J-2002D01*
G03X1173231I136J147D01*
G02X1174594Y1576740I1363J-1466D01*
G01X1174595D01*
G02Y1572736I0J-2002D01*
G01X1174594D01*
G02X1173231Y1573272I0J2002D01*
G37*
G36*
G01X1133823Y1581272D02*
G03X1133551I-136J-147D01*
G02X1132188Y1580736I-1363J1466D01*
G01X1132187D01*
G02Y1584740I0J2002D01*
G01X1132188D01*
G02X1133551Y1584204I0J-2002D01*
G03X1133823I136J147D01*
G02X1135186Y1584740I1363J-1466D01*
G01X1135187D01*
G02Y1580736I0J-2002D01*
G01X1135186D01*
G02X1133823Y1581272I0J2002D01*
G37*
G36*
G01X1143823D02*
G03X1143551I-136J-147D01*
G02X1142188Y1580736I-1363J1466D01*
G01X1142187D01*
G02Y1584740I0J2002D01*
G01X1142188D01*
G02X1143551Y1584204I0J-2002D01*
G03X1143823I136J147D01*
G02X1145186Y1584740I1363J-1466D01*
G01X1145187D01*
G02Y1580736I0J-2002D01*
G01X1145186D01*
G02X1143823Y1581272I0J2002D01*
G37*
G36*
G01X1153823D02*
G03X1153551I-136J-147D01*
G02X1152188Y1580736I-1363J1466D01*
G01X1152187D01*
G02Y1584740I0J2002D01*
G01X1152188D01*
G02X1153551Y1584204I0J-2002D01*
G03X1153823I136J147D01*
G02X1155186Y1584740I1363J-1466D01*
G01X1155187D01*
G02Y1580736I0J-2002D01*
G01X1155186D01*
G02X1153823Y1581272I0J2002D01*
G37*
G36*
G01X1163231D02*
G03X1162959I-136J-147D01*
G02X1161596Y1580736I-1363J1466D01*
G01X1161595D01*
G02Y1584740I0J2002D01*
G01X1161596D01*
G02X1162959Y1584204I0J-2002D01*
G03X1163231I136J147D01*
G02X1164594Y1584740I1363J-1466D01*
G01X1164595D01*
G02Y1580736I0J-2002D01*
G01X1164594D01*
G02X1163231Y1581272I0J2002D01*
G37*
G36*
G01X1173231D02*
G03X1172959I-136J-147D01*
G02X1171596Y1580736I-1363J1466D01*
G01X1171595D01*
G02Y1584740I0J2002D01*
G01X1171596D01*
G02X1172959Y1584204I0J-2002D01*
G03X1173231I136J147D01*
G02X1174594Y1584740I1363J-1466D01*
G01X1174595D01*
G02Y1580736I0J-2002D01*
G01X1174594D01*
G02X1173231Y1581272I0J2002D01*
G37*
G36*
G01X1133823Y1589272D02*
G03X1133551I-136J-147D01*
G02X1132188Y1588736I-1363J1466D01*
G01X1132187D01*
G02Y1592740I0J2002D01*
G01X1132188D01*
G02X1133551Y1592204I0J-2002D01*
G03X1133823I136J147D01*
G02X1135186Y1592740I1363J-1466D01*
G01X1135187D01*
G02Y1588736I0J-2002D01*
G01X1135186D01*
G02X1133823Y1589272I0J2002D01*
G37*
G36*
G01X1143823D02*
G03X1143551I-136J-147D01*
G02X1142188Y1588736I-1363J1466D01*
G01X1142187D01*
G02Y1592740I0J2002D01*
G01X1142188D01*
G02X1143551Y1592204I0J-2002D01*
G03X1143823I136J147D01*
G02X1145186Y1592740I1363J-1466D01*
G01X1145187D01*
G02Y1588736I0J-2002D01*
G01X1145186D01*
G02X1143823Y1589272I0J2002D01*
G37*
G36*
G01X1153823D02*
G03X1153551I-136J-147D01*
G02X1152188Y1588736I-1363J1466D01*
G01X1152187D01*
G02Y1592740I0J2002D01*
G01X1152188D01*
G02X1153551Y1592204I0J-2002D01*
G03X1153823I136J147D01*
G02X1155186Y1592740I1363J-1466D01*
G01X1155187D01*
G02Y1588736I0J-2002D01*
G01X1155186D01*
G02X1153823Y1589272I0J2002D01*
G37*
G36*
G01X1163231D02*
G03X1162959I-136J-147D01*
G02X1161596Y1588736I-1363J1466D01*
G01X1161595D01*
G02Y1592740I0J2002D01*
G01X1161596D01*
G02X1162959Y1592204I0J-2002D01*
G03X1163231I136J147D01*
G02X1164594Y1592740I1363J-1466D01*
G01X1164595D01*
G02Y1588736I0J-2002D01*
G01X1164594D01*
G02X1163231Y1589272I0J2002D01*
G37*
G36*
G01X1173231D02*
G03X1172959I-136J-147D01*
G02X1171596Y1588736I-1363J1466D01*
G01X1171595D01*
G02Y1592740I0J2002D01*
G01X1171596D01*
G02X1172959Y1592204I0J-2002D01*
G03X1173231I136J147D01*
G02X1174594Y1592740I1363J-1466D01*
G01X1174595D01*
G02Y1588736I0J-2002D01*
G01X1174594D01*
G02X1173231Y1589272I0J2002D01*
G37*
G54D91*
X1137717Y1558020D03*
G54D88*
X479646Y1421784D03*
G54D90*
X1074010Y1510650D03*
X1066462Y1520088D03*
G54D89*
X1175215Y1532913D03*
X1131715D03*
G54D76*
X1307572Y-26511D03*
X1040152Y-16511D03*
X1015152D03*
X1307572Y13489D03*
X1282572Y23489D03*
X1307572D03*
X1282572Y13489D03*
X1040152Y23489D03*
Y13489D03*
X973180Y-6500D03*
X998180D03*
X1015152Y13489D03*
X1282572Y-16511D03*
X973180Y-26500D03*
X998180D03*
Y-16500D03*
X1015152Y23489D03*
X1307572Y-16511D03*
X973180Y-16500D03*
X1474931Y23489D03*
X1499931D03*
X705760Y-26500D03*
X730760D03*
X705760Y-6500D03*
Y-16500D03*
X730760D03*
Y-6500D03*
X1474931Y13489D03*
X998180Y3500D03*
X973180D03*
X1499931Y13489D03*
X998180Y13500D03*
Y23500D03*
X973180D03*
Y13500D03*
X1499931Y-16511D03*
X1474931D03*
X1324471Y23489D03*
X1349471D03*
X822720Y3500D03*
X847720D03*
X822720Y23500D03*
Y13500D03*
X847720D03*
Y23500D03*
X1324471Y-16511D03*
X1349471D03*
X1324471Y13489D03*
X1349471D03*
X1307572Y-36511D03*
X1282572D03*
Y-26511D03*
X1307572Y-6511D03*
Y3489D03*
X1282572D03*
Y-6511D03*
X1015152Y-36511D03*
Y-26511D03*
X1040152D03*
Y-36511D03*
X1015152Y3489D03*
Y-6511D03*
X1040152D03*
Y3489D03*
X1499931Y-26511D03*
Y-36511D03*
X1474931D03*
Y-26511D03*
X1499931Y-6511D03*
Y3489D03*
X1474931D03*
Y-6511D03*
X1324471Y-36511D03*
Y-26511D03*
X1349471D03*
Y-36511D03*
X1324471Y3489D03*
Y-6511D03*
X1349471D03*
Y3489D03*
G54D81*
X70472Y173228D03*
Y236220D03*
G54D84*
X929331Y160413D03*
X922441Y237697D03*
G54D83*
X676508Y224606D03*
G54D82*
Y145866D03*
G54D80*
X1829725Y130315D03*
G54D98*
X791280Y1704890D03*
X1066280D03*
G54D75*
X1341752Y-31511D03*
Y-21511D03*
Y-11511D03*
Y-1511D03*
X1482650Y-31511D03*
Y-21511D03*
Y-11511D03*
Y-1511D03*
X90998Y1517237D03*
X78120Y1517136D03*
X99750Y1563678D03*
X75922Y1560674D03*
X404030Y1593690D03*
X957156Y228863D03*
X899830Y973184D03*
X397406Y1634842D03*
X736710Y605542D03*
X527310Y96447D03*
X414406Y1626692D03*
X460910Y1627472D03*
X64410Y1600802D03*
X1340420Y540122D03*
X704770Y204921D03*
X896060Y482922D03*
X716698Y210721D03*
X704770Y216732D03*
X895340Y499582D03*
X907470Y213680D03*
X902350Y220768D03*
X953970Y206575D03*
X716698Y198887D03*
X704770Y193110D03*
Y181299D03*
X947496Y227835D03*
X705800Y169488D03*
X947496Y213697D03*
X907470Y227854D03*
X941050Y530552D03*
X716698Y175387D03*
X902350Y206594D03*
X716698Y187387D03*
X944250Y196189D03*
X954420Y512952D03*
Y498852D03*
G54D74*
X723041Y-11500D03*
Y-21500D03*
X840001Y8500D03*
Y18500D03*
X980899Y-21500D03*
Y-11500D03*
Y8500D03*
Y18500D03*
X1032433Y-31511D03*
Y-21511D03*
Y-11511D03*
Y-1511D03*
X1290291Y-31511D03*
Y-21511D03*
Y-11511D03*
Y-1511D03*
X62813Y414300D03*
X47619Y417205D03*
X901829Y514430D03*
X889439Y491299D03*
X922879Y530276D03*
X946727Y506252D03*
G54D86*
X805690Y204724D03*
X1829921Y87795D03*
X27559D03*
X931692Y757874D03*
X40708Y1368897D03*
X931692Y1072834D03*
X1271260Y631890D03*
X373622Y87795D03*
X800787D03*
X931692Y1387795D03*
X661023Y631890D03*
X1499606Y87795D03*
G54D85*
X38346Y1420330D03*
G54D77*
X19685Y-29134D03*
X1837795D03*
X1808192Y1569255D03*
X41870Y1511291D03*
X1812980Y502472D03*
X49280Y337402D03*
X2081889Y1803261D03*
Y-29134D03*
G54D87*
X763602Y605413D03*
X1739744D03*
X1094075Y605378D03*
G54D78*
X177311Y1657953D03*
G54D79*
X1680232D03*
%LPC*%
G75*
G36*
G01X84334Y1252861D02*
G03X84941Y1252999I0J1402D01*
G01X84982Y1253019D01*
X120659D01*
X122963Y1250715D01*
G03X122973Y1250705I712J702D01*
G01Y862229D01*
G03X123266Y861522I999J0D01*
G01X124207Y860581D01*
Y860498D01*
G03X125498Y859207I1292J1D01*
G01X125581D01*
X125952Y858836D01*
G03X126659Y858543I707J706D01*
G01X237535D01*
X239710Y856368D01*
Y639057D01*
X239695Y639020D01*
G03Y637960I1298J-530D01*
G01X239710Y637923D01*
Y631387D01*
X239695Y631350D01*
G03Y630290I1298J-530D01*
G01X239710Y630253D01*
Y628787D01*
X239695Y628750D01*
G03Y627690I1298J-530D01*
G01X239710Y627653D01*
Y605057D01*
X239695Y605020D01*
G03Y603960I1298J-530D01*
G01X239710Y603923D01*
Y597387D01*
X239695Y597350D01*
G03Y596290I1298J-530D01*
G01X239710Y596253D01*
Y594787D01*
X239695Y594750D01*
G03Y593690I1298J-530D01*
G01X239710Y593653D01*
Y571057D01*
X239695Y571020D01*
G03Y569960I1298J-530D01*
G01X239710Y569923D01*
Y548001D01*
X237774Y546065D01*
X196951D01*
X194457Y548559D01*
Y603550D01*
X194582Y603600D01*
G03Y606202I-523J1301D01*
G01X194457Y606252D01*
Y621603D01*
G03X194164Y622310I-999J0D01*
G01X189445Y627029D01*
G03X188738Y627322I-707J-706D01*
G01X70414D01*
X60850Y636886D01*
G03X51927Y649349I-20142J-4995D01*
G01Y695475D01*
G03X51817Y695931I-1000J0D01*
G01X26047Y746220D01*
Y765210D01*
X26054Y765236D01*
G03X26102Y765600I-1354J364D01*
G03X26054Y765964I-1402J0D01*
G01X26047Y765990D01*
Y1250887D01*
X28179Y1253019D01*
X51700D01*
G03X53940I1120J843D01*
G01X83686D01*
X83727Y1252999D01*
G03X84334Y1252861I607J1264D01*
G37*
G36*
G01X756791Y1422582D02*
X820169D01*
G02X820567Y1422147I0J-400D01*
G03X820488Y1420330I20673J-1809D01*
G03X841240Y1399578I20752J0D01*
G03X854383Y1404270I1J20752D01*
G01X854523Y1404385D01*
X856457Y1402451D01*
Y1260091D01*
X829124D01*
X829103Y1260096D01*
G03X828799Y1260129I-302J-1369D01*
G03X828495Y1260096I-2J-1402D01*
G01X828474Y1260091D01*
X799424D01*
X799403Y1260096D01*
G03X799099Y1260129I-302J-1369D01*
G03X798795Y1260096I-2J-1402D01*
G01X798774Y1260091D01*
X784203D01*
G03X782057I-1073J-718D01*
G01X769724D01*
X769703Y1260096D01*
G03X769399Y1260129I-302J-1369D01*
G03X769095Y1260096I-2J-1402D01*
G01X769074Y1260091D01*
X740024D01*
X740003Y1260096D01*
G03X739699Y1260129I-302J-1369D01*
G03X739395Y1260096I-2J-1402D01*
G01X739374Y1260091D01*
X715628D01*
X714337Y1261382D01*
G03X714273Y1261441I-709J-705D01*
G01Y1272684D01*
X714295Y1272727D01*
G03Y1274001I-1250J637D01*
G01X714273Y1274044D01*
Y1282246D01*
X714398Y1282296D01*
G03Y1285082I-562J1393D01*
G01X714273Y1285132D01*
Y1288951D01*
X717034Y1291712D01*
X730710D01*
G03X731417Y1292005I0J999D01*
G01X734307Y1294895D01*
G03X734600Y1295602I-706J707D01*
G01Y1341942D01*
G03X734307Y1342649I-999J0D01*
G01X729707Y1347249D01*
G03X729079Y1347539I-707J-706D01*
G03X728104Y1347898I-975J-1143D01*
G03X727185Y1347584I0J-1502D01*
G01X727131Y1347542D01*
X726577D01*
X726523Y1347584D01*
G03X725604Y1347898I-919J-1188D01*
G03X724633Y1347542I0J-1502D01*
G01X724025D01*
G03X722083I-971J-1146D01*
G01X709108D01*
G03X707166I-971J-1146D01*
G01X706558D01*
G03X705587Y1347898I-971J-1146D01*
G03X704668Y1347584I0J-1502D01*
G01X704614Y1347542D01*
X704060D01*
X704006Y1347584D01*
G03X703087Y1347898I-919J-1188D01*
G03X702116Y1347542I0J-1502D01*
G01X690576D01*
G03X689605Y1347898I-971J-1146D01*
G03X688686Y1347584I0J-1502D01*
G01X688632Y1347542D01*
X688078D01*
X688024Y1347584D01*
G03X687105Y1347898I-919J-1188D01*
G03X686134Y1347542I0J-1502D01*
G01X685526D01*
G03X683584I-971J-1146D01*
G01X671008D01*
G03X669066I-971J-1146D01*
G01X668458D01*
G03X667487Y1347898I-971J-1146D01*
G03X666568Y1347584I0J-1502D01*
G01X666514Y1347542D01*
X665960D01*
X665906Y1347584D01*
G03X664987Y1347898I-919J-1188D01*
G03X664016Y1347542I0J-1502D01*
G01X589910D01*
G03X589203Y1347249I0J-999D01*
G01X584430Y1342476D01*
G03X584137Y1341769I706J-707D01*
G01Y1308609D01*
X582293Y1306765D01*
X528573D01*
G03X527866Y1306472I0J-999D01*
G01X526166Y1304772D01*
G03X525873Y1304065I706J-707D01*
G01Y1295279D01*
X517059Y1286465D01*
X500973D01*
G03X500266Y1286172I0J-999D01*
G01X494266Y1280172D01*
G03X493973Y1279465I706J-707D01*
G01Y1274579D01*
X491959Y1272565D01*
X367587D01*
X366273Y1273879D01*
Y1280065D01*
G03X365980Y1280772I-999J0D01*
G01X360780Y1285972D01*
G03X360073Y1286265I-707J-706D01*
G01X338087D01*
X335073Y1289279D01*
Y1296419D01*
G03X334780Y1297126I-999J0D01*
G01X329814Y1302092D01*
G03X329107Y1302385I-707J-706D01*
G01X315271D01*
X300161Y1317495D01*
G03X299454Y1317788I-707J-706D01*
G01X267859D01*
X232684Y1352963D01*
G03X231977Y1353256I-707J-706D01*
G01X150494D01*
G03X149787Y1352963I0J-999D01*
G01X142208Y1345384D01*
G03X141915Y1344677I706J-707D01*
G01Y1273375D01*
X123559Y1255019D01*
X115537D01*
X115486Y1255142D01*
G03X112896I-1295J-539D01*
G01X112845Y1255019D01*
X85515D01*
G03X83153I-1181J-757D01*
G01X53612D01*
G03X52028I-792J-1158D01*
G01X29501D01*
G02X29101Y1255411I0J400D01*
G03X27699Y1256783I-1402J-30D01*
G03X26914Y1256543I-1J-1402D01*
G01X26778Y1256450D01*
X26047Y1257181D01*
Y1289975D01*
G03X26045Y1290032I-1000J-7D01*
G01Y1318459D01*
X35051Y1327465D01*
X87907D01*
G03X88614Y1327758I0J999D01*
G01X99404Y1338548D01*
G03X99697Y1339255I-706J707D01*
G01Y1369350D01*
X146012Y1415665D01*
X223341D01*
X223384Y1415642D01*
G03X224077Y1415473I692J1333D01*
G03X224770Y1415642I1J1502D01*
G01X224813Y1415665D01*
X337843D01*
X342837Y1410671D01*
Y1400345D01*
G03X343130Y1399638I999J0D01*
G01X346620Y1396148D01*
G03X347327Y1395855I707J706D01*
G01X400353D01*
G03X401060Y1396148I0J999D01*
G01X411663Y1406751D01*
X411701Y1406766D01*
G03X412485Y1407475I-551J1397D01*
G01X444741D01*
X444781Y1407328D01*
G03X447679I1449J393D01*
G01X447719Y1407475D01*
X502062D01*
X502088Y1407306D01*
G03X505056I1484J233D01*
G01X505082Y1407475D01*
X507803D01*
G03X508510Y1407768I0J999D01*
G01X509185Y1408443D01*
X509232Y1408458D01*
G03X510206Y1409432I-457J1431D01*
G01X510221Y1409479D01*
X523324Y1422582D01*
X575434D01*
G03X577006I786J1280D01*
G01X689811D01*
G03X692447I1318J722D01*
G01X692811D01*
G03X694129Y1421801I1318J722D01*
G03X694916Y1422024I0J1502D01*
G02X695474Y1421879I209J-341D01*
G03X696784Y1421112I1310J735D01*
G03X697969Y1421691I0J1502D01*
G02X698599I315J-246D01*
G03X699784Y1421112I1185J923D01*
G03X701272Y1422409I0J1502D01*
G01X701296Y1422582D01*
X754049D01*
X754093Y1422442D01*
G03X756747I1327J420D01*
G01X756791Y1422582D01*
G37*
G36*
G01X431220Y511231D02*
G03X431498Y511259I0J1392D01*
G01X431518Y511263D01*
X520065D01*
X520102Y511111D01*
G03X521561Y509967I1459J358D01*
G01X521563D01*
G03X522631Y510414I-1J1502D01*
G02X523207Y510408I285J-280D01*
G03X524220Y509970I1014J954D01*
G03X525170Y510345I0J1391D01*
G02X525740Y510322I274J-292D01*
G03X526852Y509829I1112J1008D01*
G03X528335Y511094I0J1502D01*
G01X528362Y511263D01*
X592906D01*
G03X595574I1334J690D01*
G01X611113D01*
G03X611870Y511058I757J1297D01*
G03X612627Y511263I0J1502D01*
G01X782041D01*
G03X784759I1359J639D01*
G01X796572D01*
G03X798268I848J1241D01*
G01X833315D01*
X877633Y466945D01*
G03X878340Y466652I707J706D01*
G01X945747D01*
G03X946454Y466945I0J999D01*
G01X1006111Y526602D01*
X1165827D01*
X1165874Y526467D01*
G03X1167190Y525530I1316J456D01*
G03X1168161Y525925I0J1391D01*
G02X1168719I279J-287D01*
G03X1169690Y525530I971J996D01*
G03X1171006Y526467I0J1393D01*
G01X1171053Y526602D01*
X1171902D01*
G03X1172720Y526360I818J1260D01*
G03X1173538Y526602I0J1502D01*
G01X1314186D01*
X1434253Y406535D01*
G03X1434960Y406242I707J706D01*
G01X1448279D01*
G03X1450313I1017J1104D01*
G01X1461781D01*
X1461818Y406089D01*
G03X1464736I1459J357D01*
G01X1464773Y406242D01*
X1469458D01*
X1469495Y406089D01*
G03X1472413I1459J357D01*
G01X1472450Y406242D01*
X1489470D01*
G03X1491298I914J1050D01*
G01X1502926D01*
X1537910Y371258D01*
Y307682D01*
G03X1538203Y306975I999J0D01*
G01X1561073Y284105D01*
G03X1561780Y283812I707J706D01*
G01X1658640D01*
Y260110D01*
G03X1702014I21687J0D01*
G01Y283812D01*
X1755931D01*
X1755960Y283647D01*
G03X1757439Y282409I1479J264D01*
G03X1758587Y282943I0J1501D01*
G02X1759210Y282930I306J-258D01*
G03X1760398Y282346I1189J918D01*
G03X1761707Y283112I0J1501D01*
G02X1762408Y283105I349J-196D01*
G03X1763731Y282315I1323J713D01*
G03X1765222Y283636I0J1502D01*
G01X1765243Y283812D01*
X1775046D01*
X1780010Y278848D01*
Y179079D01*
X1779870Y179035D01*
G03Y176169I450J-1433D01*
G01X1780010Y176125D01*
Y162316D01*
X1763966Y146272D01*
X1693150D01*
X1693116Y146429D01*
G03X1686176I-3470J-760D01*
G01X1686142Y146272D01*
X1683150D01*
X1683116Y146429D01*
G03X1676176I-3470J-760D01*
G01X1676142Y146272D01*
X1527594D01*
X1527569Y146443D01*
G03X1524597I-1486J-218D01*
G01X1524572Y146272D01*
X1520420D01*
G03X1519713Y145979I0J-999D01*
G01X1468266Y94532D01*
X1394435D01*
G03X1392065I-1185J-730D01*
G01X1324269D01*
X1324222Y94667D01*
G03X1321590I-1316J-456D01*
G01X1321543Y94532D01*
X1315411D01*
G03X1312707I-1352J-656D01*
G01X1293129D01*
X1293112Y94535D01*
G03X1292880Y94554I-229J-1373D01*
G03X1292648Y94535I-3J-1392D01*
G01X1292631Y94532D01*
X1131814D01*
X1079740Y146606D01*
Y163694D01*
G03X1079807Y163755I-639J769D01*
G01X1081414Y165362D01*
X1270211D01*
X1270267Y165256D01*
G03X1272919I1326J706D01*
G01X1272975Y165362D01*
X1293379D01*
X1293407Y165354D01*
G03X1293802Y165297I396J1345D01*
G03X1294197Y165354I-1J1402D01*
G01X1294225Y165362D01*
X1299789D01*
X1299817Y165354D01*
G03X1300212Y165297I396J1345D01*
G03X1300607Y165354I-1J1402D01*
G01X1300635Y165362D01*
X1306199D01*
X1306227Y165354D01*
G03X1306622Y165297I396J1345D01*
G03X1307017Y165354I-1J1402D01*
G01X1307045Y165362D01*
X1312610D01*
X1312638Y165354D01*
G03X1313033Y165297I396J1345D01*
G03X1313428Y165354I-1J1402D01*
G01X1313456Y165362D01*
X1319029D01*
X1319057Y165354D01*
G03X1319452Y165297I396J1345D01*
G03X1319847Y165354I-1J1402D01*
G01X1319875Y165362D01*
X1331845D01*
X1331873Y165354D01*
G03X1332268Y165297I396J1345D01*
G03X1332707Y165368I-1J1402D01*
G03X1333307Y165655I-107J994D01*
G01X1334910Y167258D01*
X1335028Y167219D01*
G03X1335471Y167147I444J1330D01*
G01X1335472D01*
G03X1336874Y168549I0J1402D01*
G03X1335500Y169951I-1402J0D01*
G01Y170847D01*
G03Y173651I-28J1402D01*
G01Y175934D01*
X1335519Y175975D01*
G03Y177173I-1266J599D01*
G01X1335500Y177214D01*
Y194834D01*
X1335519Y194875D01*
G03Y196073I-1266J599D01*
G01X1335500Y196114D01*
Y221262D01*
G03X1335207Y221969I-999J0D01*
G01X1332307Y224869D01*
G03X1331600Y225162I-707J-706D01*
G01X1329914D01*
G03X1328208I-853J-1114D01*
G01X1323505D01*
G03X1321799I-853J-1114D01*
G01X1310681D01*
G03X1308975I-853J-1114D01*
G01X1304278D01*
G03X1302572I-853J-1114D01*
G01X1299514D01*
X1297300Y227376D01*
Y315062D01*
X1297310Y315093D01*
G03X1297389Y315571I-1423J481D01*
G03X1297310Y316049I-1502J-3D01*
G01X1297300Y316080D01*
Y323852D01*
G03X1297007Y324559I-999J0D01*
G01X1290267Y331299D01*
G03X1289560Y331592I-707J-706D01*
G01X1078880D01*
G03X1078173Y331299I0J-999D01*
G01X1071093Y324219D01*
G03X1070800Y323512I706J-707D01*
G01Y304376D01*
X1069786Y303362D01*
X1016942D01*
X1016889Y303480D01*
G03X1014151I-1369J-618D01*
G01X1014098Y303362D01*
X940023D01*
G02X939810Y304100I1J400D01*
G03X949492Y321653I-11070J17553D01*
G03X907986I-20753J0D01*
G03X917668Y304100I20752J0D01*
G02X917455Y303362I-214J-338D01*
G01X838940D01*
G03X838233Y303069I0J-999D01*
G01X829393Y294229D01*
X829340Y294215D01*
G03X828218Y292762I380J-1453D01*
G03X828237Y292521I1502J-3D01*
G01X828240Y292505D01*
Y280937D01*
G03X828118Y280345I1380J-593D01*
G03X828240Y279753I1502J1D01*
G01Y277819D01*
X828237Y277803D01*
G03X828218Y277562I1483J-238D01*
G03X828237Y277321I1502J-3D01*
G01X828240Y277305D01*
Y265007D01*
X828233Y264981D01*
G03X828178Y264580I1447J-403D01*
G03X828233Y264179I1502J2D01*
G01X828240Y264153D01*
Y242256D01*
X823746Y237762D01*
X675225D01*
X675200Y237934D01*
G03X672226I-1487J-209D01*
G01X672201Y237762D01*
X648600D01*
G03X647893Y237469I0J-999D01*
G01X635793Y225369D01*
G03X635500Y224662I706J-707D01*
G01Y128276D01*
X631786Y124562D01*
X599845D01*
X599794Y124685D01*
G03X597026I-1384J-582D01*
G01X596975Y124562D01*
X384724D01*
X384624Y124662D01*
X384610Y124714D01*
G03X383552Y125772I-1450J-392D01*
G01X383500Y125786D01*
X360997Y148289D01*
G03X360290Y148582I-707J-706D01*
G01X346282D01*
X346251Y148744D01*
G03X343301I-1475J-282D01*
G01X343270Y148582D01*
X128774D01*
X100240Y177116D01*
Y498698D01*
X119084Y517542D01*
X152530D01*
X158516Y511556D01*
G03X159223Y511263I707J706D01*
G01X161901D01*
G03X163599I849J1239D01*
G01X430922D01*
X430942Y511259D01*
G03X431220Y511231I278J1364D01*
G37*
G36*
G01X150908Y1351256D02*
X231563D01*
X266738Y1316081D01*
G03X267445Y1315788I707J706D01*
G01X283970D01*
X285277Y1314481D01*
Y1167285D01*
G03X285570Y1166578I999J0D01*
G01X314877Y1137271D01*
G03X315584Y1136978I707J706D01*
G01X344410D01*
X344466Y1136871D01*
G03X346756I1145J598D01*
G01X346812Y1136978D01*
X348105D01*
X348161Y1136870D01*
G03X349070Y1136194I1151J599D01*
G01X349160Y1136177D01*
X349967Y1134779D01*
X349936Y1134693D01*
G03X349864Y1134264I1225J-426D01*
G03X352458I1297J0D01*
G03X351403Y1135539I-1298J0D01*
G01X351313Y1135556D01*
X350838Y1136378D01*
G02X351185Y1136978I347J200D01*
G01X351810D01*
X351866Y1136871D01*
G03X354156I1145J598D01*
G01X354212Y1136978D01*
X355505D01*
X355561Y1136870D01*
G03X356470Y1136194I1151J599D01*
G01X356560Y1136177D01*
X357367Y1134779D01*
X357336Y1134693D01*
G03X357264Y1134264I1225J-426D01*
G03X359858I1297J0D01*
G03X358803Y1135539I-1298J0D01*
G01X358713Y1135556D01*
X358238Y1136378D01*
G02X358585Y1136978I347J200D01*
G01X359205D01*
X359261Y1136870D01*
G03X361563I1151J600D01*
G01X361619Y1136978D01*
X362905D01*
X362961Y1136870D01*
G03X363870Y1136194I1151J599D01*
G01X363960Y1136177D01*
X364768Y1134779D01*
X364737Y1134692D01*
G03X364664Y1134264I1225J-429D01*
G03X367260I1298J0D01*
G03X366204Y1135539I-1298J0D01*
G01X366114Y1135556D01*
X365639Y1136378D01*
G02X365985Y1136978I346J200D01*
G01X366605D01*
X366661Y1136870D01*
G03X368963I1151J600D01*
G01X369019Y1136978D01*
X370305D01*
X370361Y1136870D01*
G03X371270Y1136194I1151J599D01*
G01X371360Y1136177D01*
X372168Y1134779D01*
X372137Y1134692D01*
G03X372064Y1134264I1225J-429D01*
G03X374660I1298J0D01*
G03X373604Y1135539I-1298J0D01*
G01X373514Y1135556D01*
X373039Y1136378D01*
G02X373385Y1136978I346J200D01*
G01X374005D01*
X374061Y1136870D01*
G03X376363I1151J600D01*
G01X376419Y1136978D01*
X377705D01*
X377761Y1136870D01*
G03X378670Y1136194I1151J599D01*
G01X378760Y1136177D01*
X379568Y1134779D01*
X379537Y1134692D01*
G03X379464Y1134264I1225J-429D01*
G03X382060I1298J0D01*
G03X381004Y1135539I-1298J0D01*
G01X380914Y1135556D01*
X380439Y1136378D01*
G02X380785Y1136978I346J200D01*
G01X381405D01*
X381461Y1136870D01*
G03X383763I1151J600D01*
G01X383819Y1136978D01*
X385105D01*
X385161Y1136870D01*
G03X386070Y1136194I1151J599D01*
G01X386160Y1136177D01*
X386968Y1134779D01*
X386937Y1134692D01*
G03X386864Y1134264I1225J-429D01*
G03X389460I1298J0D01*
G03X388404Y1135539I-1298J0D01*
G01X388314Y1135556D01*
X387839Y1136378D01*
G02X388185Y1136978I346J200D01*
G01X388805D01*
X388861Y1136870D01*
G03X391163I1151J600D01*
G01X391219Y1136978D01*
X392505D01*
X392561Y1136870D01*
G03X393470Y1136194I1151J599D01*
G01X393560Y1136177D01*
X394368Y1134779D01*
X394337Y1134692D01*
G03X394264Y1134264I1225J-429D01*
G03X396860I1298J0D01*
G03X395804Y1135539I-1298J0D01*
G01X395714Y1135556D01*
X395239Y1136378D01*
G02X395585Y1136978I346J200D01*
G01X396205D01*
X396261Y1136870D01*
G03X398563I1151J600D01*
G01X398619Y1136978D01*
X399905D01*
X399961Y1136870D01*
G03X400870Y1136194I1151J599D01*
G01X400960Y1136177D01*
X401768Y1134779D01*
X401737Y1134692D01*
G03X401664Y1134264I1225J-429D01*
G03X404260I1298J0D01*
G03X403204Y1135539I-1298J0D01*
G01X403114Y1135556D01*
X402639Y1136378D01*
G02X402985Y1136978I346J200D01*
G01X403605D01*
X403661Y1136870D01*
G03X405963I1151J600D01*
G01X406019Y1136978D01*
X407021D01*
X409096Y1134903D01*
X409168Y1134779D01*
X409137Y1134692D01*
G03X409064Y1134264I1225J-429D01*
G03X409781Y1133104I1297J0D01*
G01X409891Y1133049D01*
Y1129066D01*
X409781Y1129010D01*
G03Y1126702I579J-1154D01*
G01X409891Y1126646D01*
Y1126037D01*
G02X409260Y1125710I-400J0D01*
G03X408511Y1125948I-749J-1060D01*
G03X407214Y1124651I0J-1297D01*
G03X408269Y1123376I1298J0D01*
G01X408359Y1123359D01*
X409167Y1121960D01*
X409137Y1121874D01*
G03X409064Y1121447I1225J-429D01*
G03X409781Y1120287I1297J0D01*
G01X409891Y1120232D01*
Y1117188D01*
G03X410184Y1116481I999J0D01*
G01X414626Y1112039D01*
X414618Y1111946D01*
G03X414614Y1111834I1293J-102D01*
G03X415911Y1110536I1298J0D01*
G03X416023Y1110541I-2J1298D01*
G01X416116Y1110549D01*
X416980Y1109685D01*
X416840Y1109543D01*
G03X416464Y1108630I922J-914D01*
G03X417762Y1107332I1298J0D01*
G03X418675Y1107708I-1J1298D01*
G01X418817Y1107848D01*
X419349Y1107316D01*
G02X419194Y1106655I-283J-282D01*
G03X418572Y1106204I417J-1229D01*
G01X416950D01*
G03X415911Y1106724I-1039J-778D01*
G03Y1104128I0J-1298D01*
G03X416950Y1104648I0J1298D01*
G01X418572D01*
G03X419611Y1104128I1039J778D01*
G03X420840Y1105009I0J1298D01*
G02X421501Y1105164I379J-128D01*
G01X423958Y1102707D01*
X423924Y1102593D01*
G03X423869Y1102221I1237J-373D01*
G03X424586Y1101064I1292J0D01*
G01X424697Y1101009D01*
Y1097031D01*
X424586Y1096976D01*
G03X423864Y1095813I576J-1163D01*
G03X423937Y1095385I1298J1D01*
G01X423968Y1095298D01*
X423161Y1093900D01*
X423070Y1093883D01*
G03X422014Y1092608I242J-1275D01*
G03X423311Y1091310I1298J0D01*
G03X424065Y1091552I-1J1298D01*
G02X424697Y1091226I232J-326D01*
G01Y1090616D01*
X424586Y1090561D01*
G03Y1088247I577J-1157D01*
G01X424697Y1088192D01*
Y1087582D01*
G02X424065Y1087256I-400J0D01*
G03X423311Y1087498I-755J-1056D01*
G03X422272Y1086978I0J-1298D01*
G01X420650D01*
G03X419611Y1087498I-1039J-778D01*
G03Y1084902I0J-1298D01*
G03X420650Y1085422I0J1298D01*
G01X422272D01*
G03X423311Y1084902I1039J778D01*
G03X424065Y1085144I-1J1298D01*
G02X424697Y1084818I232J-326D01*
G01Y1084213D01*
X424586Y1084158D01*
G03X423864Y1082995I576J-1163D01*
G03X424586Y1081832I1298J0D01*
G01X424697Y1081777D01*
Y1077799D01*
X424586Y1077744D01*
G03Y1075430I577J-1157D01*
G01X424697Y1075375D01*
Y1071390D01*
X424586Y1071335D01*
G03Y1069021I577J-1157D01*
G01X424697Y1068966D01*
Y1064982D01*
X424586Y1064927D01*
G03Y1062613I577J-1157D01*
G01X424697Y1062558D01*
Y1058573D01*
X424586Y1058518D01*
G03Y1056204I577J-1157D01*
G01X424697Y1056149D01*
Y1052164D01*
X424586Y1052109D01*
G03Y1049795I577J-1157D01*
G01X424697Y1049740D01*
Y1045756D01*
X424586Y1045701D01*
G03Y1043387I577J-1157D01*
G01X424697Y1043332D01*
Y1043000D01*
X424084Y1042387D01*
X423952Y1042463D01*
G03X423312Y1042632I-639J-1123D01*
G03X422020Y1041340I0J-1292D01*
G03X422189Y1040700I1292J-1D01*
G01X422265Y1040568D01*
X420218Y1038521D01*
G03X419925Y1037814I706J-707D01*
G01Y1031961D01*
G03X420218Y1031254I999J0D01*
G01X421534Y1029938D01*
G03X422241Y1029645I707J706D01*
G01X423040D01*
X423795Y1028890D01*
Y1028300D01*
X423323Y1027828D01*
X415636D01*
G03X414929Y1027535I0J-999D01*
G01X414559Y1027165D01*
X414175D01*
Y1027166D01*
X411984D01*
X410742Y1028409D01*
Y1029685D01*
X411074Y1030018D01*
Y1030019D01*
X411427Y1030371D01*
G03X411572Y1030699I-354J353D01*
G03X412073Y1031565I-498J866D01*
G01Y1048565D01*
G03X411780Y1049272I-999J0D01*
G01X405080Y1055972D01*
G03X404373Y1056265I-707J-706D01*
G01X380473D01*
G03X379766Y1055972I0J-999D01*
G01X379212Y1055418D01*
X379111Y1055433D01*
G03X378911Y1055449I-203J-1276D01*
G03X377619Y1054157I0J-1292D01*
G03X377635Y1053957I1292J3D01*
G01X377650Y1053856D01*
X369632Y1045838D01*
X369558Y1045832D01*
G03X368374Y1044648I104J-1288D01*
G01X368368Y1044574D01*
X363000Y1039206D01*
X362870Y1039276D01*
G03X361122Y1037528I-608J-1140D01*
G01X361192Y1037398D01*
X359921Y1036127D01*
X359887Y1036112D01*
G03X359230Y1035455I524J-1181D01*
G01X359215Y1035421D01*
X353513Y1029719D01*
X353398Y1029756D01*
G03X353011Y1029815I-386J-1233D01*
G03X351719Y1028523I0J-1292D01*
G03X351819Y1028025I1292J0D01*
G01X351766Y1027972D01*
G03X351473Y1027265I706J-707D01*
G01Y983428D01*
X351448Y983382D01*
G03X351286Y982756I1130J-626D01*
G03X351448Y982130I1292J0D01*
G01X351473Y982084D01*
Y977017D01*
X351448Y976972D01*
G03X351287Y976347I1131J-625D01*
G03X351448Y975722I1292J0D01*
G01X351473Y975677D01*
Y970611D01*
X351448Y970565D01*
G03X351286Y969939I1130J-626D01*
G03X351448Y969313I1292J0D01*
G01X351473Y969267D01*
Y964202D01*
X351448Y964156D01*
G03X351286Y963530I1130J-626D01*
G03X351448Y962904I1292J0D01*
G01X351473Y962858D01*
Y957794D01*
X351448Y957748D01*
G03X351286Y957122I1130J-626D01*
G03X351448Y956496I1292J0D01*
G01X351473Y956450D01*
Y951385D01*
X351448Y951339D01*
G03X351286Y950713I1130J-626D01*
G03X351448Y950087I1292J0D01*
G01X351473Y950041D01*
Y944976D01*
X351448Y944930D01*
G03X351286Y944304I1130J-626D01*
G03X351448Y943678I1292J0D01*
G01X351473Y943632D01*
Y938568D01*
X351448Y938522D01*
G03X351286Y937896I1130J-626D01*
G03X351448Y937270I1292J0D01*
G01X351473Y937224D01*
Y932160D01*
X351448Y932114D01*
G03X351286Y931488I1130J-626D01*
G03X351448Y930862I1292J0D01*
G01X351473Y930816D01*
Y925751D01*
X351448Y925705D01*
G03X351286Y925079I1130J-626D01*
G03X351448Y924453I1292J0D01*
G01X351473Y924407D01*
Y919943D01*
G03X351581Y919491I1000J0D01*
G03X351286Y918670I997J-822D01*
G03X352578Y917378I1292J0D01*
G03X353233Y917557I-1J1292D01*
G01X353367Y917635D01*
X358685Y912317D01*
X358686Y912237D01*
G03X359953Y910970I1292J25D01*
G01X360033Y910969D01*
X367986Y903016D01*
X367964Y902911D01*
G03X367937Y902649I1265J-263D01*
G03X369229Y901357I1292J0D01*
G03X369491Y901384I-1J1292D01*
G01X369596Y901406D01*
X377341Y893661D01*
X377288Y893538D01*
G03X377187Y893036I1191J-501D01*
G03X378479Y891744I1292J0D01*
G03X378981Y891845I1J1292D01*
G01X379104Y891898D01*
X381317Y889685D01*
Y887598D01*
G03X380880Y886627I860J-971D01*
G03X380953Y886199I1298J1D01*
G01X380984Y886112D01*
X380177Y884715D01*
X380087Y884698D01*
G03X379032Y883423I243J-1275D01*
G03X380329Y882126I1297J0D01*
G03X380778Y882206I1J1297D01*
G02X381317Y881831I139J-375D01*
G01Y881181D01*
G03Y879257I861J-962D01*
G01Y874781D01*
G03X380880Y873810I860J-971D01*
G03X380953Y873382I1298J1D01*
G01X380984Y873295D01*
X380177Y871898D01*
X380087Y871881D01*
G03X379032Y870606I243J-1275D01*
G03X379035Y870506I1297J-11D01*
G01X379042Y870414D01*
X378520Y869892D01*
G02X377890Y869975I-283J282D01*
G01X377823Y870091D01*
X377854Y870177D01*
G03X377926Y870606I-1225J426D01*
G03X375332I-1297J0D01*
G03X376387Y869331I1298J0D01*
G01X376477Y869314D01*
X377013Y868385D01*
X373970Y865342D01*
G03X373677Y864635I706J-707D01*
G01Y861682D01*
X373651Y861636D01*
G03X373480Y860993I1127J-644D01*
G03X373553Y860565I1298J1D01*
G01X373584Y860478D01*
X372777Y859081D01*
X372687Y859064D01*
G03X372000Y858695I242J-1275D01*
G01X370158D01*
G03X369229Y859086I-928J-906D01*
G03X368300Y858695I-1J-1297D01*
G01X367642D01*
G02X367295Y859295I0J400D01*
G01X367530Y859701D01*
X367620Y859718D01*
G03X368676Y860993I-242J1275D01*
G03X366080I-1298J0D01*
G03X366153Y860565I1298J1D01*
G01X366184Y860478D01*
X365377Y859081D01*
X365287Y859064D01*
G03X364600Y858695I242J-1275D01*
G01X362758D01*
G03X361829Y859086I-928J-906D01*
G03X360900Y858695I-1J-1297D01*
G01X360242D01*
G02X359895Y859295I0J400D01*
G01X360130Y859701D01*
X360220Y859718D01*
G03X361276Y860993I-242J1275D01*
G03X358680I-1298J0D01*
G03X358753Y860565I1298J1D01*
G01X358784Y860478D01*
X357977Y859081D01*
X357887Y859064D01*
G03X357200Y858695I242J-1275D01*
G01X355358D01*
G03X354429Y859086I-928J-906D01*
G03X353500Y858695I-1J-1297D01*
G01X353031D01*
X352472Y859254D01*
X352730Y859701D01*
X352820Y859718D01*
G03X353876Y860993I-242J1275D01*
G03X351280I-1298J0D01*
G03X351282Y860924I1298J3D01*
G02X350861Y860504I-399J-21D01*
G03X350807Y860505I-46J-999D01*
G01X293247D01*
X293223Y860511D01*
G03X292973Y860543I-251J-968D01*
G01X202343D01*
X202316Y860710D01*
G03X199766I-1275J-211D01*
G01X199739Y860543D01*
X186201D01*
X186174Y860710D01*
G03X183624I-1275J-211D01*
G01X183597Y860543D01*
X142943D01*
X142916Y860710D01*
G03X140366I-1275J-211D01*
G01X140339Y860543D01*
X127073D01*
X126734Y860882D01*
X126719Y860925D01*
G03X125925Y861719I-1220J-426D01*
G01X125882Y861734D01*
X124973Y862643D01*
Y1253605D01*
X132227Y1260859D01*
X132354Y1260801D01*
G03X132941Y1260672I587J1273D01*
G03X134343Y1262074I0J1402D01*
G03X134214Y1262661I-1402J0D01*
G01X134156Y1262788D01*
X143622Y1272254D01*
G03X143915Y1272961I-706J707D01*
G01Y1344263D01*
X150908Y1351256D01*
G37*
G36*
G01X471868Y1065765D02*
X472907D01*
G03X473773Y1065265I866J500D01*
G01X519459D01*
X520262Y1064462D01*
X520200Y1064334D01*
G03X520070Y1063770I1162J-565D01*
G03X521362Y1062478I1292J0D01*
G03X521926Y1062608I-1J1292D01*
G01X522054Y1062670D01*
X527473Y1057251D01*
X527482Y1057184D01*
G03X528585Y1056081I1280J177D01*
G01X528652Y1056072D01*
X529668Y1055056D01*
X529567Y1054918D01*
G03X529319Y1054157I1044J-761D01*
G03X530611Y1052865I1292J0D01*
G03X531502Y1053222I-1J1292D01*
G01X533836Y1050888D01*
G03X534543Y1050595I707J706D01*
G01X534912D01*
X534962Y1050470D01*
G03X537360I1199J482D01*
G01X537410Y1050595D01*
X552753D01*
X556627Y1046721D01*
Y910419D01*
X553970Y907762D01*
X534970D01*
G03X534263Y907469I0J-999D01*
G01X533940Y907146D01*
X533859Y907145D01*
G03X532587Y905873I20J-1292D01*
G01X532586Y905792D01*
X527265Y900471D01*
G03X526479Y900737I-785J-1026D01*
G03X525187Y899445I0J-1292D01*
G03X525453Y898659I1292J-1D01*
G01X524278Y897484D01*
X524233Y897470D01*
G03X523399Y896636I396J-1230D01*
G01X523385Y896591D01*
X521659Y894865D01*
X508773D01*
G03X508066Y894572I0J-999D01*
G01X507813Y894319D01*
X507751Y894308D01*
G03X506706Y893263I227J-1272D01*
G01X506695Y893201D01*
X501766Y888272D01*
G03X501581Y888016I707J-706D01*
G02X501072Y887827I-357J181D01*
G03X500578Y887924I-492J-1200D01*
G03X499280Y886627I0J-1298D01*
G03X499353Y886199I1298J1D01*
G01X499384Y886112D01*
X498577Y884715D01*
X498487Y884698D01*
G03X497432Y883423I243J-1275D01*
G03X500026I1297J0D01*
G03X499954Y883851I-1297J2D01*
G01X499923Y883938D01*
X500730Y885335D01*
X500820Y885352D01*
G03X500956Y885386I-246J1274D01*
G02X501473Y885003I117J-383D01*
G01Y884300D01*
G03Y882546I957J-877D01*
G01Y877883D01*
G03Y876145I956J-869D01*
G01Y875434D01*
G02X500956Y875051I-400J0D01*
G03X500578Y875108I-380J-1241D01*
G03X499280Y873810I0J-1298D01*
G03X500336Y872535I1298J0D01*
G01X500426Y872518D01*
X501234Y871119D01*
X501203Y871032D01*
G03X501132Y870606I1226J-423D01*
G03X501473Y869729I1298J0D01*
G01Y865066D01*
G03Y863328I956J-869D01*
G01Y862617D01*
G02X500956Y862234I-400J0D01*
G03X500578Y862290I-377J-1241D01*
G03X499280Y860993I0J-1298D01*
G03X500336Y859718I1298J0D01*
G01X500426Y859701D01*
X501234Y858302D01*
X501203Y858215D01*
G03X501132Y857789I1226J-423D01*
G03X501473Y856912I1298J0D01*
G01Y852249D01*
G03Y850511I956J-869D01*
G01Y849800D01*
G02X500956Y849417I-400J0D01*
G03X500578Y849474I-380J-1241D01*
G03X499280Y848176I0J-1298D01*
G03X500336Y846901I1298J0D01*
G01X500426Y846884D01*
X501233Y845486D01*
X501202Y845400D01*
G03X501130Y844971I1225J-426D01*
G03X502427Y843674I1297J0D01*
G03X503624Y844471I0J1297D01*
G02X504102Y844702I369J-154D01*
G03X504373Y844665I269J963D01*
G01X504858D01*
X504906Y844533D01*
G03X504941Y844444I1224J430D01*
G01X504980Y844356D01*
X504139Y842761D01*
X504044Y842743D01*
G03X502982Y841467I236J-1276D01*
G03X505576I1297J0D01*
G03X505465Y841994I-1297J2D01*
G01X505426Y842082D01*
X506267Y843677D01*
X506362Y843695D01*
G03X507348Y844533I-235J1276D01*
G01X507396Y844665D01*
X508558D01*
X508606Y844533D01*
G03X511048I1221J438D01*
G01X511096Y844665D01*
X512258D01*
X512306Y844533D01*
G03X512341Y844444I1224J430D01*
G01X512380Y844356D01*
X511539Y842761D01*
X511444Y842743D01*
G03X510382Y841467I236J-1276D01*
G03X512976I1297J0D01*
G03X512865Y841994I-1297J2D01*
G01X512826Y842082D01*
X513667Y843677D01*
X513762Y843695D01*
G03X514748Y844533I-235J1276D01*
G01X514796Y844665D01*
X515958D01*
X516006Y844533D01*
G03X518448I1221J438D01*
G01X518496Y844665D01*
X519658D01*
X519706Y844533D01*
G03X519741Y844444I1224J430D01*
G01X519780Y844356D01*
X518939Y842761D01*
X518844Y842743D01*
G03X517782Y841467I236J-1276D01*
G03X520376I1297J0D01*
G03X520265Y841994I-1297J2D01*
G01X520226Y842082D01*
X521067Y843677D01*
X521162Y843695D01*
G03X522148Y844533I-235J1276D01*
G01X522196Y844665D01*
X523358D01*
X523406Y844533D01*
G03X525848I1221J438D01*
G01X525896Y844665D01*
X527025D01*
X527049Y844493D01*
G03X529609I1280J178D01*
G01X529633Y844665D01*
X530719D01*
X530743Y844493D01*
G03X533313I1285J178D01*
G01X533337Y844665D01*
X534425D01*
X534449Y844493D01*
G03X537009I1280J178D01*
G01X537033Y844665D01*
X594257D01*
X594275Y844662D01*
G03X594457Y844645I184J983D01*
G01X595457D01*
G03X595639Y844662I-2J1000D01*
G01X595657Y844665D01*
X596257D01*
X596275Y844662D01*
G03X596457Y844645I184J983D01*
G01X605283D01*
X606867Y843061D01*
Y773043D01*
X600393Y766569D01*
G03X600100Y765862I706J-707D01*
G01Y760376D01*
X385789Y546065D01*
X243830D01*
X241710Y548185D01*
Y569170D01*
G03Y571810I-717J1320D01*
G01Y592900D01*
G03X242495Y594220I-717J1320D01*
G03X242089Y595247I-1502J0D01*
G02Y595793I292J273D01*
G03X242495Y596820I-1096J1027D01*
G03X241710Y598140I-1502J0D01*
G01Y603170D01*
G03Y605810I-717J1320D01*
G01Y626900D01*
G03X242495Y628220I-717J1320D01*
G03X242089Y629247I-1502J0D01*
G02Y629793I292J273D01*
G03X242495Y630820I-1096J1027D01*
G03X241977Y631955I-1502J0D01*
G02X241956Y632540I262J302D01*
G01X244118Y634702D01*
X278086D01*
X282633Y630155D01*
G03X283340Y629862I707J706D01*
G01X285376D01*
G03X287788I1206J895D01*
G01X295181D01*
G03X297629I1224J869D01*
G01X314976D01*
G03X315683Y630155I0J999D01*
G01X327817Y642289D01*
G03X327841Y642314I-709J705D01*
G01X327843Y642316D01*
X454880Y769353D01*
G03X455173Y770060I-706J707D01*
G01Y843987D01*
G03X455624Y844971I-846J983D01*
G03X455173Y845955I-1297J1D01*
G01Y846590D01*
G02X455716Y846964I400J0D01*
G03X455936Y846901I466J1211D01*
G01X456026Y846884D01*
X456833Y845486D01*
X456802Y845400D01*
G03X456730Y844971I1225J-426D01*
G03X459324I1297J0D01*
G03X458269Y846246I-1298J0D01*
G01X458179Y846263D01*
X457372Y847661D01*
X457403Y847747D01*
G03X457476Y848176I-1224J429D01*
G03X456178Y849474I-1298J0D01*
G03X455716Y849388I3J-1298D01*
G02X455173Y849762I-143J374D01*
G01Y850403D01*
G03Y852357I-844J977D01*
G01Y856804D01*
G03Y858774I-844J985D01*
G01Y859407D01*
G02X455716Y859781I400J0D01*
G03X455936Y859718I466J1211D01*
G01X456026Y859701D01*
X456834Y858302D01*
X456803Y858215D01*
G03X456732Y857789I1226J-423D01*
G03X459326I1297J0D01*
G03X458268Y859064I-1297J0D01*
G01X458178Y859081D01*
X457372Y860478D01*
X457403Y860564D01*
G03X457476Y860993I-1224J429D01*
G03X456178Y862290I-1297J0D01*
G03X455716Y862205I0J-1298D01*
G02X455173Y862579I-143J374D01*
G01Y863219D01*
G03Y865175I-844J978D01*
G01Y869621D01*
G03Y871591I-844J985D01*
G01Y872224D01*
G02X455716Y872598I400J0D01*
G03X455936Y872535I466J1211D01*
G01X456026Y872518D01*
X456834Y871119D01*
X456803Y871032D01*
G03X456732Y870606I1226J-423D01*
G03X459326I1297J0D01*
G03X458268Y871881I-1297J0D01*
G01X458178Y871898D01*
X457372Y873295D01*
X457403Y873381D01*
G03X457476Y873810I-1224J429D01*
G03X456178Y875108I-1298J0D01*
G03X455716Y875022I3J-1298D01*
G02X455173Y875396I-143J374D01*
G01Y876036D01*
G03Y877992I-844J978D01*
G01Y882438D01*
G03X455626Y883423I-844J985D01*
G03X455554Y883851I-1297J2D01*
G01X455523Y883938D01*
X456330Y885335D01*
X456420Y885352D01*
G03X457476Y886627I-242J1275D01*
G03X456178Y887924I-1297J0D01*
G03X455716Y887839I0J-1298D01*
G02X455173Y888213I-143J374D01*
G01Y888854D01*
G03Y890810I-844J978D01*
G01Y895262D01*
G03X455621Y896240I-844J978D01*
G03X455602Y896460I-1292J-1D01*
G01X455584Y896562D01*
X463581Y904559D01*
X463656Y904563D01*
G03X464868Y905775I-78J1290D01*
G01X464872Y905850D01*
X470225Y911203D01*
X470357Y911130D01*
G03X470980Y910970I623J1133D01*
G03X472272Y912262I0J1292D01*
G03X472112Y912885I-1293J0D01*
G01X472039Y913017D01*
X473275Y914253D01*
X473313Y914268D01*
G03X474026Y914981I-485J1198D01*
G01X474041Y915019D01*
X479708Y920686D01*
X479825Y920648D01*
G03X480229Y920583I405J1227D01*
G03X481521Y921875I0J1292D01*
G03X481456Y922279I-1292J-1D01*
G01X481418Y922396D01*
X489237Y930215D01*
X489333Y930204D01*
G03X489478Y930196I144J1284D01*
G03X490770Y931488I0J1292D01*
G03X490762Y931633I-1292J1D01*
G01X490751Y931729D01*
X495985Y936963D01*
G03X496879Y936604I894J934D01*
G03X498171Y937896I0J1292D01*
G03X497921Y938660I-1292J0D01*
G01X497820Y938798D01*
X498832Y939810D01*
X498899Y939819D01*
G03X500010Y940930I-170J1281D01*
G01X500019Y940997D01*
X501664Y942642D01*
G03X501957Y943349I-706J707D01*
G01Y1002008D01*
G03Y1003768I-946J880D01*
G01Y1008417D01*
G03Y1010177I-946J880D01*
G01Y1014824D01*
G03Y1016586I-945J881D01*
G01Y1021234D01*
G03Y1022994I-946J880D01*
G01Y1027643D01*
G03X502303Y1028523I-946J880D01*
G03X501011Y1029815I-1292J0D01*
G03X500461Y1029692I0J-1291D01*
G01X500334Y1029632D01*
X497594Y1032372D01*
G03X496887Y1032665I-707J-706D01*
G01X496349D01*
G03X494573I-888J-937D01*
G01X492650D01*
G03X490874I-888J-937D01*
G01X488950D01*
G03X487174I-888J-937D01*
G01X485249D01*
G03X483473I-888J-937D01*
G01X481550D01*
G03X480662Y1033019I-888J-937D01*
G03X479446Y1032164I0J-1292D01*
G03X479119Y1032019I26J-500D01*
G01X478766Y1031666D01*
X478765D01*
X477772Y1030673D01*
Y1029852D01*
G03Y1027194I1039J-1329D01*
G01Y1025672D01*
X477126Y1025027D01*
X475780Y1026372D01*
G03X475073Y1026665I-707J-706D01*
G01X468374D01*
X467673Y1027366D01*
Y1035610D01*
X467806Y1035657D01*
G03Y1038091I-434J1217D01*
G01X467673Y1038138D01*
Y1063058D01*
X470380Y1065765D01*
X470954D01*
X470986Y1065754D01*
G03X471411Y1065682I425J1220D01*
G03X471836Y1065754I0J1292D01*
G01X471868Y1065765D01*
G37*
G36*
G01X478773Y1030258D02*
X479258Y1030743D01*
G02X479806Y1030760I283J-283D01*
G03X480662Y1030435I857J967D01*
G03X481398Y1030665I0J1293D01*
G01X483625D01*
G03X485097I736J1063D01*
G01X487326D01*
G03X488798I736J1063D01*
G01X491026D01*
G03X492498I736J1063D01*
G01X494725D01*
G03X495461Y1030435I736J1063D01*
G03X496150Y1030634I0J1292D01*
G01X496199Y1030665D01*
X496473D01*
X499957Y1027181D01*
Y1022861D01*
G03Y1021367I1053J-747D01*
G01Y1016451D01*
G03Y1014959I1056J-746D01*
G01Y1010044D01*
G03Y1008550I1053J-747D01*
G01Y1003635D01*
G03Y1002141I1053J-747D01*
G01Y983889D01*
G03Y981623I621J-1133D01*
G01Y977480D01*
G03Y975214I621J-1133D01*
G01Y971072D01*
G03Y968806I621J-1133D01*
G01Y964662D01*
G03Y962398I621J-1132D01*
G01Y958255D01*
G03Y955989I621J-1133D01*
G01Y951846D01*
G03Y949580I621J-1133D01*
G01Y945437D01*
G03X499286Y944304I621J-1133D01*
G03X499625Y943431I1292J-1D01*
G01X498579Y942385D01*
X498516Y942374D01*
G03X497455Y941313I213J-1274D01*
G01X497444Y941250D01*
X491999Y935805D01*
X491872Y935863D01*
G03X491329Y935983I-544J-1172D01*
G03X490037Y934691I0J-1292D01*
G03X490157Y934148I1292J1D01*
G01X490215Y934021D01*
X488748Y932554D01*
X488734Y932545D01*
G03X488412Y932218I745J-1056D01*
G01X482500Y926306D01*
X482390Y926333D01*
G03X482078Y926371I-311J-1254D01*
G03X480786Y925079I0J-1292D01*
G03X480824Y924767I1292J-1D01*
G01X480851Y924657D01*
X472949Y916755D01*
X472863Y916758D01*
X472828D01*
G03X471536Y915466I0J-1292D01*
G01Y915431D01*
X471539Y915345D01*
X466256Y910062D01*
X466121Y910148D01*
G03X465429Y910349I-692J-1091D01*
G03X464137Y909057I0J-1292D01*
G03X464338Y908365I1292J0D01*
G01X464424Y908230D01*
X463313Y907119D01*
X463259Y907105D01*
G03X462326Y906172I319J-1252D01*
G01X462312Y906118D01*
X456786Y900592D01*
X456664Y900642D01*
G03X456178Y900737I-486J-1196D01*
G03X454886Y899445I0J-1292D01*
G03X454981Y898959I1291J0D01*
G01X455031Y898837D01*
X453466Y897272D01*
G03X453251Y896952I707J-707D01*
G03X453037Y896240I1077J-712D01*
G03X453155Y895701I1292J0D01*
G01X453173Y895661D01*
Y890411D01*
X453155Y890371D01*
G03X453037Y889832I1174J-539D01*
G03X453155Y889293I1292J0D01*
G01X453173Y889253D01*
Y884014D01*
X453154Y883974D01*
G03Y882872I1183J-551D01*
G01X453173Y882832D01*
Y881433D01*
X452939D01*
X452907Y881444D01*
G03X452719Y881494I-427J-1225D01*
G01X452629Y881511D01*
X451823Y882908D01*
X451854Y882994D01*
G03X451926Y883423I-1225J426D01*
G03X449332I-1297J0D01*
G03X450387Y882148I1298J0D01*
G01X450477Y882131D01*
X451284Y880733D01*
X451254Y880646D01*
G03X451182Y880219I1225J-426D01*
G03X452479Y878922I1297J0D01*
G03X452704Y878941I4J1297D01*
G02X453173Y878547I69J-394D01*
G01Y877593D01*
X453155Y877553D01*
G03X453037Y877014I1174J-539D01*
G03X453155Y876475I1292J0D01*
G01X453173Y876435D01*
Y871197D01*
X453154Y871157D01*
G03X453032Y870606I1183J-551D01*
G03X453104Y870178I1297J-2D01*
G01X453135Y870091D01*
X452328Y868693D01*
X452238Y868676D01*
G03X451180Y867401I239J-1275D01*
G03X452478Y866104I1297J0D01*
G03X452704Y866123I5J1297D01*
G02X453173Y865729I69J-394D01*
G01Y864776D01*
X453155Y864736D01*
G03X453037Y864197I1174J-539D01*
G03X453155Y863658I1292J0D01*
G01X453173Y863618D01*
Y858380D01*
X453154Y858340D01*
G03X453032Y857789I1183J-551D01*
G03X453104Y857361I1297J-2D01*
G01X453135Y857274D01*
X452328Y855876D01*
X452238Y855859D01*
G03X451180Y854584I239J-1275D01*
G03X452478Y853286I1298J0D01*
G03X452704Y853306I-1J1298D01*
G02X453173Y852912I69J-394D01*
G01Y851961D01*
X453155Y851921D01*
G03X453036Y851380I1173J-542D01*
G03X453155Y850839I1292J1D01*
G01X453173Y850799D01*
Y845566D01*
X453154Y845525D01*
G03X453030Y844971I1173J-553D01*
G03X453141Y844444I1297J-2D01*
G01X453180Y844356D01*
X452339Y842761D01*
X452244Y842743D01*
G03X451182Y841467I236J-1276D01*
G03X452479Y840170I1297J0D01*
G03X452704Y840189I4J1297D01*
G02X453173Y839795I69J-394D01*
G01Y770474D01*
X322491Y639792D01*
G03X322467Y639767I709J-705D01*
G01X322465Y639765D01*
X314562Y631862D01*
X297394D01*
G03X295416I-989J-1129D01*
G01X287599D01*
G03X285565I-1017J-1104D01*
G01X283754D01*
X279207Y636409D01*
G03X278500Y636702I-707J-706D01*
G01X243870D01*
X242452Y638120D01*
X242471Y638223D01*
G03X242495Y638490I-1478J267D01*
G03X241710Y639810I-1502J0D01*
G01Y659248D01*
X241716Y659272D01*
G03X241747Y659519I-969J247D01*
G03X241716Y659766I-1000J0D01*
G01X241710Y659790D01*
Y664573D01*
X241711Y664585D01*
G03X241718Y664700I-993J118D01*
G01Y664812D01*
G03X241711Y664927I-1000J-3D01*
G01X241710Y664939D01*
Y668858D01*
X243314Y670462D01*
X258600D01*
G03X259307Y670755I0J999D01*
G01X268414Y679862D01*
X295197D01*
G03X295904Y680155I0J999D01*
G01X304130Y688381D01*
G03X304336Y688680I-707J707D01*
G01X339262Y766940D01*
G03X339315Y767089I-913J409D01*
G01X341987Y777045D01*
X342076Y777083D01*
G03X342919Y778362I-549J1279D01*
G03X342643Y779194I-1392J0D01*
G01X342585Y779272D01*
X348809Y802461D01*
X348983Y802439D01*
G03X350098Y802368I1113J8683D01*
G03X358852Y811122I0J8754D01*
G03X358134Y814595I-8754J1D01*
G01X358065Y814756D01*
X397737Y838669D01*
G03X398221Y839525I-515J856D01*
G01Y841110D01*
X398228Y841135D01*
G03X398271Y841467I-1249J331D01*
G03X398228Y841799I-1292J1D01*
G01X398221Y841824D01*
Y843286D01*
G02X398670Y843683I400J0D01*
G03X398827Y843674I153J1288D01*
G03X400124Y844971I0J1297D01*
G03X399069Y846246I-1298J0D01*
G01X398979Y846263D01*
X398221Y847577D01*
Y847803D01*
X398228Y847829D01*
G03X398276Y848176I-1250J350D01*
G03X398228Y848523I-1298J-3D01*
G01X398221Y848549D01*
Y854227D01*
X398228Y854252D01*
G03X398271Y854584I-1249J331D01*
G03X398228Y854916I-1292J1D01*
G01X398221Y854941D01*
Y856548D01*
X398449D01*
X398475Y856541D01*
G03X398587Y856514I360J1247D01*
G01X398677Y856497D01*
X399484Y855099D01*
X399453Y855013D01*
G03X399380Y854584I1224J-429D01*
G03X401976I1298J0D01*
G03X400920Y855859I-1298J0D01*
G01X400830Y855876D01*
X400023Y857274D01*
X400054Y857360D01*
G03X400126Y857789I-1225J426D01*
G03X398829Y859086I-1297J0D01*
G03X398670Y859077I-6J-1297D01*
G02X398221Y859474I-49J397D01*
G01Y860620D01*
X398228Y860646D01*
G03X398276Y860993I-1250J350D01*
G03X398228Y861340I-1298J-3D01*
G01X398221Y861366D01*
Y862518D01*
G02X398670Y862915I400J0D01*
G03X398829Y862905I160J1282D01*
G03X400121Y864197I0J1292D01*
G03X400056Y864600I-1292J-2D01*
G01X400018Y864717D01*
X404974Y869673D01*
G03X405003Y869703I-704J710D01*
G02X405294Y869706I147J-135D01*
G03X405987Y869331I935J900D01*
G01X406077Y869314D01*
X406884Y867916D01*
X406853Y867830D01*
G03X406780Y867401I1224J-429D01*
G03X409376I1298J0D01*
G03X408320Y868676I-1298J0D01*
G01X408230Y868693D01*
X407423Y870091D01*
X407454Y870177D01*
G03X407526Y870606I-1225J426D01*
G03X406229Y871904I-1298J0D01*
G03X405799Y871830I2J-1298D01*
G02X405267Y872208I-132J378D01*
G01Y872865D01*
G03X405676Y873810I-889J946D01*
G03X405267Y874755I-1298J-1D01*
G01Y879281D01*
G03Y881157I-887J938D01*
G01Y881821D01*
G02X405799Y882199I400J0D01*
G03X405987Y882148I433J1223D01*
G01X406077Y882131D01*
X406883Y880734D01*
X406853Y880647D01*
G03X406780Y880219I1225J-429D01*
G03X409376I1298J0D01*
G03X408319Y881494I-1297J0D01*
G01X408229Y881511D01*
X407423Y882908D01*
X407454Y882994D01*
G03X407526Y883423I-1225J426D01*
G03X406229Y884720I-1297J0D01*
G03X405799Y884647I-1J-1297D01*
G02X405267Y885025I-132J378D01*
G01Y885682D01*
G03X405676Y886627I-889J946D01*
G03X405267Y887572I-1298J-1D01*
G01Y892098D01*
G03Y893974I-890J938D01*
G01Y898507D01*
G03Y900383I-890J938D01*
G01Y901525D01*
G03X404974Y902232I-999J0D01*
G01X401869Y905337D01*
X401907Y905454D01*
G03X401970Y905853I-1229J399D01*
G03X400678Y907145I-1292J0D01*
G03X400279Y907082I0J-1292D01*
G01X400162Y907044D01*
X394487Y912719D01*
X394472Y912756D01*
G03X393772Y913456I-1194J-494D01*
G01X393735Y913471D01*
X392491Y914715D01*
X392563Y914846D01*
G03X392721Y915466I-1134J619D01*
G03X391429Y916758I-1292J0D01*
G03X390809Y916600I-1J-1292D01*
G01X390678Y916528D01*
X385323Y921883D01*
X385318Y921958D01*
G03X384112Y923164I-1289J-83D01*
G01X384037Y923169D01*
X381837Y925369D01*
Y998967D01*
G03Y1000401I-1076J717D01*
G01Y1005376D01*
G03Y1006810I-1076J717D01*
G01Y1011784D01*
G03Y1013218I-1076J717D01*
G01Y1018193D01*
G03Y1019627I-1076J717D01*
G01Y1024604D01*
G03X382052Y1025318I-1078J714D01*
G03X382050Y1025390I-1292J0D01*
G01X382045Y1025479D01*
X383431Y1026865D01*
X403259D01*
X403808Y1026316D01*
X403823Y1026283D01*
G03X404460Y1025646I1175J538D01*
G01X404493Y1025631D01*
X404873Y1025251D01*
Y1023724D01*
X404715Y1023690D01*
G03Y1021164I271J-1263D01*
G01X404873Y1021130D01*
Y1017969D01*
X404013Y1017109D01*
G03X403720Y1016402I706J-707D01*
G01Y1013495D01*
G03X404013Y1012788I999J0D01*
G01X404873Y1011928D01*
Y1008406D01*
X404747Y1008356D01*
G03X403935Y1007156I481J-1200D01*
G03X404284Y1006273I1292J0D01*
G02X404285Y1005728I-292J-273D01*
G03X403939Y1004848I946J-880D01*
G03X404748Y1003650I1292J0D01*
G01X404873Y1003599D01*
Y996551D01*
X404730Y996509D01*
G03X403809Y995271I372J-1238D01*
G03X404153Y994393I1292J0D01*
G02Y993849I-293J-272D01*
G03X403809Y992971I948J-878D01*
G03X404730Y991733I1293J0D01*
G01X404873Y991691D01*
Y978365D01*
G03X405166Y977658I999J0D01*
G01X407066Y975758D01*
G03X407773Y975465I707J706D01*
G01X410959D01*
X412873Y973551D01*
Y969679D01*
X412159Y968965D01*
X407773D01*
G03X407066Y968672I0J-999D01*
G01X405523Y967129D01*
X405415Y967154D01*
G03X405122Y967188I-294J-1258D01*
G03X403830Y965896I0J-1292D01*
G03X404174Y965018I1292J0D01*
G02Y964474I-293J-272D01*
G03X403830Y963596I948J-878D01*
G03X404560Y962433I1291J0D01*
G01X404673Y962378D01*
Y949748D01*
X404563Y949693D01*
G03X403853Y948539I583J-1154D01*
G03X404197Y947661I1292J0D01*
G02Y947117I-293J-272D01*
G03X403853Y946239I948J-878D01*
G03X404563Y945085I1293J0D01*
G01X404673Y945030D01*
Y943300D01*
G03X403997Y942164I617J-1136D01*
G03X405289Y940872I1292J0D01*
G03X405781Y940969I1J1292D01*
G01X405904Y941020D01*
X410266Y936658D01*
G03X410973Y936365I707J706D01*
G01X426577D01*
X426610Y936206D01*
G03X429140I1265J264D01*
G01X429173Y936365D01*
X454073D01*
G03X454780Y936658I0J999D01*
G01X456780Y938658D01*
G03X457073Y939365I-706J707D01*
G01Y944551D01*
X463987Y951465D01*
X474273D01*
G03X474980Y951758I0J999D01*
G01X477180Y953958D01*
G03X477473Y954665I-706J707D01*
G01Y957965D01*
G03X477180Y958672I-999J0D01*
G01X476080Y959772D01*
G03X475373Y960065I-707J-706D01*
G01X473187D01*
X468000Y965252D01*
Y971378D01*
X476087Y979465D01*
X476184Y979454D01*
G03X476335Y979445I152J1283D01*
G03X477627Y980737I0J1292D01*
G03X477599Y981002I-1292J-3D01*
G03X477773Y981565I-825J563D01*
G01Y1023966D01*
G03X477760Y1024127I-1000J0D01*
G01X477743Y1024228D01*
X478627Y1025111D01*
G03X478773Y1025463I-354J353D01*
G01Y1030258D01*
G37*
G36*
G01X380887Y1054265D02*
X403510D01*
X403521Y1054077D01*
G03X404811Y1052865I1290J81D01*
G03X405165Y1052914I2J1292D01*
G01X405278Y1052946D01*
X410073Y1048151D01*
Y1045811D01*
X409939Y1045765D01*
G03Y1043323I423J-1221D01*
G01X410073Y1043277D01*
Y1031565D01*
G03X410306Y1030924I1000J1D01*
G01X410423Y1030783D01*
X409886Y1030246D01*
G03X409740Y1029894I354J-353D01*
G01Y1028200D01*
G03X409886Y1027848I500J1D01*
G01X411423Y1026311D01*
G03X411775Y1026165I353J354D01*
G01X412987D01*
G02X413383Y1025708I0J-400D01*
G03X413373Y1025565I990J-141D01*
G01Y1012179D01*
X411959Y1010765D01*
X408158D01*
G03X408131Y1010793I-733J-680D01*
G01X406873Y1012051D01*
Y1012342D01*
G03X406580Y1013049I-999J0D01*
G01X405720Y1013909D01*
Y1015988D01*
X406580Y1016848D01*
G03X406873Y1017555I-706J707D01*
G01Y1025665D01*
G03X406580Y1026372I-999J0D01*
G01X406284Y1026668D01*
X406288Y1026757D01*
G03X406290Y1026821I-1290J72D01*
G03X404998Y1028113I-1292J0D01*
G03X404934Y1028111I8J-1292D01*
G01X404845Y1028107D01*
X404380Y1028572D01*
G03X403673Y1028865I-707J-706D01*
G01X402364D01*
X402315Y1028992D01*
G03X399907I-1204J-469D01*
G01X399858Y1028865D01*
X398664D01*
X398615Y1028992D01*
G03X396207I-1204J-469D01*
G01X396158Y1028865D01*
X394964D01*
X394915Y1028992D01*
G03X392507I-1204J-469D01*
G01X392458Y1028865D01*
X391264D01*
X391215Y1028992D01*
G03X388807I-1204J-469D01*
G01X388758Y1028865D01*
X387564D01*
X387515Y1028992D01*
G03X385107I-1204J-469D01*
G01X385058Y1028865D01*
X383864D01*
X383815Y1028992D01*
G03X382611Y1029815I-1204J-469D01*
G03X381319Y1028523I0J-1292D01*
G03X381465Y1027925I1292J-1D01*
G01X381533Y1027795D01*
X380239Y1026501D01*
X380207Y1026486D01*
G03X379468Y1025318I554J-1168D01*
G03X379837Y1024414I1292J0D01*
G01Y1019812D01*
G03Y1018008I925J-902D01*
G01Y1013403D01*
G03Y1011599I925J-902D01*
G01Y1006995D01*
G03Y1005191I925J-902D01*
G01Y1000586D01*
G03Y998782I925J-902D01*
G01Y980753D01*
X379730Y980697D01*
G03Y978407I599J-1145D01*
G01X379837Y978351D01*
Y974344D01*
X379730Y974288D01*
G03Y971998I598J-1145D01*
G01X379837Y971942D01*
Y967936D01*
X379730Y967880D01*
G03Y965590I599J-1145D01*
G01X379837Y965534D01*
Y961527D01*
X379730Y961471D01*
G03Y959181I599J-1145D01*
G01X379837Y959125D01*
Y955118D01*
X379730Y955062D01*
G03Y952772I599J-1145D01*
G01X379837Y952716D01*
Y948710D01*
X379730Y948654D01*
G03Y946364I599J-1145D01*
G01X379837Y946308D01*
Y942301D01*
X379730Y942245D01*
G03Y939955I599J-1145D01*
G01X379837Y939899D01*
Y935892D01*
X379730Y935836D01*
G03Y933546I599J-1145D01*
G01X379837Y933490D01*
Y929484D01*
X379730Y929428D01*
G03Y927138I599J-1145D01*
G01X379837Y927082D01*
Y924955D01*
G03X380130Y924248I999J0D01*
G01X382762Y921616D01*
X382775Y921562D01*
G03X383716Y920621I1254J313D01*
G01X383770Y920608D01*
X384877Y919501D01*
X384790Y919366D01*
G03X384587Y918670I1089J-695D01*
G03X385879Y917378I1292J0D01*
G03X386575Y917581I1J1292D01*
G01X386710Y917668D01*
X391989Y912389D01*
X391987Y912302D01*
G03X391986Y912262I1291J-52D01*
G03X393278Y910970I1292J0D01*
G03X393318Y910971I-12J1292D01*
G01X393405Y910973D01*
X401304Y903074D01*
X401276Y902964D01*
G03X401237Y902649I1253J-315D01*
G03X402529Y901357I1292J0D01*
G03X402844Y901396I0J1292D01*
G01X402954Y901424D01*
X403267Y901111D01*
Y900106D01*
X403243Y900062D01*
G03Y898828I1134J-617D01*
G01X403267Y898784D01*
Y893697D01*
X403243Y893653D01*
G03Y892419I1134J-617D01*
G01X403267Y892375D01*
Y887299D01*
X403242Y887254D01*
G03X403080Y886627I1136J-628D01*
G03X403153Y886199I1298J1D01*
G01X403184Y886112D01*
X402377Y884715D01*
X402287Y884698D01*
G03X401232Y883423I243J-1275D01*
G03X402529Y882126I1297J0D01*
G03X402787Y882151I4J1297D01*
G02X403267Y881760I80J-392D01*
G01Y880879D01*
X403243Y880834D01*
G03X403087Y880219I1136J-615D01*
G03X403243Y879604I1292J0D01*
G01X403267Y879559D01*
Y874482D01*
X403242Y874437D01*
G03X403080Y873810I1136J-628D01*
G03X403153Y873382I1298J1D01*
G01X403184Y873295D01*
X402377Y871898D01*
X402287Y871881D01*
G03X401232Y870606I243J-1275D01*
G03X401606Y869695I1297J0D01*
G02X401604Y869131I-285J-281D01*
G01X401105Y868632D01*
X400995Y868659D01*
G03X400920Y868676I-324J-1256D01*
G01X400830Y868693D01*
X400023Y870091D01*
X400054Y870177D01*
G03X400126Y870606I-1225J426D01*
G03X397532I-1297J0D01*
G03X398587Y869331I1298J0D01*
G01X398677Y869314D01*
X399484Y867916D01*
X399453Y867830D01*
G03X399380Y867401I1224J-429D01*
G03X399420Y867084I1298J3D01*
G01X399447Y866974D01*
X396514Y864041D01*
G03X396221Y863334I706J-707D01*
G01Y862047D01*
G03X395680Y860993I756J-1054D01*
G03X395753Y860565I1298J1D01*
G01X395784Y860478D01*
X394977Y859081D01*
X394887Y859064D01*
G03X393832Y857789I243J-1275D01*
G03X395129Y856492I1297J0D01*
G03X395658Y856604I0J1305D01*
G02X396221Y856239I163J-365D01*
G01Y855630D01*
G03Y853538I757J-1046D01*
G01Y849230D01*
G03Y847122I756J-1054D01*
G01Y846520D01*
G02X395657Y846155I-400J0D01*
G03X395127Y846268I-530J-1184D01*
G03X393830Y844971I0J-1297D01*
G03X393941Y844444I1297J-2D01*
G01X393980Y844356D01*
X393139Y842761D01*
X393044Y842743D01*
G03X391982Y841467I236J-1276D01*
G03X394576I1297J0D01*
G03X394465Y841994I-1297J2D01*
G01X394426Y842082D01*
X395267Y843677D01*
X395362Y843695D01*
G03X395657Y843787I-236J1276D01*
G02X396221Y843422I164J-365D01*
G01Y842513D01*
G03X395687Y841467I757J-1046D01*
G03X396149Y840477I1292J0D01*
G01X396221Y840417D01*
Y840090D01*
X357033Y816468D01*
X356924Y816604D01*
G03X350098Y819876I-6825J-5482D01*
G03X341344Y811122I0J-8754D01*
G03X346717Y803047I8754J0D01*
G01X346878Y802979D01*
X340532Y779337D01*
X340499Y779301D01*
G03X340135Y778362I1029J-939D01*
G03X340167Y778064I1392J-1D01*
G01X340178Y778016D01*
X337404Y767683D01*
X302585Y689664D01*
X294783Y681862D01*
X268000D01*
G03X267293Y681569I0J-999D01*
G01X258186Y672462D01*
X243514D01*
X241710Y674266D01*
Y856636D01*
X243617Y858543D01*
X292737D01*
X292761Y858537D01*
G03X293011Y858505I251J968D01*
G01X349061D01*
G02X349454Y858031I0J-400D01*
G03X349432Y857789I1275J-238D01*
G03X350729Y856492I1297J0D01*
G03X351690Y856917I1J1297D01*
G02X351968Y856935I148J-134D01*
G03X352617Y856695I650J759D01*
G01X353731D01*
G03X354187Y856514I698J1094D01*
G01X354277Y856497D01*
X355084Y855099D01*
X355053Y855013D01*
G03X354980Y854584I1224J-429D01*
G03X357576I1298J0D01*
G03X356520Y855859I-1298J0D01*
G01X356430Y855876D01*
X356303Y856095D01*
G02X356650Y856695I347J200D01*
G01X357431D01*
G03X358129Y856492I697J1094D01*
G03X358827Y856695I1J1297D01*
G01X361131D01*
G03X361587Y856514I698J1094D01*
G01X361677Y856497D01*
X362484Y855099D01*
X362453Y855013D01*
G03X362380Y854584I1224J-429D01*
G03X364976I1298J0D01*
G03X363920Y855859I-1298J0D01*
G01X363830Y855876D01*
X363703Y856095D01*
G02X364050Y856695I347J200D01*
G01X364831D01*
G03X365529Y856492I697J1094D01*
G03X366227Y856695I1J1297D01*
G01X368531D01*
G03X368987Y856514I698J1094D01*
G01X369077Y856497D01*
X369884Y855099D01*
X369853Y855013D01*
G03X369780Y854584I1224J-429D01*
G03X372376I1298J0D01*
G03X371320Y855859I-1298J0D01*
G01X371230Y855876D01*
X371103Y856095D01*
G02X371450Y856695I347J200D01*
G01X372231D01*
G03X372929Y856492I697J1094D01*
G03X373852Y856877I0J1299D01*
G03X373984Y856988I-575J818D01*
G01X374691Y857695D01*
G02X375364Y857501I283J-283D01*
G03X376387Y856514I1265J288D01*
G01X376477Y856497D01*
X377284Y855099D01*
X377253Y855013D01*
G03X377180Y854584I1224J-429D01*
G03X379776I1298J0D01*
G03X378720Y855859I-1298J0D01*
G01X378630Y855876D01*
X377823Y857274D01*
X377854Y857360D01*
G03X377926Y857789I-1225J426D01*
G03X376629Y859086I-1297J0D01*
G03X376020Y858935I-2J-1297D01*
G02X375727Y859117I-93J177D01*
G01Y860108D01*
G03X376076Y860993I-948J885D01*
G03X375677Y861929I-1297J0D01*
G01Y864221D01*
X377764Y866308D01*
X377893Y866243D01*
G03X378478Y866104I584J1158D01*
G03X379776Y867401I0J1298D01*
G03X379636Y867986I-1298J-1D01*
G01X379571Y868115D01*
X380893Y869437D01*
X380921Y869451D01*
G03X381484Y870014I-592J1155D01*
G01X381498Y870042D01*
X382071Y870615D01*
G02X382748Y870397I282J-283D01*
G03X383787Y869331I1281J209D01*
G01X383877Y869314D01*
X384684Y867916D01*
X384653Y867830D01*
G03X384580Y867401I1224J-429D01*
G03X387176I1298J0D01*
G03X386120Y868676I-1298J0D01*
G01X386030Y868693D01*
X385223Y870091D01*
X385254Y870177D01*
G03X385326Y870606I-1225J426D01*
G03X384029Y871904I-1298J0D01*
G03X383790Y871881I4J-1298D01*
G02X383317Y872275I-73J393D01*
G01Y873187D01*
X383338Y873229D01*
G03X383476Y873810I-1160J582D01*
G03X383338Y874391I-1298J-1D01*
G01X383317Y874433D01*
Y879605D01*
X383338Y879647D01*
G03X383471Y880219I-1159J571D01*
G03X383338Y880791I-1292J1D01*
G01X383317Y880833D01*
Y882216D01*
X383552D01*
X383585Y882204D01*
G03X383787Y882148I447J1218D01*
G01X383877Y882131D01*
X384683Y880734D01*
X384653Y880647D01*
G03X384580Y880219I1225J-429D01*
G03X387176I1298J0D01*
G03X386119Y881494I-1297J0D01*
G01X386029Y881511D01*
X385223Y882908D01*
X385254Y882994D01*
G03X385326Y883423I-1225J426D01*
G03X384029Y884720I-1297J0D01*
G03X383790Y884698I-1J-1297D01*
G02X383317Y885092I-73J393D01*
G01Y886004D01*
X383338Y886046D01*
G03X383476Y886627I-1160J582D01*
G03X383338Y887208I-1298J-1D01*
G01X383317Y887250D01*
Y890099D01*
G03X383024Y890806I-999J0D01*
G01X377890Y895940D01*
X377906Y896041D01*
G03X377921Y896240I-1277J196D01*
G03X376629Y897532I-1292J0D01*
G03X376430Y897517I-3J-1292D01*
G01X376329Y897501D01*
X368545Y905285D01*
X368590Y905405D01*
G03X368670Y905853I-1212J448D01*
G03X367378Y907145I-1292J0D01*
G03X366930Y907065I0J-1292D01*
G01X366810Y907020D01*
X361224Y912606D01*
X361210Y912652D01*
G03X360368Y913494I-1232J-390D01*
G01X360322Y913508D01*
X359159Y914671D01*
X359239Y914805D01*
G03X359421Y915466I-1109J661D01*
G03X358129Y916758I-1292J0D01*
G03X357468Y916576I0J-1291D01*
G01X357334Y916496D01*
X353473Y920357D01*
Y924147D01*
G03Y926011I-895J932D01*
G01Y930556D01*
G03Y932420I-895J932D01*
G01Y936964D01*
G03Y938828I-895J932D01*
G01Y943372D01*
G03Y945236I-895J932D01*
G01Y949781D01*
G03Y951645I-895J932D01*
G01Y956190D01*
G03Y958054I-895J932D01*
G01Y962598D01*
G03Y964462I-895J932D01*
G01Y969007D01*
G03Y970871I-895J932D01*
G01Y975414D01*
G03Y977280I-895J933D01*
G01Y981824D01*
G03Y983688I-895J932D01*
G01Y1001675D01*
X353584Y1001730D01*
G03Y1004046I-573J1158D01*
G01X353473Y1004101D01*
Y1008084D01*
X353584Y1008139D01*
G03Y1010455I-573J1158D01*
G01X353473Y1010510D01*
Y1014492D01*
X353584Y1014547D01*
G03Y1016863I-573J1158D01*
G01X353473Y1016918D01*
Y1020901D01*
X353584Y1020956D01*
G03Y1023272I-573J1158D01*
G01X353473Y1023327D01*
Y1026851D01*
X360266Y1033644D01*
X360354Y1033640D01*
G03X360411Y1033639I51J1291D01*
G03X361703Y1034931I0J1292D01*
G03X361702Y1034988I-1292J6D01*
G01X361698Y1035076D01*
X366969Y1040347D01*
X367105Y1040258D01*
G03X367811Y1040048I706J1082D01*
G03X369103Y1041340I0J1292D01*
G03X368893Y1042046I-1292J0D01*
G01X368804Y1042182D01*
X369894Y1043272D01*
X369950Y1043284D01*
G03X370922Y1044256I-288J1260D01*
G01X370934Y1044312D01*
X376436Y1049814D01*
X376560Y1049762D01*
G03X377062Y1049660I503J1190D01*
G03X378354Y1050952I0J1292D01*
G03X378252Y1051454I-1292J-1D01*
G01X378200Y1051578D01*
X380887Y1054265D01*
G37*
G36*
G01X288564Y1315788D02*
X299040D01*
X314150Y1300678D01*
G03X314857Y1300385I707J706D01*
G01X328693D01*
X333073Y1296005D01*
Y1288865D01*
G03X333366Y1288158I999J0D01*
G01X336966Y1284558D01*
G03X337673Y1284265I707J706D01*
G01X359659D01*
X364273Y1279651D01*
Y1273465D01*
G03X364566Y1272758I999J0D01*
G01X366466Y1270858D01*
G03X367173Y1270565I707J706D01*
G01X492373D01*
G03X493080Y1270858I0J999D01*
G01X495680Y1273458D01*
G03X495973Y1274165I-706J707D01*
G01Y1279051D01*
X501387Y1284465D01*
X517473D01*
G03X518180Y1284758I0J999D01*
G01X527580Y1294158D01*
G03X527873Y1294865I-706J707D01*
G01Y1303651D01*
X528987Y1304765D01*
X567926D01*
G03X568015Y1304663I796J605D01*
G01X569397Y1303281D01*
Y1167749D01*
X540722Y1139074D01*
X526887D01*
X526208Y1140359D01*
X526247Y1140448D01*
G03X526358Y1140973I-1186J525D01*
G03X523764I-1297J0D01*
G03X524826Y1139697I1298J0D01*
G01X524921Y1139679D01*
X525086Y1139367D01*
G02X524909Y1139074I-177J-93D01*
G01X519487D01*
X518808Y1140359D01*
X518847Y1140448D01*
G03X518958Y1140973I-1186J525D01*
G03X516364I-1297J0D01*
G03X517426Y1139697I1298J0D01*
G01X517521Y1139679D01*
X517686Y1139367D01*
G02X517509Y1139074I-177J-93D01*
G01X512087D01*
X511408Y1140359D01*
X511447Y1140448D01*
G03X511558Y1140973I-1186J525D01*
G03X508964I-1297J0D01*
G03X510026Y1139697I1298J0D01*
G01X510121Y1139679D01*
X510286Y1139367D01*
G02X510109Y1139074I-177J-93D01*
G01X504687D01*
X504008Y1140359D01*
X504047Y1140448D01*
G03X504158Y1140973I-1186J525D01*
G03X501564I-1297J0D01*
G03X502626Y1139697I1298J0D01*
G01X502721Y1139679D01*
X502886Y1139367D01*
G02X502709Y1139074I-177J-93D01*
G01X497287D01*
X496608Y1140359D01*
X496647Y1140448D01*
G03X496758Y1140973I-1186J525D01*
G03X494164I-1297J0D01*
G03X495226Y1139697I1298J0D01*
G01X495321Y1139679D01*
X495486Y1139367D01*
G02X495309Y1139074I-177J-93D01*
G01X489887D01*
X489208Y1140359D01*
X489247Y1140448D01*
G03X489358Y1140973I-1186J525D01*
G03X486764I-1297J0D01*
G03X487826Y1139697I1298J0D01*
G01X487921Y1139679D01*
X488086Y1139367D01*
G02X487909Y1139074I-177J-93D01*
G01X482487D01*
X481808Y1140359D01*
X481847Y1140448D01*
G03X481958Y1140973I-1186J525D01*
G03X479364I-1297J0D01*
G03X480426Y1139697I1298J0D01*
G01X480521Y1139679D01*
X480686Y1139367D01*
G02X480509Y1139074I-177J-93D01*
G01X479380D01*
G03X478673Y1138781I0J-999D01*
G01X478648Y1138756D01*
G03X477514Y1137469I163J-1287D01*
G03X477558Y1137137I1298J3D01*
G01X477579Y1137058D01*
X476708Y1135539D01*
X476627Y1135518D01*
G03X475664Y1134264I335J-1254D01*
G03X475711Y1133920I1298J2D01*
G01X475733Y1133839D01*
X474869Y1132332D01*
X474787Y1132311D01*
G03X473819Y1131060I324J-1251D01*
G03X473868Y1130708I1292J0D01*
G01X473891Y1130627D01*
X473037Y1129137D01*
X472953Y1129116D01*
G03X471964Y1127856I308J-1260D01*
G03X472018Y1127486I1298J0D01*
G01X472043Y1127404D01*
X471200Y1125934D01*
X471116Y1125914D01*
G03X470114Y1124651I295J-1263D01*
G03X470171Y1124268I1297J-3D01*
G01X470197Y1124185D01*
X469364Y1122732D01*
X469278Y1122713D01*
G03X468264Y1121447I283J-1266D01*
G03X468326Y1121052I1298J1D01*
G01X468353Y1120968D01*
X467525Y1119525D01*
X467438Y1119506D01*
G03X466419Y1118243I273J-1263D01*
G03X466483Y1117841I1292J0D01*
G01X466511Y1117756D01*
X465689Y1116323D01*
X465601Y1116304D01*
G03X464570Y1115039I261J-1265D01*
G03X464638Y1114626I1292J1D01*
G01X464667Y1114540D01*
X463852Y1113119D01*
X463763Y1113102D01*
G03X462720Y1111834I249J-1268D01*
G03X462792Y1111409I1292J0D01*
G01X462822Y1111323D01*
X462016Y1109917D01*
X461925Y1109900D01*
G03X460870Y1108630I237J-1270D01*
G03X460946Y1108193I1292J0D01*
G01X460977Y1108106D01*
X460179Y1106715D01*
X460087Y1106698D01*
G03X459020Y1105426I225J-1272D01*
G03X459100Y1104977I1292J-1D01*
G01X459133Y1104890D01*
X458342Y1103511D01*
X458249Y1103495D01*
G03X457170Y1102221I213J-1274D01*
G03X457255Y1101761I1292J1D01*
G01X457288Y1101673D01*
X456506Y1100308D01*
X456411Y1100293D01*
G03X455319Y1099017I200J-1276D01*
G03X455773Y1098034I1291J0D01*
G01Y1093590D01*
G03Y1091624I840J-983D01*
G01Y1087183D01*
G03Y1085217I837J-983D01*
G01Y1080774D01*
G03Y1078808I840J-983D01*
G01Y1074366D01*
G03Y1072400I837J-983D01*
G01Y1067957D01*
G03Y1065991I837J-983D01*
G01Y1061548D01*
G03Y1059582I837J-983D01*
G01Y1055140D01*
G03Y1053174I837J-983D01*
G01Y1048732D01*
G03Y1046766I837J-983D01*
G01Y1042323D01*
G03Y1040357I837J-983D01*
G01Y1028265D01*
G03X456066Y1027558I999J0D01*
G01X458666Y1024958D01*
G03X459373Y1024665I707J706D01*
G01X474659D01*
X475288Y1024036D01*
G02X475305Y1023489I-283J-283D01*
G03X474983Y1022636I969J-853D01*
G03X475667Y1021496I1292J0D01*
G01X475773Y1021439D01*
Y1018718D01*
X475668Y1018661D01*
G03Y1016391I617J-1135D01*
G01X475773Y1016334D01*
Y1014118D01*
X475668Y1014061D01*
G03X474993Y1012926I617J-1135D01*
G03X475388Y1011996I1292J0D01*
G02X475390Y1011423I-278J-287D01*
G03X475003Y1010500I905J-922D01*
G03X475670Y1009369I1292J0D01*
G01X475773Y1009312D01*
Y1007218D01*
X475668Y1007161D01*
G03X474993Y1006026I617J-1135D01*
G03X475337Y1005148I1292J0D01*
G02Y1004604I-293J-272D01*
G03X474993Y1003726I948J-878D01*
G03X475668Y1002591I1292J0D01*
G01X475773Y1002534D01*
Y998018D01*
X475668Y997961D01*
G03X474993Y996826I617J-1135D01*
G03X475337Y995948I1292J0D01*
G02Y995404I-293J-272D01*
G03X474993Y994526I948J-878D01*
G03X475668Y993391I1292J0D01*
G01X475773Y993334D01*
Y991118D01*
X475668Y991061D01*
G03X474993Y989926I617J-1135D01*
G03X475337Y989048I1292J0D01*
G02Y988504I-293J-272D01*
G03X474993Y987626I948J-878D01*
G03X475668Y986491I1292J0D01*
G01X475773Y986434D01*
Y981979D01*
X475578Y981784D01*
X475566Y981776D01*
G03X475296Y981506I769J-1039D01*
G01X475288Y981494D01*
X466293Y972499D01*
G03X466199Y972390I708J-705D01*
G03X464980Y971100I73J-1290D01*
G03X465863Y969874I1293J0D01*
G01X466000Y969829D01*
Y964838D01*
G03X466293Y964131I999J0D01*
G01X472066Y958358D01*
G03X472773Y958065I707J706D01*
G01X474959D01*
X475473Y957551D01*
Y955079D01*
X473859Y953465D01*
X463573D01*
G03X462866Y953172I0J-999D01*
G01X455366Y945672D01*
G03X455073Y944965I706J-707D01*
G01Y939779D01*
X453659Y938365D01*
X449990D01*
X449934Y938475D01*
G03X447624I-1155J-577D01*
G01X447568Y938365D01*
X446290D01*
X446234Y938475D01*
G03X443924I-1155J-577D01*
G01X443868Y938365D01*
X442590D01*
X442534Y938475D01*
G03X440224I-1155J-577D01*
G01X440168Y938365D01*
X438890D01*
X438834Y938475D01*
G03X436524I-1155J-577D01*
G01X436468Y938365D01*
X435190D01*
X435134Y938475D01*
G03X432824I-1155J-577D01*
G01X432768Y938365D01*
X431490D01*
X431434Y938475D01*
G03X429124I-1155J-577D01*
G01X429068Y938365D01*
X411387D01*
X406673Y943079D01*
Y965451D01*
X408187Y966965D01*
X412573D01*
G03X413280Y967258I0J999D01*
G01X414580Y968558D01*
G03X414873Y969265I-706J707D01*
G01Y969946D01*
X414978Y970003D01*
G03Y972277I-612J1137D01*
G01X414873Y972334D01*
Y973965D01*
G03X414580Y974672I-999J0D01*
G01X412080Y977172D01*
G03X411373Y977465I-707J-706D01*
G01X408187D01*
X406873Y978779D01*
Y1007514D01*
X408124Y1008765D01*
X412373D01*
G03X413080Y1009058I0J999D01*
G01X415080Y1011058D01*
G03X415373Y1011765I-706J707D01*
G01Y1013253D01*
X415521Y1013292D01*
G03Y1015788I-337J1248D01*
G01X415373Y1015827D01*
Y1025151D01*
X416050Y1025828D01*
X423737D01*
G03X424444Y1026121I0J999D01*
G01X425502Y1027179D01*
G03X425795Y1027886I-706J707D01*
G01Y1029304D01*
G03X425502Y1030011I-999J0D01*
G01X424161Y1031352D01*
G03X423454Y1031645I-707J-706D01*
G01X422655D01*
X421925Y1032375D01*
Y1037400D01*
X426404Y1041879D01*
G03X426697Y1042586I-706J707D01*
G01Y1084100D01*
X427164Y1084908D01*
X427254Y1084925D01*
G03X428310Y1086200I-242J1275D01*
G03X427077Y1087496I-1298J0D01*
G02X426697Y1087895I20J399D01*
G01Y1090913D01*
G02X427077Y1091312I400J0D01*
G03X428050Y1091830I-66J1296D01*
G01X429672D01*
G03X430711Y1091310I1039J778D01*
G03Y1093906I0J1298D01*
G03X429672Y1093386I0J-1298D01*
G01X428050D01*
G03X427077Y1093904I-1039J-778D01*
G02X426697Y1094303I20J399D01*
G01Y1102382D01*
G03X426404Y1103089I-999J0D01*
G01X424525Y1104968D01*
X424556Y1105081D01*
G03X424603Y1105426I-1245J345D01*
G03X423311Y1106718I-1292J0D01*
G03X422966Y1106671I0J-1292D01*
G01X422853Y1106640D01*
X419466Y1110027D01*
X419763Y1110542D01*
X419853Y1110559D01*
G03X420908Y1111834I-243J1275D01*
G03X419611Y1113132I-1298J0D01*
G03X418332Y1112053I0J-1298D01*
G02X417655Y1111838I-394J68D01*
G01X417065Y1112428D01*
X417051Y1112454D01*
G03X416531Y1112974I-1140J-620D01*
G01X416505Y1112988D01*
X415649Y1113844D01*
X415256Y1114524D01*
X415287Y1114611D01*
G03X415360Y1115039I-1225J429D01*
G03X414062Y1116336I-1297J0D01*
G03X413485Y1116201I-1J-1297D01*
G01X413356Y1116137D01*
X411891Y1117602D01*
Y1134522D01*
G03X411598Y1135229I-999J0D01*
G01X409753Y1137074D01*
X409777Y1137182D01*
G03X409810Y1137469I-1265J291D01*
G03X408512Y1138766I-1297J0D01*
G03X408120Y1138706I-2J-1297D01*
G03X407435Y1138978I-685J-727D01*
G01X407094D01*
G02X406740Y1139565I0J400D01*
G01X406801Y1139679D01*
X406896Y1139697D01*
G03X407958Y1140973I-236J1276D01*
G03X405364I-1297J0D01*
G03X405475Y1140447I1297J-1D01*
G01X405514Y1140358D01*
X404786Y1138978D01*
X399694D01*
G02X399340Y1139565I0J400D01*
G01X399401Y1139679D01*
X399496Y1139697D01*
G03X400558Y1140973I-236J1276D01*
G03X397964I-1297J0D01*
G03X398075Y1140447I1297J-1D01*
G01X398114Y1140358D01*
X397386Y1138978D01*
X392294D01*
G02X391940Y1139565I0J400D01*
G01X392001Y1139679D01*
X392096Y1139697D01*
G03X393158Y1140973I-236J1276D01*
G03X390564I-1297J0D01*
G03X390675Y1140447I1297J-1D01*
G01X390714Y1140358D01*
X389986Y1138978D01*
X384894D01*
G02X384540Y1139565I0J400D01*
G01X384601Y1139679D01*
X384696Y1139697D01*
G03X385758Y1140973I-236J1276D01*
G03X383164I-1297J0D01*
G03X383275Y1140447I1297J-1D01*
G01X383314Y1140358D01*
X382586Y1138978D01*
X377494D01*
G02X377140Y1139565I0J400D01*
G01X377201Y1139679D01*
X377296Y1139697D01*
G03X378358Y1140973I-236J1276D01*
G03X375764I-1297J0D01*
G03X375875Y1140447I1297J-1D01*
G01X375914Y1140358D01*
X375186Y1138978D01*
X370094D01*
G02X369740Y1139565I0J400D01*
G01X369801Y1139679D01*
X369896Y1139697D01*
G03X370958Y1140973I-236J1276D01*
G03X368364I-1297J0D01*
G03X368475Y1140447I1297J-1D01*
G01X368514Y1140358D01*
X367786Y1138978D01*
X362694D01*
G02X362340Y1139565I0J400D01*
G01X362401Y1139679D01*
X362496Y1139697D01*
G03X363558Y1140973I-236J1276D01*
G03X360964I-1297J0D01*
G03X361075Y1140447I1297J-1D01*
G01X361114Y1140358D01*
X360386Y1138978D01*
X315998D01*
X287277Y1167699D01*
Y1314501D01*
X288564Y1315788D01*
G37*
G36*
G01X726720Y1345542D02*
X726988D01*
X727048Y1345474D01*
G03X728104Y1344994I1056J922D01*
G03X728767Y1345160I1J1402D01*
G01X728897Y1345231D01*
X732600Y1341528D01*
Y1296016D01*
X730296Y1293712D01*
X716620D01*
G03X715913Y1293419I0J-999D01*
G01X712566Y1290072D01*
G03X712273Y1289365I706J-707D01*
G01Y1274534D01*
G03Y1272194I774J-1170D01*
G01Y848380D01*
X710538Y846645D01*
X601057D01*
X601039Y846648D01*
G03X600857Y846665I-184J-983D01*
G01X535161D01*
G02X534859Y847327I0J400D01*
G03X535176Y848176I-981J850D01*
G03X532580I-1298J0D01*
G03X532670Y847702I1298J1D01*
G01X532704Y847616D01*
X532202Y846665D01*
X531461D01*
G02X531159Y847327I0J400D01*
G03X531476Y848176I-981J850D01*
G03X530178Y849474I-1298J0D01*
G03X529139Y848954I0J-1298D01*
G01X527517D01*
G03X526478Y849474I-1039J-778D01*
G03X525180Y848176I0J-1298D01*
G03X525497Y847327I1298J1D01*
G02X525195Y846665I-302J-262D01*
G01X524547D01*
X523972Y847661D01*
X524003Y847747D01*
G03X524076Y848176I-1224J429D01*
G03X521480I-1298J0D01*
G03X521797Y847327I1298J1D01*
G02X521495Y846665I-302J-262D01*
G01X517147D01*
X516572Y847661D01*
X516603Y847747D01*
G03X516676Y848176I-1224J429D01*
G03X514080I-1298J0D01*
G03X514397Y847327I1298J1D01*
G02X514095Y846665I-302J-262D01*
G01X509747D01*
X509172Y847661D01*
X509203Y847747D01*
G03X509276Y848176I-1224J429D01*
G03X506680I-1298J0D01*
G03X506997Y847327I1298J1D01*
G02X506695Y846665I-302J-262D01*
G01X504787D01*
X503473Y847979D01*
Y850619D01*
G03Y852141I-1044J761D01*
G01Y852936D01*
G02X503968Y853324I400J0D01*
G03X504278Y853286I312J1260D01*
G03X505576Y854584I0J1298D01*
G03X505503Y855011I-1298J-2D01*
G01X505473Y855098D01*
X506281Y856497D01*
X506371Y856514D01*
G03X507426Y857789I-243J1275D01*
G03X504832I-1297J0D01*
G03X504904Y857361I1297J-2D01*
G01X504935Y857274D01*
X504128Y855876D01*
X504038Y855859D01*
G03X503968Y855844I237J-1276D01*
G02X503473Y856232I-95J388D01*
G01Y857019D01*
G03Y858559I-1045J770D01*
G01Y863436D01*
G03Y864958I-1044J761D01*
G01Y865753D01*
G02X503968Y866141I400J0D01*
G03X504278Y866104I308J1260D01*
G03X505576Y867401I0J1298D01*
G03X505503Y867828I-1298J-2D01*
G01X505473Y867915D01*
X506281Y869314D01*
X506371Y869331D01*
G03X507426Y870606I-243J1275D01*
G03X504832I-1297J0D01*
G03X504904Y870178I1297J-2D01*
G01X504935Y870091D01*
X504128Y868693D01*
X504038Y868676D01*
G03X503968Y868661I237J-1276D01*
G02X503473Y869049I-95J388D01*
G01Y869836D01*
G03Y871376I-1045J770D01*
G01Y876253D01*
G03Y877775I-1044J761D01*
G01Y878571D01*
G02X503968Y878959I400J0D01*
G03X504278Y878922I308J1260D01*
G03X505576Y880219I0J1298D01*
G03X504519Y881494I-1297J0D01*
G01X504429Y881511D01*
X503623Y882908D01*
X503654Y882994D01*
G03X503726Y883423I-1225J426D01*
G03X503473Y884193I-1298J0D01*
G01Y887151D01*
X505220Y888898D01*
X505358Y888795D01*
G03X506129Y888540I771J1038D01*
G03X507421Y889832I0J1292D01*
G03X507166Y890603I-1293J0D01*
G01X507063Y890741D01*
X508067Y891745D01*
X508136Y891754D01*
G03X509229Y892715I-158J1282D01*
G01X509268Y892865D01*
X510388D01*
X510427Y892715D01*
G03X512929I1251J320D01*
G01X512968Y892865D01*
X514089D01*
X514128Y892715D01*
G03X516630I1251J320D01*
G01X516669Y892865D01*
X517788D01*
X517827Y892715D01*
G03X520329I1251J320D01*
G01X520368Y892865D01*
X522073D01*
G03X522780Y893158I0J999D01*
G01X524569Y894947D01*
X524650Y894948D01*
G03X525921Y896219I-21J1292D01*
G01X525922Y896300D01*
X531238Y901616D01*
X531371Y901537D01*
G03X532029Y901357I658J1113D01*
G03X533321Y902649I0J1292D01*
G03X533141Y903307I-1293J0D01*
G01X533062Y903440D01*
X534231Y904609D01*
X534277Y904624D01*
G03X535108Y905455I-398J1229D01*
G01X535123Y905501D01*
X535384Y905762D01*
X536280D01*
X536312Y905601D01*
G03X538846I1267J252D01*
G01X538878Y905762D01*
X547380D01*
X547412Y905601D01*
G03X549946I1267J252D01*
G01X549978Y905762D01*
X554384D01*
G03X555091Y906055I0J999D01*
G01X558334Y909298D01*
G03X558627Y910005I-706J707D01*
G01Y1047135D01*
G03X558334Y1047842I-999J0D01*
G01X553874Y1052302D01*
G03X553167Y1052595I-707J-706D01*
G01X534957D01*
X530048Y1057504D01*
X530037Y1057568D01*
G03X528969Y1058636I-1275J-207D01*
G01X528905Y1058647D01*
X527870Y1059682D01*
X527967Y1059820D01*
G03X528203Y1060565I-1056J744D01*
G03X526911Y1061857I-1292J0D01*
G03X526166Y1061621I-1J-1292D01*
G01X526028Y1061524D01*
X520789Y1066763D01*
X520798Y1066856D01*
G03X520803Y1066974I-1287J114D01*
G03X519511Y1068266I-1292J0D01*
G03X518291Y1067399I0J-1292D01*
G01X518244Y1067265D01*
X517078D01*
X517031Y1067399D01*
G03X514591I-1220J-425D01*
G01X514544Y1067265D01*
X513378D01*
X513331Y1067399D01*
G03X510891I-1220J-425D01*
G01X510844Y1067265D01*
X509678D01*
X509631Y1067399D01*
G03X507191I-1220J-425D01*
G01X507144Y1067265D01*
X505978D01*
X505931Y1067399D01*
G03X503491I-1220J-425D01*
G01X503444Y1067265D01*
X502278D01*
X502231Y1067399D01*
G03X499791I-1220J-425D01*
G01X499744Y1067265D01*
X498578D01*
X498531Y1067399D01*
G03X496091I-1220J-425D01*
G01X496044Y1067265D01*
X494878D01*
X494831Y1067399D01*
G03X492391I-1220J-425D01*
G01X492344Y1067265D01*
X491178D01*
X491131Y1067399D01*
G03X488691I-1220J-425D01*
G01X488644Y1067265D01*
X487478D01*
X487431Y1067399D01*
G03X484991I-1220J-425D01*
G01X484944Y1067265D01*
X483779D01*
X483732Y1067399D01*
G03X481292I-1220J-425D01*
G01X481245Y1067265D01*
X480078D01*
X480031Y1067399D01*
G03X477591I-1220J-425D01*
G01X477544Y1067265D01*
X476378D01*
X476331Y1067399D01*
G03X475111Y1068266I-1220J-425D01*
G03X473851Y1067262I0J-1293D01*
G03X472908Y1066766I-78J-997D01*
G01X469965D01*
X466672Y1063473D01*
Y1061893D01*
G03Y1059237I1039J-1328D01*
G01Y1055485D01*
G03Y1052829I1039J-1328D01*
G01Y1048517D01*
G03X466419Y1047750I1039J-768D01*
G03X466672Y1046983I1292J1D01*
G01Y1042107D01*
G03X466419Y1041340I1039J-768D01*
G03X466672Y1040573I1292J1D01*
G01Y1037960D01*
G03Y1035788I700J-1086D01*
G01Y1027171D01*
X466166Y1026665D01*
X459787D01*
X457773Y1028679D01*
Y1040774D01*
X457790Y1040813D01*
G03X457903Y1041340I-1179J528D01*
G03X457790Y1041867I-1292J-1D01*
G01X457773Y1041906D01*
Y1047183D01*
X457790Y1047222D01*
G03X457903Y1047749I-1179J528D01*
G03X457790Y1048276I-1292J-1D01*
G01X457773Y1048315D01*
Y1053591D01*
X457790Y1053630D01*
G03X457903Y1054157I-1179J528D01*
G03X457790Y1054684I-1292J-1D01*
G01X457773Y1054723D01*
Y1059999D01*
X457790Y1060038D01*
G03X457903Y1060565I-1179J528D01*
G03X457790Y1061092I-1292J-1D01*
G01X457773Y1061131D01*
Y1066408D01*
X457790Y1066447D01*
G03X457903Y1066974I-1179J528D01*
G03X457790Y1067501I-1292J-1D01*
G01X457773Y1067540D01*
Y1072817D01*
X457790Y1072856D01*
G03X457903Y1073383I-1179J528D01*
G03X457790Y1073910I-1292J-1D01*
G01X457773Y1073949D01*
Y1079223D01*
X457791Y1079262D01*
G03X457904Y1079791I-1179J528D01*
G03X457791Y1080320I-1292J1D01*
G01X457773Y1080359D01*
Y1085634D01*
X457790Y1085673D01*
G03X457903Y1086200I-1179J528D01*
G03X457790Y1086727I-1292J-1D01*
G01X457773Y1086766D01*
Y1092039D01*
X457791Y1092078D01*
G03X457904Y1092607I-1179J528D01*
G03X457791Y1093136I-1292J1D01*
G01X457773Y1093175D01*
Y1098451D01*
X457790Y1098490D01*
G03X457832Y1098595I-1177J532D01*
G01X457838Y1098613D01*
X459394Y1101326D01*
X459410Y1101343D01*
G03X459699Y1101847I-948J878D01*
G01X459705Y1101869D01*
X461215Y1104502D01*
X461233Y1104520D01*
G03X461559Y1105088I-921J906D01*
G01X461566Y1105113D01*
X463037Y1107679D01*
X463058Y1107699D01*
G03X463418Y1108327I-896J931D01*
G01X463425Y1108355D01*
X464861Y1110859D01*
X464884Y1110881D01*
G03X465275Y1111563I-872J953D01*
G01X465282Y1111594D01*
X466687Y1114044D01*
X466712Y1114066D01*
G03X467131Y1114797I-850J973D01*
G01X467137Y1114829D01*
X468514Y1117230D01*
X468541Y1117253D01*
G03X468985Y1118026I-830J991D01*
G01X468991Y1118061D01*
X470333Y1120403D01*
X470364Y1120427D01*
G03X470847Y1121270I-802J1020D01*
G01X470853Y1121309D01*
X472162Y1123592D01*
X472195Y1123617D01*
G03X472699Y1124497I-784J1034D01*
G01X472704Y1124537D01*
X473143Y1125304D01*
G02X473837I347J-199D01*
G01X473917Y1125166D01*
X473886Y1125080D01*
G03X473814Y1124651I1225J-426D01*
G03X476408I1297J0D01*
G03X475353Y1125926I-1298J0D01*
G01X475263Y1125943D01*
X474456Y1127341D01*
X474487Y1127427D01*
G03X474553Y1127727I-1225J427D01*
G01X474557Y1127769D01*
X475827Y1129984D01*
X475863Y1130009D01*
G03X476398Y1130942I-752J1051D01*
G01X476402Y1130985D01*
X477650Y1133163D01*
X477689Y1133189D01*
G03X478257Y1134180I-727J1075D01*
G01X478260Y1134226D01*
X479482Y1136357D01*
X479522Y1136383D01*
G03X480003Y1136953I-709J1087D01*
G01X480055Y1137074D01*
X481269D01*
X481321Y1136953D01*
G03X482512Y1136172I1190J516D01*
G03X483703Y1136953I1J1297D01*
G01X483755Y1137074D01*
X484394D01*
G02X484741Y1136474I0J-400D01*
G01X484211Y1135556D01*
X484121Y1135539D01*
G03X483064Y1134264I240J-1275D01*
G03X485660I1298J0D01*
G03X485587Y1134692I-1298J-1D01*
G01X485557Y1134779D01*
X486364Y1136177D01*
X486454Y1136194D01*
G03X487403Y1136953I-242J1275D01*
G01X487455Y1137074D01*
X488669D01*
X488721Y1136953D01*
G03X489912Y1136172I1190J516D01*
G03X491103Y1136953I1J1297D01*
G01X491155Y1137074D01*
X491794D01*
G02X492141Y1136474I0J-400D01*
G01X491611Y1135556D01*
X491521Y1135539D01*
G03X490464Y1134264I240J-1275D01*
G03X493060I1298J0D01*
G03X492987Y1134692I-1298J-1D01*
G01X492957Y1134779D01*
X493764Y1136177D01*
X493854Y1136194D01*
G03X494803Y1136953I-242J1275D01*
G01X494855Y1137074D01*
X496069D01*
X496121Y1136953D01*
G03X497312Y1136172I1190J516D01*
G03X498503Y1136953I1J1297D01*
G01X498555Y1137074D01*
X499194D01*
G02X499541Y1136474I0J-400D01*
G01X499011Y1135556D01*
X498921Y1135539D01*
G03X497864Y1134264I240J-1275D01*
G03X500460I1298J0D01*
G03X500387Y1134692I-1298J-1D01*
G01X500357Y1134779D01*
X501164Y1136177D01*
X501254Y1136194D01*
G03X502203Y1136953I-242J1275D01*
G01X502255Y1137074D01*
X503469D01*
X503521Y1136953D01*
G03X504712Y1136172I1190J516D01*
G03X505903Y1136953I1J1297D01*
G01X505955Y1137074D01*
X506594D01*
G02X506941Y1136474I0J-400D01*
G01X506411Y1135556D01*
X506321Y1135539D01*
G03X505264Y1134264I240J-1275D01*
G03X507860I1298J0D01*
G03X507787Y1134692I-1298J-1D01*
G01X507757Y1134779D01*
X508564Y1136177D01*
X508654Y1136194D01*
G03X509603Y1136953I-242J1275D01*
G01X509655Y1137074D01*
X510869D01*
X510921Y1136953D01*
G03X512112Y1136172I1190J516D01*
G03X513303Y1136953I1J1297D01*
G01X513355Y1137074D01*
X513994D01*
G02X514341Y1136474I0J-400D01*
G01X513811Y1135556D01*
X513721Y1135539D01*
G03X512664Y1134264I240J-1275D01*
G03X515260I1298J0D01*
G03X515187Y1134692I-1298J-1D01*
G01X515157Y1134779D01*
X515964Y1136177D01*
X516054Y1136194D01*
G03X517003Y1136953I-242J1275D01*
G01X517055Y1137074D01*
X518269D01*
X518321Y1136953D01*
G03X519512Y1136172I1190J516D01*
G03X520703Y1136953I1J1297D01*
G01X520755Y1137074D01*
X521394D01*
G02X521741Y1136474I0J-400D01*
G01X521211Y1135556D01*
X521121Y1135539D01*
G03X520064Y1134264I240J-1275D01*
G03X522660I1298J0D01*
G03X522587Y1134692I-1298J-1D01*
G01X522557Y1134779D01*
X523364Y1136177D01*
X523454Y1136194D01*
G03X524403Y1136953I-242J1275D01*
G01X524455Y1137074D01*
X525669D01*
X525721Y1136953D01*
G03X526912Y1136172I1190J516D01*
G03X528103Y1136953I1J1297D01*
G01X528155Y1137074D01*
X529375D01*
X529427Y1136954D01*
G03X531797I1185J515D01*
G01X531849Y1137074D01*
X532494D01*
G02X532840Y1136474I0J-400D01*
G01X532310Y1135556D01*
X532220Y1135539D01*
G03X531164Y1134264I242J-1275D01*
G03X533760I1298J0D01*
G03X533687Y1134692I-1298J-1D01*
G01X533656Y1134779D01*
X534464Y1136177D01*
X534554Y1136194D01*
G03X535503Y1136953I-242J1275D01*
G01X535555Y1137074D01*
X541136D01*
G03X541843Y1137367I0J999D01*
G01X571104Y1166628D01*
G03X571397Y1167335I-706J707D01*
G01Y1303321D01*
X572841Y1304765D01*
X582707D01*
G03X583414Y1305058I0J999D01*
G01X585844Y1307488D01*
G03X586137Y1308195I-706J707D01*
G01Y1341355D01*
X590324Y1345542D01*
X663875D01*
G03X664987Y1344994I1112J854D01*
G03X666043Y1345474I0J1402D01*
G01X666103Y1345542D01*
X666371D01*
X666431Y1345474D01*
G03X668543I1056J922D01*
G01X668603Y1345542D01*
X668921D01*
X668981Y1345474D01*
G03X670037Y1344994I1056J922D01*
G03X671149Y1345542I0J1402D01*
G01X683443D01*
G03X684555Y1344994I1112J854D01*
G03X685611Y1345474I0J1402D01*
G01X685671Y1345542D01*
X685989D01*
X686049Y1345474D01*
G03X688161I1056J922D01*
G01X688221Y1345542D01*
X688489D01*
X688549Y1345474D01*
G03X689605Y1344994I1056J922D01*
G03X690717Y1345542I0J1402D01*
G01X701975D01*
G03X703087Y1344994I1112J854D01*
G03X704143Y1345474I0J1402D01*
G01X704203Y1345542D01*
X704471D01*
X704531Y1345474D01*
G03X706643I1056J922D01*
G01X706703Y1345542D01*
X707021D01*
X707081Y1345474D01*
G03X708137Y1344994I1056J922D01*
G03X709249Y1345542I0J1402D01*
G01X721942D01*
G03X723054Y1344994I1112J854D01*
G03X724110Y1345474I0J1402D01*
G01X724170Y1345542D01*
X724488D01*
X724548Y1345474D01*
G03X726660I1056J922D01*
G01X726720Y1345542D01*
G37*
G36*
G01X846066Y1258091D02*
X855167D01*
G03X855175Y1258083I711J703D01*
G01X856270Y1256988D01*
G03X856457Y1256841I707J707D01*
G01Y765869D01*
X851223Y760635D01*
X671104D01*
G03X668452I-1326J-706D01*
G01X603782D01*
G02X603392Y761126I0J400D01*
G03X603429Y761445I-1365J320D01*
G03X602266Y762826I-1401J0D01*
G01X602100Y762855D01*
Y765448D01*
X608574Y771922D01*
G03X608867Y772629I-706J707D01*
G01Y843061D01*
X610451Y844645D01*
X710952D01*
G03X711659Y844938I0J999D01*
G01X713980Y847259D01*
G03X714273Y847966I-706J707D01*
G01Y1256853D01*
G03X714337Y1256912I-645J764D01*
G01X715516Y1258091D01*
X722575D01*
G03X724825I1125J637D01*
G01X738450D01*
G03X740948I1249J635D01*
G01X768150D01*
G03X770648I1249J635D01*
G01X782961D01*
X782973Y1258090D01*
G03X783130Y1258080I160J1282D01*
G03X783287Y1258090I-3J1292D01*
G01X783299Y1258091D01*
X797850D01*
G03X800348I1249J635D01*
G01X811315D01*
G03X813565I1125J637D01*
G01X827550D01*
G03X830048I1249J635D01*
G01X843816D01*
G03X846066I1125J637D01*
G37*
G36*
G01X1102415Y1256125D02*
X1119023D01*
X1119400Y1255748D01*
Y861362D01*
G03X1119693Y860655I999J0D01*
G01X1122058Y858290D01*
G03X1122765Y857997I707J706D01*
G01X1250061D01*
X1252220Y855838D01*
Y767022D01*
X1250503Y765305D01*
X1002681D01*
X1000207Y767779D01*
Y1255065D01*
X1001086Y1255944D01*
G03X1002070Y1255540I985J998D01*
G03X1003209Y1256125I0J1401D01*
G01X1011806D01*
G03X1012543Y1255896I737J1073D01*
G03X1013280Y1256125I0J1302D01*
G01X1071355D01*
X1071398Y1256103D01*
G03X1072584I593J1158D01*
G01X1072627Y1256125D01*
X1100693D01*
G03X1102415I861J978D01*
G37*
G36*
G01X1676377Y1426535D02*
X1734813D01*
X1752487Y1408861D01*
Y1322085D01*
G03X1752780Y1321378I999J0D01*
G01X1755130Y1319028D01*
G03X1755837Y1318735I707J706D01*
G01X1785448D01*
X1787247Y1316936D01*
Y1295949D01*
X1783560Y1292262D01*
G03X1783267Y1291555I706J-707D01*
G01Y1290695D01*
G03Y1284633I1944J-3031D01*
G01Y1268869D01*
X1782543Y1268145D01*
X1691714D01*
X1690478Y1269381D01*
G03X1690414Y1269440I-709J-705D01*
G01Y1272662D01*
X1690436Y1272705D01*
G03Y1273983I-1249J639D01*
G01X1690414Y1274026D01*
Y1294850D01*
X1692914Y1297350D01*
G03X1693207Y1298057I-706J707D01*
G01Y1382985D01*
G03X1692914Y1383692I-999J0D01*
G01X1691074Y1385532D01*
G03X1690367Y1385825I-707J-706D01*
G01X1607424D01*
G03X1606717Y1385532I0J-999D01*
G01X1560571Y1339386D01*
G03X1560278Y1338679I706J-707D01*
G01Y1302860D01*
X1559233Y1301815D01*
X1507617D01*
G03X1506910Y1301522I0J-999D01*
G01X1491852Y1286464D01*
X1477114D01*
G03X1476407Y1286171I0J-999D01*
G01X1470407Y1280171D01*
G03X1470114Y1279464I706J-707D01*
G01Y1274578D01*
X1468100Y1272564D01*
X1346762D01*
X1336164Y1283162D01*
G03X1335457Y1283455I-707J-706D01*
G01X1325611D01*
X1299311Y1309755D01*
G03X1298604Y1310048I-707J-706D01*
G01X1255724D01*
X1254531Y1311241D01*
Y1333482D01*
G03Y1335816I-944J1167D01*
G01Y1380553D01*
G03X1254238Y1381260I-999J0D01*
G01X1248975Y1386523D01*
G03X1248268Y1386816I-707J-706D01*
G01X1121944D01*
G03X1121237Y1386523I0J-999D01*
G01X1117993Y1383279D01*
G03X1117700Y1382572I706J-707D01*
G01Y1258125D01*
X1102513D01*
G03X1100595I-959J-1024D01*
G01X1073096D01*
G03X1070886I-1105J-863D01*
G01X1043580D01*
G03X1041082I-1249J-637D01*
G01X1013595D01*
G03X1011491I-1052J-927D01*
G01X1002822D01*
G03X1002070Y1258344I-752J-1182D01*
G03X1001362Y1258152I0J-1401D01*
G01X1001316Y1258125D01*
X1001113D01*
X1000207Y1259031D01*
Y1395505D01*
X1006635Y1401933D01*
X1006765Y1401867D01*
G03X1016240Y1399578I9474J18463D01*
G03X1036992Y1420330I0J20752D01*
G03X1036351Y1425450I-20752J2D01*
G02X1036739Y1425949I388J99D01*
G01X1114397D01*
X1114445Y1425819D01*
G03X1117261I1408J523D01*
G01X1117309Y1425949D01*
X1133255D01*
G03X1134429Y1425362I1174J881D01*
G03X1135546Y1425879I-1J1467D01*
G01X1135606Y1425949D01*
X1135852D01*
X1135912Y1425879D01*
G03X1137029Y1425362I1118J950D01*
G03X1138203Y1425949I0J1468D01*
G01X1144393D01*
G03X1146691I1149J912D01*
G01X1171398D01*
G03X1172572Y1425362I1174J881D01*
G03X1173689Y1425879I-1J1467D01*
G01X1173749Y1425949D01*
X1173995D01*
X1174055Y1425879D01*
G03X1175172Y1425362I1118J950D01*
G03X1176346Y1425949I0J1468D01*
G01X1182536D01*
G03X1184834I1149J912D01*
G01X1303629D01*
X1329530Y1400048D01*
G03X1330237Y1399755I707J706D01*
G01X1368298D01*
G03X1369005Y1400048I0J999D01*
G01X1394088Y1425131D01*
X1394130Y1425146D01*
G03X1395046Y1426062I-500J1416D01*
G01X1395061Y1426104D01*
X1395492Y1426535D01*
X1413320D01*
X1413366Y1426400D01*
G03X1416206I1420J490D01*
G01X1416252Y1426535D01*
X1430691D01*
G03X1432743I1026J1097D01*
G01X1511359D01*
G03X1512177Y1426293I818J1260D01*
G03X1512995Y1426535I0J1502D01*
G01X1631698D01*
G03X1633334I818J1219D01*
G01X1634168D01*
G03X1635804I818J1219D01*
G01X1636598D01*
G03X1638234I818J1219D01*
G01X1669841D01*
G03X1671477I818J1219D01*
G01X1672311D01*
G03X1673947I818J1219D01*
G01X1674741D01*
G03X1676377I818J1219D01*
G37*
G36*
G01X1079294Y329592D02*
X1289146D01*
X1295300Y323438D01*
Y316959D01*
X1295192Y316903D01*
G03Y314239I696J-1332D01*
G01X1295300Y314183D01*
Y301552D01*
G02X1294816Y301161I-400J0D01*
G03X1294500Y301194I-313J-1469D01*
G01X1291100D01*
G03Y298190I0J-1502D01*
G01X1294500D01*
G03X1294816Y298223I3J1502D01*
G02X1295300Y297832I84J-391D01*
G01Y226962D01*
G03X1295593Y226255I999J0D01*
G01X1298393Y223455D01*
G03X1299100Y223162I707J706D01*
G01X1302339D01*
G03X1304511I1086J888D01*
G01X1308742D01*
G03X1310914I1086J888D01*
G01X1321566D01*
G03X1323738I1086J888D01*
G01X1327975D01*
G03X1330147I1086J888D01*
G01X1330555D01*
G02X1330935Y222637I0J-400D01*
G03X1330865Y222199I1332J-437D01*
G03X1332267Y220797I1402J0D01*
G03X1333067Y221048I0J1402D01*
G01X1333205Y221143D01*
X1333500Y220848D01*
Y196657D01*
G03Y194291I752J-1183D01*
G01Y177757D01*
G03Y175391I752J-1183D01*
G01Y168676D01*
X1332818Y167994D01*
X1332702Y168032D01*
G03X1332268Y168101I-434J-1333D01*
G03X1331033Y167362I0J-1401D01*
G01X1320687D01*
G03X1318217I-1235J-662D01*
G01X1314268D01*
G03X1311798I-1235J-662D01*
G01X1307857D01*
G03X1305387I-1235J-662D01*
G01X1301447D01*
G03X1298977I-1235J-662D01*
G01X1295037D01*
G03X1292567I-1235J-662D01*
G01X1272138D01*
X1272105Y167374D01*
G03X1271081I-512J-1411D01*
G01X1271048Y167362D01*
X1080814D01*
X1079740Y168436D01*
Y220112D01*
G03X1079447Y220819I-999J0D01*
G01X1072800Y227466D01*
Y323098D01*
X1079294Y329592D01*
G37*
G36*
G01X1189152Y1384816D02*
X1247854D01*
X1252531Y1380139D01*
Y1335718D01*
G03Y1333580I1055J-1069D01*
G01Y1310827D01*
G03X1252824Y1310120I999J0D01*
G01X1254603Y1308341D01*
G03X1255310Y1308048I707J706D01*
G01X1267250D01*
X1268587Y1306711D01*
Y1168775D01*
G03X1268880Y1168068I999J0D01*
G01X1299678Y1137270D01*
G03X1300385Y1136977I707J706D01*
G01X1320551D01*
X1320607Y1136870D01*
G03X1322897I1145J599D01*
G01X1322953Y1136977D01*
X1324247D01*
X1324303Y1136869D01*
G03X1325212Y1136194I1151J600D01*
G01X1325302Y1136177D01*
X1326109Y1134779D01*
X1326078Y1134693D01*
G03X1326006Y1134264I1225J-426D01*
G03X1328600I1297J0D01*
G03X1327545Y1135539I-1298J0D01*
G01X1327455Y1135556D01*
X1326981Y1136377D01*
G02X1327327Y1136977I346J200D01*
G01X1327951D01*
X1328007Y1136870D01*
G03X1330297I1145J599D01*
G01X1330353Y1136977D01*
X1331647D01*
X1331703Y1136869D01*
G03X1332612Y1136194I1151J600D01*
G01X1332702Y1136177D01*
X1333509Y1134779D01*
X1333478Y1134693D01*
G03X1333406Y1134264I1225J-426D01*
G03X1336000I1297J0D01*
G03X1334945Y1135539I-1298J0D01*
G01X1334855Y1135556D01*
X1334381Y1136377D01*
G02X1334727Y1136977I346J200D01*
G01X1335347D01*
X1335403Y1136869D01*
G03X1336554Y1136172I1150J600D01*
G03X1337705Y1136869I1J1297D01*
G01X1337761Y1136977D01*
X1339047D01*
X1339103Y1136869D01*
G03X1340012Y1136194I1151J600D01*
G01X1340102Y1136177D01*
X1340910Y1134779D01*
X1340879Y1134692D01*
G03X1340806Y1134264I1225J-429D01*
G03X1343402I1298J0D01*
G03X1342346Y1135539I-1298J0D01*
G01X1342256Y1135556D01*
X1341782Y1136377D01*
G02X1342128Y1136977I346J200D01*
G01X1342747D01*
X1342803Y1136869D01*
G03X1343954Y1136172I1150J600D01*
G03X1345105Y1136869I1J1297D01*
G01X1345161Y1136977D01*
X1346447D01*
X1346503Y1136869D01*
G03X1347412Y1136194I1151J600D01*
G01X1347502Y1136177D01*
X1348310Y1134779D01*
X1348279Y1134692D01*
G03X1348206Y1134264I1225J-429D01*
G03X1350802I1298J0D01*
G03X1349746Y1135539I-1298J0D01*
G01X1349656Y1135556D01*
X1349182Y1136377D01*
G02X1349528Y1136977I346J200D01*
G01X1350147D01*
X1350203Y1136869D01*
G03X1351354Y1136172I1150J600D01*
G03X1352505Y1136869I1J1297D01*
G01X1352561Y1136977D01*
X1353847D01*
X1353903Y1136869D01*
G03X1354812Y1136194I1151J600D01*
G01X1354902Y1136177D01*
X1355710Y1134779D01*
X1355679Y1134692D01*
G03X1355606Y1134264I1225J-429D01*
G03X1358202I1298J0D01*
G03X1357146Y1135539I-1298J0D01*
G01X1357056Y1135556D01*
X1356582Y1136377D01*
G02X1356928Y1136977I346J200D01*
G01X1357547D01*
X1357603Y1136869D01*
G03X1358754Y1136172I1150J600D01*
G03X1359905Y1136869I1J1297D01*
G01X1359961Y1136977D01*
X1361247D01*
X1361303Y1136869D01*
G03X1362212Y1136194I1151J600D01*
G01X1362302Y1136177D01*
X1363110Y1134779D01*
X1363079Y1134692D01*
G03X1363006Y1134264I1225J-429D01*
G03X1365602I1298J0D01*
G03X1364546Y1135539I-1298J0D01*
G01X1364456Y1135556D01*
X1363982Y1136377D01*
G02X1364328Y1136977I346J200D01*
G01X1364947D01*
X1365003Y1136869D01*
G03X1366154Y1136172I1150J600D01*
G03X1367305Y1136869I1J1297D01*
G01X1367361Y1136977D01*
X1368647D01*
X1368703Y1136869D01*
G03X1369612Y1136194I1151J600D01*
G01X1369702Y1136177D01*
X1370510Y1134779D01*
X1370479Y1134692D01*
G03X1370406Y1134264I1225J-429D01*
G03X1373002I1298J0D01*
G03X1371946Y1135539I-1298J0D01*
G01X1371856Y1135556D01*
X1371382Y1136377D01*
G02X1371728Y1136977I346J200D01*
G01X1372347D01*
X1372403Y1136869D01*
G03X1373554Y1136172I1150J600D01*
G03X1374705Y1136869I1J1297D01*
G01X1374761Y1136977D01*
X1376047D01*
X1376103Y1136869D01*
G03X1377012Y1136194I1151J600D01*
G01X1377102Y1136177D01*
X1377910Y1134779D01*
X1377879Y1134692D01*
G03X1377806Y1134264I1225J-429D01*
G03X1380402I1298J0D01*
G03X1379346Y1135539I-1298J0D01*
G01X1379256Y1135556D01*
X1378782Y1136377D01*
G02X1379128Y1136977I346J200D01*
G01X1379747D01*
X1379803Y1136869D01*
G03X1380954Y1136172I1150J600D01*
G03X1382105Y1136869I1J1297D01*
G01X1382161Y1136977D01*
X1383162D01*
X1385240Y1134899D01*
X1385310Y1134779D01*
X1385279Y1134692D01*
G03X1385206Y1134264I1225J-429D01*
G03X1385922Y1133104I1298J0D01*
G01X1386032Y1133049D01*
Y1129065D01*
X1385922Y1129010D01*
G03Y1126702I581J-1154D01*
G01X1386032Y1126647D01*
Y1126038D01*
G02X1385401Y1125711I-400J0D01*
G03X1384653Y1125948I-747J-1060D01*
G03X1383356Y1124651I0J-1297D01*
G03X1384411Y1123376I1298J0D01*
G01X1384501Y1123359D01*
X1385309Y1121960D01*
X1385279Y1121874D01*
G03X1385206Y1121447I1225J-429D01*
G03X1385922Y1120287I1298J0D01*
G01X1386032Y1120232D01*
Y1117187D01*
G03X1386325Y1116480I999J0D01*
G01X1390768Y1112037D01*
X1390760Y1111944D01*
G03X1390756Y1111834I1293J-102D01*
G03X1392053Y1110536I1298J0D01*
G03X1392163Y1110541I-4J1298D01*
G01X1392256Y1110549D01*
X1392981Y1109824D01*
G02Y1109542I-142J-141D01*
G03X1392606Y1108630I923J-913D01*
G03X1393904Y1107332I1298J0D01*
G03X1394816Y1107707I-1J1298D01*
G02X1395098I141J-142D01*
G01X1395489Y1107316D01*
G02X1395335Y1106654I-283J-283D01*
G03X1394714Y1106204I417J-1229D01*
G01X1393092D01*
G03X1392053Y1106724I-1039J-778D01*
G03Y1104128I0J-1298D01*
G03X1393092Y1104648I0J1298D01*
G01X1394714D01*
G03X1395753Y1104128I1039J778D01*
G03X1396981Y1105008I0J1297D01*
G02X1397643Y1105162I379J-129D01*
G01X1400099Y1102706D01*
X1400065Y1102591D01*
G03X1400011Y1102221I1238J-370D01*
G03X1400727Y1101064I1293J0D01*
G01X1400838Y1101009D01*
Y1097030D01*
X1400727Y1096975D01*
G03X1400006Y1095813I576J-1162D01*
G03X1400079Y1095385I1298J1D01*
G01X1400110Y1095298D01*
X1399303Y1093900D01*
X1399212Y1093883D01*
G03X1398156Y1092608I242J-1275D01*
G03X1399453Y1091310I1298J0D01*
G03X1400206Y1091551I0J1297D01*
G02X1400838Y1091226I232J-326D01*
G01Y1090615D01*
X1400727Y1090560D01*
G03Y1088248I577J-1156D01*
G01X1400838Y1088193D01*
Y1087582D01*
G02X1400206Y1087257I-400J1D01*
G03X1399453Y1087498I-753J-1056D01*
G03X1398414Y1086978I0J-1298D01*
G01X1396792D01*
G03X1395753Y1087498I-1039J-778D01*
G03Y1084902I0J-1298D01*
G03X1396792Y1085422I0J1298D01*
G01X1398414D01*
G03X1399453Y1084902I1039J778D01*
G03X1400206Y1085143I0J1297D01*
G02X1400838Y1084818I232J-326D01*
G01Y1084212D01*
X1400727Y1084157D01*
G03Y1081833I576J-1162D01*
G01X1400838Y1081778D01*
Y1077798D01*
X1400727Y1077743D01*
G03Y1075431I577J-1156D01*
G01X1400838Y1075376D01*
Y1071389D01*
X1400727Y1071334D01*
G03Y1069022I577J-1156D01*
G01X1400838Y1068967D01*
Y1064981D01*
X1400727Y1064926D01*
G03Y1062614I577J-1156D01*
G01X1400838Y1062559D01*
Y1058572D01*
X1400727Y1058517D01*
G03Y1056205I577J-1156D01*
G01X1400838Y1056150D01*
Y1052163D01*
X1400727Y1052108D01*
G03Y1049796I577J-1156D01*
G01X1400838Y1049741D01*
Y1045755D01*
X1400727Y1045700D01*
G03Y1043388I577J-1156D01*
G01X1400838Y1043333D01*
Y1042999D01*
X1400226Y1042387D01*
X1400094Y1042463D01*
G03X1399454Y1042632I-639J-1123D01*
G03X1398162Y1041340I0J-1292D01*
G03X1398331Y1040700I1292J-1D01*
G01X1398407Y1040568D01*
X1396359Y1038520D01*
G03X1396066Y1037813I706J-707D01*
G01Y1031960D01*
G03X1396359Y1031253I999J0D01*
G01X1397675Y1029937D01*
G03X1398382Y1029644I707J706D01*
G01X1399181D01*
X1399936Y1028889D01*
Y1028299D01*
X1399464Y1027827D01*
X1391777D01*
G03X1391070Y1027534I0J-999D01*
G01X1390700Y1027164D01*
X1389525D01*
X1389401Y1027289D01*
G03X1389374Y1027314I-353J-354D01*
G01X1389367Y1027319D01*
X1387716Y1028971D01*
Y1030699D01*
G03X1388214Y1031564I-502J865D01*
G01Y1048564D01*
G03X1387921Y1049271I-999J0D01*
G01X1381221Y1055971D01*
G03X1380514Y1056264I-707J-706D01*
G01X1356614D01*
G03X1355907Y1055971I0J-999D01*
G01X1355354Y1055418D01*
X1355253Y1055433D01*
G03X1355053Y1055449I-203J-1276D01*
G03X1353761Y1054157I0J-1292D01*
G03X1353777Y1053957I1292J3D01*
G01X1353792Y1053856D01*
X1345774Y1045838D01*
X1345700Y1045832D01*
G03X1344516Y1044648I104J-1288D01*
G01X1344510Y1044574D01*
X1339142Y1039206D01*
X1339012Y1039276D01*
G03X1337264Y1037528I-608J-1140D01*
G01X1337334Y1037398D01*
X1336063Y1036127D01*
X1336029Y1036112D01*
G03X1335372Y1035455I524J-1181D01*
G01X1335357Y1035421D01*
X1329655Y1029719D01*
X1329540Y1029756D01*
G03X1329153Y1029815I-386J-1233D01*
G03X1327861Y1028523I0J-1292D01*
G03X1327961Y1028025I1292J0D01*
G01X1327907Y1027971D01*
G03X1327614Y1027264I706J-707D01*
G01Y983426D01*
X1327589Y983381D01*
G03X1327428Y982756I1131J-625D01*
G03X1327589Y982131I1292J0D01*
G01X1327614Y982086D01*
Y977015D01*
X1327589Y976970D01*
G03Y975724I1133J-623D01*
G01X1327614Y975679D01*
Y970609D01*
X1327589Y970564D01*
G03X1327428Y969939I1131J-625D01*
G03X1327589Y969314I1292J0D01*
G01X1327614Y969269D01*
Y964200D01*
X1327589Y964155D01*
G03X1327428Y963530I1131J-625D01*
G03X1327589Y962905I1292J0D01*
G01X1327614Y962860D01*
Y957792D01*
X1327589Y957747D01*
G03X1327428Y957122I1131J-625D01*
G03X1327589Y956497I1292J0D01*
G01X1327614Y956452D01*
Y951383D01*
X1327589Y951338D01*
G03X1327428Y950713I1131J-625D01*
G03X1327589Y950088I1292J0D01*
G01X1327614Y950043D01*
Y944974D01*
X1327589Y944929D01*
G03X1327428Y944304I1131J-625D01*
G03X1327589Y943679I1292J0D01*
G01X1327614Y943634D01*
Y938566D01*
X1327589Y938521D01*
G03X1327428Y937896I1131J-625D01*
G03X1327589Y937271I1292J0D01*
G01X1327614Y937226D01*
Y932158D01*
X1327589Y932113D01*
G03X1327428Y931488I1131J-625D01*
G03X1327589Y930863I1292J0D01*
G01X1327614Y930818D01*
Y925749D01*
X1327589Y925704D01*
G03X1327428Y925079I1131J-625D01*
G03X1327589Y924454I1292J0D01*
G01X1327614Y924409D01*
Y919340D01*
X1327589Y919295D01*
G03X1327428Y918670I1131J-625D01*
G03X1327589Y918045I1292J0D01*
G01X1327614Y918000D01*
Y915664D01*
G03X1327907Y914957I999J0D01*
G01X1331420Y911444D01*
G03X1331595Y911267I1002J816D01*
G01X1331603Y911261D01*
X1333149Y909715D01*
X1333092Y909589D01*
G03X1332978Y909057I1178J-531D01*
G03X1334270Y907765I1292J0D01*
G03X1334802Y907879I1J1292D01*
G01X1334928Y907936D01*
X1340389Y902475D01*
X1340401Y902414D01*
G03X1341436Y901379I1270J235D01*
G01X1341497Y901367D01*
X1342550Y900314D01*
X1342455Y900177D01*
G03X1342228Y899445I1065J-732D01*
G03X1343520Y898153I1292J0D01*
G03X1344252Y898380I0J1292D01*
G01X1344389Y898475D01*
X1349639Y893225D01*
X1349632Y893134D01*
G03X1349628Y893036I1288J-102D01*
G03X1350920Y891744I1292J0D01*
G03X1351018Y891748I-4J1292D01*
G01X1351109Y891755D01*
X1356714Y886150D01*
Y885399D01*
X1356319Y884715D01*
X1356229Y884698D01*
G03X1355174Y883423I243J-1275D01*
G03X1356351Y882131I1298J0D01*
G02X1356714Y881733I-37J-398D01*
G01Y872582D01*
X1356319Y871898D01*
X1356229Y871881D01*
G03X1355174Y870606I243J-1275D01*
G03X1356351Y869314I1298J0D01*
G02X1356714Y868916I-37J-398D01*
G01Y868494D01*
X1356301Y868081D01*
G02X1355689Y868137I-283J283D01*
G03X1354862Y868676I-1069J-736D01*
G01X1354772Y868693D01*
X1353965Y870091D01*
X1353996Y870177D01*
G03X1354068Y870606I-1225J426D01*
G03X1351474I-1297J0D01*
G03X1352529Y869331I1298J0D01*
G01X1352619Y869314D01*
X1353426Y867916D01*
X1353395Y867830D01*
G03X1353322Y867401I1224J-429D01*
G03X1353884Y866332I1298J0D01*
G02X1353940Y865720I-227J-329D01*
G01X1353496Y865276D01*
X1353366Y865344D01*
G03X1352771Y865489I-595J-1148D01*
G03X1351479Y864197I0J-1292D01*
G03X1351624Y863602I1293J0D01*
G01X1351692Y863472D01*
X1350404Y862184D01*
X1350372Y862169D01*
G03X1349744Y861541I548J-1176D01*
G01X1349729Y861509D01*
X1348217Y859997D01*
X1345109D01*
G02X1344735Y860537I1J400D01*
G03X1344818Y860993I-1215J457D01*
G03X1342222I-1298J0D01*
G03X1342295Y860565I1298J1D01*
G01X1342326Y860478D01*
X1342048Y859997D01*
X1337709D01*
G02X1337335Y860537I1J400D01*
G03X1337418Y860993I-1215J457D01*
G03X1334822I-1298J0D01*
G03X1334895Y860565I1298J1D01*
G01X1334926Y860478D01*
X1334648Y859997D01*
X1330309D01*
G02X1329935Y860537I1J400D01*
G03X1330018Y860993I-1215J457D01*
G03X1327422I-1298J0D01*
G03X1327495Y860565I1298J1D01*
G01X1327526Y860478D01*
X1327248Y859997D01*
X1123179D01*
X1121400Y861776D01*
Y1256162D01*
G03X1121107Y1256869I-999J0D01*
G01X1120144Y1257832D01*
G03X1119823Y1258048I-708J-706D01*
G01X1119700Y1258099D01*
Y1382158D01*
X1122358Y1384816D01*
X1123324D01*
X1123373Y1384689D01*
G03X1124679Y1383798I1306J512D01*
G03X1125652Y1384190I1J1402D01*
G02X1126206I277J-288D01*
G03X1127179Y1383798I972J1010D01*
G03X1128171Y1384209I0J1403D01*
G02X1128737I283J-282D01*
G03X1129729Y1383798I992J992D01*
G03X1131035Y1384689I0J1403D01*
G01X1131084Y1384816D01*
X1142892D01*
X1142941Y1384689D01*
G03X1144247Y1383798I1306J512D01*
G03X1145239Y1384209I0J1403D01*
G02X1145805I283J-282D01*
G03X1146797Y1383798I992J992D01*
G03X1147770Y1384190I1J1402D01*
G02X1148324I277J-288D01*
G03X1149297Y1383798I972J1010D01*
G03X1150603Y1384689I0J1403D01*
G01X1150652Y1384816D01*
X1161424D01*
X1161473Y1384689D01*
G03X1162779Y1383798I1306J512D01*
G03X1163752Y1384190I1J1402D01*
G02X1164306I277J-288D01*
G03X1165279Y1383798I972J1010D01*
G03X1166271Y1384209I0J1403D01*
G02X1166837I283J-282D01*
G03X1167829Y1383798I992J992D01*
G03X1169135Y1384689I0J1403D01*
G01X1169184Y1384816D01*
X1181392D01*
X1181441Y1384689D01*
G03X1182747Y1383798I1306J512D01*
G03X1183739Y1384209I0J1403D01*
G02X1184305I283J-282D01*
G03X1185297Y1383798I992J992D01*
G03X1186270Y1384190I1J1402D01*
G02X1186824I277J-288D01*
G03X1187797Y1383798I972J1010D01*
G03X1189103Y1384689I0J1403D01*
G01X1189152Y1384816D01*
G37*
G36*
G01X1357028Y1054264D02*
X1379652D01*
X1379664Y1054076D01*
G03X1380953Y1052865I1289J81D01*
G03X1381305Y1052914I0J1292D01*
G01X1381418Y1052946D01*
X1386214Y1048150D01*
Y1045811D01*
X1386080Y1045764D01*
G03Y1043324I423J-1220D01*
G01X1386214Y1043277D01*
Y1031564D01*
G03X1386714Y1030698I1000J0D01*
G01Y1029813D01*
G03X1386415Y1028854I1388J-959D01*
G03X1388027Y1027169I1687J0D01*
G01X1388105Y1027165D01*
X1388960Y1026310D01*
G03X1388993Y1026281I346J361D01*
G01X1389001Y1026274D01*
X1389526Y1025748D01*
X1389518Y1025655D01*
G03X1389514Y1025564I996J-89D01*
G01Y1012178D01*
X1388100Y1010764D01*
X1384299D01*
G03X1384272Y1010792I-733J-680D01*
G01X1383014Y1012050D01*
Y1025664D01*
G03X1382721Y1026371I-999J0D01*
G01X1382426Y1026666D01*
X1382430Y1026755D01*
G03X1382432Y1026821I-1290J72D01*
G03X1381140Y1028113I-1292J0D01*
G03X1381074Y1028111I6J-1292D01*
G01X1380985Y1028107D01*
X1380521Y1028571D01*
G03X1379814Y1028864I-707J-706D01*
G01X1378507D01*
X1378457Y1028991D01*
G03X1376049I-1204J-468D01*
G01X1375999Y1028864D01*
X1374807D01*
X1374757Y1028991D01*
G03X1372349I-1204J-468D01*
G01X1372299Y1028864D01*
X1371107D01*
X1371057Y1028991D01*
G03X1368649I-1204J-468D01*
G01X1368599Y1028864D01*
X1367407D01*
X1367357Y1028991D01*
G03X1364949I-1204J-468D01*
G01X1364899Y1028864D01*
X1363707D01*
X1363657Y1028991D01*
G03X1361249I-1204J-468D01*
G01X1361199Y1028864D01*
X1360007D01*
X1359957Y1028991D01*
G03X1358753Y1029815I-1204J-468D01*
G03X1357461Y1028523I0J-1292D01*
G03X1357607Y1027925I1292J-1D01*
G01X1357675Y1027795D01*
X1356381Y1026501D01*
X1356349Y1026486D01*
G03X1355610Y1025318I554J-1168D01*
G03X1355978Y1024415I1292J0D01*
G01Y1019811D01*
G03Y1018009I926J-901D01*
G01Y1013402D01*
G03Y1011600I926J-901D01*
G01Y1006994D01*
G03Y1005192I926J-901D01*
G01Y1000585D01*
G03Y998783I926J-901D01*
G01Y980752D01*
X1355871Y980696D01*
G03Y978408I600J-1144D01*
G01X1355978Y978352D01*
Y974344D01*
X1355871Y974288D01*
G03Y971998I599J-1145D01*
G01X1355978Y971942D01*
Y967935D01*
X1355871Y967879D01*
G03Y965591I600J-1144D01*
G01X1355978Y965535D01*
Y961526D01*
X1355871Y961470D01*
G03Y959182I600J-1144D01*
G01X1355978Y959126D01*
Y955117D01*
X1355871Y955061D01*
G03Y952773I600J-1144D01*
G01X1355978Y952717D01*
Y948709D01*
X1355871Y948653D01*
G03Y946365I600J-1144D01*
G01X1355978Y946309D01*
Y942300D01*
X1355871Y942244D01*
G03Y939956I600J-1144D01*
G01X1355978Y939900D01*
Y935891D01*
X1355871Y935835D01*
G03Y933547I600J-1144D01*
G01X1355978Y933491D01*
Y929483D01*
X1355871Y929427D01*
G03Y927139I600J-1144D01*
G01X1355978Y927083D01*
Y924954D01*
G03X1356271Y924247I999J0D01*
G01X1358905Y921613D01*
X1358918Y921560D01*
G03X1359856Y920622I1253J315D01*
G01X1359909Y920609D01*
X1361018Y919500D01*
X1360932Y919365D01*
G03X1360729Y918670I1088J-695D01*
G03X1362021Y917378I1292J0D01*
G03X1362716Y917581I0J1291D01*
G01X1362851Y917667D01*
X1368131Y912387D01*
X1368129Y912301D01*
G03X1368128Y912262I1291J-53D01*
G03X1369420Y910970I1292J0D01*
G03X1369459Y910971I-14J1292D01*
G01X1369545Y910973D01*
X1377445Y903073D01*
X1377418Y902963D01*
G03X1377379Y902649I1253J-315D01*
G03X1378671Y901357I1292J0D01*
G03X1378985Y901396I-1J1292D01*
G01X1379095Y901423D01*
X1384971Y895547D01*
Y890512D01*
X1384945Y890466D01*
G03X1384779Y889832I1126J-634D01*
G03X1384945Y889198I1292J0D01*
G01X1384971Y889152D01*
Y884113D01*
X1384945Y884067D01*
G03Y882779I1127J-644D01*
G01X1384971Y882733D01*
Y881880D01*
G02X1384488Y881488I-400J-1D01*
G03X1384461Y881494I-295J-1263D01*
G01X1384371Y881511D01*
X1383565Y882908D01*
X1383596Y882994D01*
G03X1383668Y883423I-1225J426D01*
G03X1381074I-1297J0D01*
G03X1382129Y882148I1298J0D01*
G01X1382219Y882131D01*
X1383025Y880734D01*
X1382995Y880647D01*
G03X1382922Y880219I1225J-429D01*
G03X1384220Y878922I1297J0D01*
G03X1384488Y878950I0J1297D01*
G02X1384971Y878558I83J-391D01*
G01Y877694D01*
X1384945Y877648D01*
G03X1384779Y877014I1126J-634D01*
G03X1384945Y876380I1292J0D01*
G01X1384971Y876334D01*
Y874363D01*
X1382507Y871899D01*
X1382420Y871903D01*
G03X1382371Y871904I-51J-1297D01*
G03X1381074Y870606I0J-1297D01*
G01Y870557D01*
X1381078Y870470D01*
X1378574Y867966D01*
G02X1377944Y868049I-283J282D01*
G03X1377062Y868676I-1124J-648D01*
G01X1376972Y868693D01*
X1376165Y870091D01*
X1376196Y870177D01*
G03X1376268Y870606I-1225J426D01*
G03X1373674I-1297J0D01*
G03X1374729Y869331I1298J0D01*
G01X1374819Y869314D01*
X1375626Y867916D01*
X1375595Y867830D01*
G03X1375522Y867401I1224J-429D01*
G03X1376172Y866277I1297J0D01*
G02X1376255Y865647I-199J-347D01*
G01X1375805Y865197D01*
X1375669Y865284D01*
G03X1374971Y865489I-698J-1086D01*
G03X1373679Y864197I0J-1292D01*
G03X1373884Y863499I1291J0D01*
G01X1373971Y863363D01*
X1373835Y863227D01*
G03X1373542Y862520I706J-707D01*
G01Y862274D01*
X1373327D01*
X1373312Y862276D01*
G03X1373120Y862290I-190J-1283D01*
G03X1371822Y860993I0J-1298D01*
G03X1371895Y860565I1298J1D01*
G01X1371926Y860478D01*
X1371119Y859081D01*
X1371029Y859064D01*
G03X1369974Y857789I243J-1275D01*
G03X1372568I1297J0D01*
G03X1372496Y858217I-1297J2D01*
G01X1372465Y858304D01*
X1372796Y858876D01*
G02X1373542Y858676I346J-200D01*
G01Y849873D01*
G02X1373137Y849473I-400J0D01*
G03X1373120Y849474I-85J-1293D01*
G03X1371822Y848176I0J-1298D01*
G03X1372878Y846901I1298J0D01*
G01X1372968Y846884D01*
X1373542Y845889D01*
Y745470D01*
G03X1373835Y744763I999J0D01*
G01X1376073Y742525D01*
G03X1376780Y742232I707J706D01*
G01X1398006D01*
X1399940Y740298D01*
Y687042D01*
G03X1400233Y686335I999J0D01*
G01X1468076Y618492D01*
G03X1468783Y618199I707J706D01*
G01X1612228D01*
X1614042Y616385D01*
Y587013D01*
X1612335Y585306D01*
G03X1612176Y585099I707J-707D01*
G01X1608020D01*
G03X1606380I-820J-1136D01*
G01X1562761D01*
G03X1560227I-1267J-807D01*
G01X1401697D01*
X1254220Y732576D01*
Y763305D01*
X1255187D01*
G03Y765305I0J1000D01*
G01X1254220D01*
Y766608D01*
G03Y766618I-1000J5D01*
G03Y766628I-1000J5D01*
G01Y856004D01*
X1256213Y857997D01*
X1325574D01*
Y857796D01*
Y857789D01*
G03X1328168I1297J0D01*
G01Y857796D01*
Y857997D01*
X1329274D01*
Y857796D01*
Y857789D01*
G03X1330329Y856514I1298J0D01*
G01X1330419Y856497D01*
X1331226Y855099D01*
X1331195Y855013D01*
G03X1331122Y854584I1224J-429D01*
G03X1333718I1298J0D01*
G03X1332662Y855859I-1298J0D01*
G01X1332572Y855876D01*
X1331765Y857274D01*
X1331796Y857360D01*
G03X1331868Y857789I-1225J426D01*
G01Y857796D01*
Y857997D01*
X1332974D01*
Y857796D01*
Y857789D01*
G03X1335568I1297J0D01*
G01Y857796D01*
Y857997D01*
X1336674D01*
Y857796D01*
Y857789D01*
G03X1337729Y856514I1298J0D01*
G01X1337819Y856497D01*
X1338626Y855099D01*
X1338595Y855013D01*
G03X1338522Y854584I1224J-429D01*
G03X1341118I1298J0D01*
G03X1340062Y855859I-1298J0D01*
G01X1339972Y855876D01*
X1339165Y857274D01*
X1339196Y857360D01*
G03X1339268Y857789I-1225J426D01*
G01Y857796D01*
Y857997D01*
X1340374D01*
Y857796D01*
Y857789D01*
G03X1342968I1297J0D01*
G01Y857796D01*
Y857997D01*
X1344074D01*
Y857796D01*
Y857789D01*
G03X1345129Y856514I1298J0D01*
G01X1345219Y856497D01*
X1346026Y855099D01*
X1345995Y855013D01*
G03X1345922Y854584I1224J-429D01*
G03X1348518I1298J0D01*
G03X1347462Y855859I-1298J0D01*
G01X1347372Y855876D01*
X1346565Y857274D01*
X1346596Y857360D01*
G03X1346668Y857789I-1225J426D01*
G01Y857796D01*
Y857997D01*
X1347774D01*
Y857796D01*
Y857789D01*
G03X1350368I1297J0D01*
G03X1350296Y858217I-1297J2D01*
G01X1350265Y858304D01*
X1351072Y859701D01*
X1351162Y859718D01*
G03X1352218Y860993I-242J1275D01*
G03X1352215Y861072I-1298J-10D01*
G01X1352210Y861162D01*
X1357466Y866418D01*
X1357603Y866327D01*
G03X1358321Y866109I718J1073D01*
G03X1359613Y867401I0J1292D01*
G03X1358835Y868587I-1293J0D01*
G01X1358714Y868639D01*
Y869278D01*
G02X1359363Y869591I400J0D01*
G03X1359929Y869331I809J1015D01*
G01X1360019Y869314D01*
X1360826Y867916D01*
X1360795Y867830D01*
G03X1360722Y867401I1224J-429D01*
G03X1363318I1298J0D01*
G03X1362262Y868676I-1298J0D01*
G01X1362172Y868693D01*
X1361365Y870091D01*
X1361396Y870177D01*
G03X1361468Y870606I-1225J426D01*
G03X1360171Y871904I-1298J0D01*
G03X1359363Y871621I1J-1298D01*
G02X1358714Y871934I-249J313D01*
G01Y872567D01*
X1358835Y872619D01*
G03Y875001I-514J1191D01*
G01X1358714Y875053D01*
Y878981D01*
X1358835Y879033D01*
G03Y881405I-515J1186D01*
G01X1358714Y881457D01*
Y882095D01*
G02X1359363Y882408I400J0D01*
G03X1359929Y882148I809J1015D01*
G01X1360019Y882131D01*
X1360825Y880734D01*
X1360795Y880647D01*
G03X1360722Y880219I1225J-429D01*
G03X1363318I1298J0D01*
G03X1362261Y881494I-1297J0D01*
G01X1362171Y881511D01*
X1361365Y882908D01*
X1361396Y882994D01*
G03X1361468Y883423I-1225J426D01*
G03X1360171Y884720I-1297J0D01*
G03X1359363Y884438I0J-1297D01*
G02X1358714Y884751I-249J313D01*
G01Y885384D01*
X1358835Y885436D01*
G03X1359618Y886627I-514J1191D01*
G03X1358320Y887924I-1297J0D01*
G03X1357963Y887874I0J-1297D01*
G01X1357850Y887842D01*
X1352074Y893618D01*
X1352060Y893644D01*
G03X1351528Y894176I-1140J-608D01*
G01X1351502Y894190D01*
X1350161Y895531D01*
X1350226Y895660D01*
G03X1350363Y896240I-1155J579D01*
G03X1349071Y897532I-1292J0D01*
G03X1348491Y897395I-1J-1292D01*
G01X1348362Y897330D01*
X1342962Y902730D01*
X1342954Y902799D01*
G03X1341821Y903932I-1283J-150D01*
G01X1341752Y903940D01*
X1340751Y904941D01*
X1340855Y905079D01*
G03X1341112Y905853I-1035J773D01*
G03X1339820Y907145I-1292J0D01*
G03X1339046Y906888I-1J-1292D01*
G01X1338908Y906784D01*
X1333689Y912003D01*
X1333702Y912100D01*
G03X1333712Y912262I-1282J160D01*
G03X1332420Y913554I-1292J0D01*
G03X1332258Y913544I-2J-1292D01*
G01X1332161Y913531D01*
X1329614Y916078D01*
Y917737D01*
G03Y919603I-895J933D01*
G01Y924146D01*
G03Y926012I-895J933D01*
G01Y930555D01*
G03Y932421I-895J933D01*
G01Y936963D01*
G03Y938829I-895J933D01*
G01Y943371D01*
G03Y945237I-895J933D01*
G01Y949780D01*
G03Y951646I-895J933D01*
G01Y956189D01*
G03Y958055I-895J933D01*
G01Y962597D01*
G03Y964463I-895J933D01*
G01Y969006D01*
G03Y970872I-895J933D01*
G01Y975413D01*
G03Y977281I-894J934D01*
G01Y981823D01*
G03Y983689I-895J933D01*
G01Y1001675D01*
X1329725Y1001730D01*
G03Y1004046I-571J1158D01*
G01X1329614Y1004101D01*
Y1008084D01*
X1329725Y1008139D01*
G03Y1010455I-571J1158D01*
G01X1329614Y1010510D01*
Y1014492D01*
X1329725Y1014547D01*
G03Y1016863I-571J1158D01*
G01X1329614Y1016918D01*
Y1020901D01*
X1329725Y1020956D01*
G03Y1023272I-571J1158D01*
G01X1329614Y1023327D01*
Y1026850D01*
X1336408Y1033644D01*
X1336496Y1033640D01*
G03X1336553Y1033639I51J1291D01*
G03X1337845Y1034931I0J1292D01*
G03X1337844Y1034988I-1292J6D01*
G01X1337840Y1035076D01*
X1343111Y1040347D01*
X1343247Y1040258D01*
G03X1343953Y1040048I706J1082D01*
G03X1345245Y1041340I0J1292D01*
G03X1345035Y1042046I-1292J0D01*
G01X1344946Y1042182D01*
X1346036Y1043272D01*
X1346092Y1043284D01*
G03X1347064Y1044256I-288J1260D01*
G01X1347076Y1044312D01*
X1352578Y1049814D01*
X1352702Y1049762D01*
G03X1353204Y1049660I503J1190D01*
G03X1354496Y1050952I0J1292D01*
G03X1354394Y1051454I-1292J-1D01*
G01X1354342Y1051578D01*
X1357028Y1054264D01*
G37*
G36*
G01X1272064Y1308048D02*
X1298190D01*
X1324490Y1281748D01*
G03X1325197Y1281455I707J706D01*
G01X1335043D01*
X1345641Y1270857D01*
G03X1346348Y1270564I707J706D01*
G01X1468514D01*
G03X1469221Y1270857I0J999D01*
G01X1471821Y1273457D01*
G03X1472114Y1274164I-706J707D01*
G01Y1279050D01*
X1477528Y1284464D01*
X1492266D01*
G03X1492973Y1284757I0J999D01*
G01X1508031Y1299815D01*
X1544393D01*
X1545707Y1298501D01*
Y1166619D01*
X1518161Y1139073D01*
X1503030D01*
X1502350Y1140359D01*
X1502389Y1140448D01*
G03X1502500Y1140973I-1186J525D01*
G03X1499906I-1297J0D01*
G03X1500968Y1139697I1298J0D01*
G01X1501063Y1139679D01*
X1501229Y1139366D01*
G02X1501052Y1139073I-177J-93D01*
G01X1495630D01*
X1494950Y1140359D01*
X1494989Y1140448D01*
G03X1495100Y1140973I-1186J525D01*
G03X1492506I-1297J0D01*
G03X1493568Y1139697I1298J0D01*
G01X1493663Y1139679D01*
X1493829Y1139366D01*
G02X1493652Y1139073I-177J-93D01*
G01X1488230D01*
X1487550Y1140359D01*
X1487589Y1140448D01*
G03X1487700Y1140973I-1186J525D01*
G03X1485106I-1297J0D01*
G03X1486168Y1139697I1298J0D01*
G01X1486263Y1139679D01*
X1486429Y1139366D01*
G02X1486252Y1139073I-177J-93D01*
G01X1480830D01*
X1480150Y1140359D01*
X1480189Y1140448D01*
G03X1480300Y1140973I-1186J525D01*
G03X1477706I-1297J0D01*
G03X1478768Y1139697I1298J0D01*
G01X1478863Y1139679D01*
X1479029Y1139366D01*
G02X1478852Y1139073I-177J-93D01*
G01X1473430D01*
X1472750Y1140359D01*
X1472789Y1140448D01*
G03X1472900Y1140973I-1186J525D01*
G03X1470306I-1297J0D01*
G03X1471368Y1139697I1298J0D01*
G01X1471463Y1139679D01*
X1471629Y1139366D01*
G02X1471452Y1139073I-177J-93D01*
G01X1466030D01*
X1465350Y1140359D01*
X1465389Y1140448D01*
G03X1465500Y1140973I-1186J525D01*
G03X1462906I-1297J0D01*
G03X1463968Y1139697I1298J0D01*
G01X1464063Y1139679D01*
X1464229Y1139366D01*
G02X1464052Y1139073I-177J-93D01*
G01X1458630D01*
X1457950Y1140359D01*
X1457989Y1140448D01*
G03X1458100Y1140973I-1186J525D01*
G03X1455506I-1297J0D01*
G03X1456568Y1139697I1298J0D01*
G01X1456663Y1139679D01*
X1456829Y1139366D01*
G02X1456652Y1139073I-177J-93D01*
G01X1455521D01*
G03X1454814Y1138780I0J-999D01*
G01X1454790Y1138756D01*
G03X1453656Y1137469I163J-1287D01*
G03X1453700Y1137138I1297J4D01*
G01X1453721Y1137058D01*
X1452849Y1135539D01*
X1452769Y1135518D01*
G03X1451806Y1134264I335J-1254D01*
G03X1451853Y1133920I1298J2D01*
G01X1451875Y1133840D01*
X1451010Y1132332D01*
X1450929Y1132311D01*
G03X1449961Y1131060I324J-1251D01*
G03X1450010Y1130708I1292J0D01*
G01X1450033Y1130627D01*
X1449178Y1129137D01*
X1449095Y1129116D01*
G03X1448106Y1127856I308J-1260D01*
G03X1448160Y1127486I1298J0D01*
G01X1448185Y1127404D01*
X1447342Y1125934D01*
X1447257Y1125914D01*
G03X1446256Y1124651I296J-1263D01*
G03X1446313Y1124268I1297J-3D01*
G01X1446339Y1124185D01*
X1445506Y1122732D01*
X1445420Y1122713D01*
G03X1444406Y1121447I283J-1266D01*
G03X1444468Y1121053I1298J2D01*
G01X1444495Y1120969D01*
X1443666Y1119525D01*
X1443580Y1119506D01*
G03X1442561Y1118243I273J-1263D01*
G03X1442625Y1117841I1292J0D01*
G01X1442653Y1117757D01*
X1441830Y1116322D01*
X1441742Y1116304D01*
G03X1440712Y1115039I262J-1265D01*
G03X1440780Y1114626I1292J1D01*
G01X1440809Y1114541D01*
X1439994Y1113119D01*
X1439904Y1113102D01*
G03X1438862Y1111834I251J-1268D01*
G03X1438934Y1111409I1292J0D01*
G01X1438964Y1111323D01*
X1438157Y1109917D01*
X1438067Y1109900D01*
G03X1437012Y1108630I237J-1270D01*
G03X1437088Y1108193I1292J0D01*
G01X1437119Y1108107D01*
X1436321Y1106715D01*
X1436229Y1106698D01*
G03X1435162Y1105426I225J-1272D01*
G03X1435242Y1104978I1292J0D01*
G01X1435275Y1104890D01*
X1434484Y1103511D01*
X1434391Y1103495D01*
G03X1433312Y1102221I213J-1274D01*
G03X1433396Y1101762I1292J-1D01*
G01X1433430Y1101673D01*
X1432648Y1100308D01*
X1432553Y1100293D01*
G03X1431461Y1099017I200J-1276D01*
G03X1431914Y1098034I1293J0D01*
G01Y1093589D01*
G03Y1091625I841J-982D01*
G01Y1087183D01*
G03Y1085217I840J-983D01*
G01Y1080773D01*
G03Y1078809I841J-982D01*
G01Y1074366D01*
G03Y1072400I840J-983D01*
G01Y1067957D01*
G03Y1065991I840J-983D01*
G01Y1061548D01*
G03Y1059582I840J-983D01*
G01Y1055140D01*
G03Y1053174I840J-983D01*
G01Y1048732D01*
G03Y1046766I840J-983D01*
G01Y1042323D01*
G03Y1040357I840J-983D01*
G01Y1028264D01*
G03X1432207Y1027557I999J0D01*
G01X1434807Y1024957D01*
G03X1435514Y1024664I707J706D01*
G01X1450800D01*
X1451429Y1024035D01*
G02X1451446Y1023488I-283J-283D01*
G03X1451124Y1022635I969J-853D01*
G03X1451808Y1021495I1292J0D01*
G01X1451914Y1021438D01*
Y1018717D01*
X1451809Y1018660D01*
G03Y1016390I617J-1135D01*
G01X1451914Y1016333D01*
Y1014117D01*
X1451809Y1014060D01*
G03X1451134Y1012925I617J-1135D01*
G03X1451529Y1011995I1292J0D01*
G02X1451531Y1011422I-278J-287D01*
G03X1451144Y1010499I905J-922D01*
G03X1451811Y1009368I1292J0D01*
G01X1451914Y1009311D01*
Y1007217D01*
X1451809Y1007160D01*
G03X1451134Y1006025I617J-1135D01*
G03X1451478Y1005147I1292J0D01*
G02Y1004603I-293J-272D01*
G03X1451134Y1003725I948J-878D01*
G03X1451809Y1002590I1292J0D01*
G01X1451914Y1002533D01*
Y998017D01*
X1451809Y997960D01*
G03X1451134Y996825I617J-1135D01*
G03X1451478Y995947I1292J0D01*
G02Y995403I-293J-272D01*
G03X1451134Y994525I948J-878D01*
G03X1451809Y993390I1292J0D01*
G01X1451914Y993333D01*
Y991117D01*
X1451809Y991060D01*
G03X1451134Y989925I617J-1135D01*
G03X1451478Y989047I1292J0D01*
G02Y988503I-293J-272D01*
G03X1451134Y987625I948J-878D01*
G03X1451809Y986490I1292J0D01*
G01X1451914Y986433D01*
Y981899D01*
G03X1451187Y980821I562J-1163D01*
G01X1451182Y980746D01*
X1443107Y972671D01*
G03X1442814Y971964I706J-707D01*
G01Y964164D01*
G03X1443107Y963457I999J0D01*
G01X1448207Y958357D01*
G03X1448914Y958064I707J706D01*
G01X1451100D01*
X1451614Y957550D01*
Y955078D01*
X1450000Y953464D01*
X1439714D01*
G03X1439007Y953171I0J-999D01*
G01X1431507Y945671D01*
G03X1431214Y944964I706J-707D01*
G01Y939778D01*
X1429800Y938364D01*
X1426131D01*
X1426075Y938474D01*
G03X1423765I-1155J-577D01*
G01X1423709Y938364D01*
X1422431D01*
X1422375Y938474D01*
G03X1420065I-1155J-577D01*
G01X1420009Y938364D01*
X1418731D01*
X1418675Y938474D01*
G03X1416365I-1155J-577D01*
G01X1416309Y938364D01*
X1415031D01*
X1414975Y938474D01*
G03X1412665I-1155J-577D01*
G01X1412609Y938364D01*
X1411331D01*
X1411275Y938474D01*
G03X1408965I-1155J-577D01*
G01X1408909Y938364D01*
X1407631D01*
X1407575Y938474D01*
G03X1405265I-1155J-577D01*
G01X1405209Y938364D01*
X1387528D01*
X1382814Y943078D01*
Y965450D01*
X1384328Y966964D01*
X1388714D01*
G03X1389421Y967257I0J999D01*
G01X1390721Y968557D01*
G03X1391014Y969264I-706J707D01*
G01Y969945D01*
X1391119Y970002D01*
G03Y972276I-612J1137D01*
G01X1391014Y972333D01*
Y973964D01*
G03X1390721Y974671I-999J0D01*
G01X1388221Y977171D01*
G03X1387514Y977464I-707J-706D01*
G01X1384328D01*
X1383014Y978778D01*
Y1007513D01*
X1384265Y1008764D01*
X1388514D01*
G03X1389221Y1009057I0J999D01*
G01X1391221Y1011057D01*
G03X1391514Y1011764I-706J707D01*
G01Y1013252D01*
X1391662Y1013291D01*
G03Y1015787I-337J1248D01*
G01X1391514Y1015826D01*
Y1025150D01*
X1392191Y1025827D01*
X1399878D01*
G03X1400585Y1026120I0J999D01*
G01X1401643Y1027178D01*
G03X1401936Y1027885I-706J707D01*
G01Y1029303D01*
G03X1401643Y1030010I-999J0D01*
G01X1400302Y1031351D01*
G03X1399595Y1031644I-707J-706D01*
G01X1398796D01*
X1398066Y1032374D01*
Y1037399D01*
X1402545Y1041878D01*
G03X1402838Y1042585I-706J707D01*
G01Y1084098D01*
X1403306Y1084908D01*
X1403396Y1084925D01*
G03X1404452Y1086200I-242J1275D01*
G03X1403218Y1087496I-1298J0D01*
G02X1402838Y1087895I20J399D01*
G01Y1090913D01*
G02X1403218Y1091312I400J0D01*
G03X1404192Y1091830I-65J1296D01*
G01X1405814D01*
G03X1406853Y1091310I1039J778D01*
G03Y1093906I0J1298D01*
G03X1405814Y1093386I0J-1298D01*
G01X1404192D01*
G03X1403218Y1093904I-1039J-778D01*
G02X1402838Y1094303I20J399D01*
G01Y1102381D01*
G03X1402545Y1103088I-999J0D01*
G01X1400666Y1104967D01*
X1400698Y1105079D01*
G03X1400745Y1105426I-1245J345D01*
G03X1399453Y1106718I-1292J0D01*
G03X1399106Y1106671I-2J-1292D01*
G01X1398994Y1106639D01*
X1395607Y1110026D01*
X1395905Y1110542D01*
X1395995Y1110559D01*
G03X1397050Y1111834I-243J1275D01*
G03X1395753Y1113132I-1298J0D01*
G03X1394474Y1112052I0J-1297D01*
G02X1393797Y1111836I-394J67D01*
G01X1393209Y1112424D01*
X1393195Y1112450D01*
G03X1392669Y1112976I-1142J-616D01*
G01X1392643Y1112990D01*
X1391794Y1113839D01*
X1391398Y1114524D01*
X1391429Y1114611D01*
G03X1391502Y1115039I-1225J429D01*
G03X1390204Y1116336I-1297J0D01*
G03X1389626Y1116200I0J-1296D01*
G01X1389497Y1116136D01*
X1388032Y1117601D01*
Y1134521D01*
G03X1387739Y1135228I-999J0D01*
G01X1385894Y1137073D01*
X1385919Y1137180D01*
G03X1385952Y1137469I-1265J291D01*
G03X1384654Y1138766I-1297J0D01*
G03X1384261Y1138706I-3J-1297D01*
G03X1383576Y1138977I-684J-729D01*
G01X1383235D01*
G02X1382881Y1139564I0J400D01*
G01X1382943Y1139679D01*
X1383038Y1139697D01*
G03X1384100Y1140973I-236J1276D01*
G03X1381506I-1297J0D01*
G03X1381617Y1140447I1297J-1D01*
G01X1381656Y1140358D01*
X1380928Y1138977D01*
X1375835D01*
G02X1375481Y1139564I0J400D01*
G01X1375543Y1139679D01*
X1375638Y1139697D01*
G03X1376700Y1140973I-236J1276D01*
G03X1374106I-1297J0D01*
G03X1374217Y1140447I1297J-1D01*
G01X1374256Y1140358D01*
X1373528Y1138977D01*
X1368435D01*
G02X1368081Y1139564I0J400D01*
G01X1368143Y1139679D01*
X1368238Y1139697D01*
G03X1369300Y1140973I-236J1276D01*
G03X1366706I-1297J0D01*
G03X1366817Y1140447I1297J-1D01*
G01X1366856Y1140358D01*
X1366128Y1138977D01*
X1361035D01*
G02X1360681Y1139564I0J400D01*
G01X1360743Y1139679D01*
X1360838Y1139697D01*
G03X1361900Y1140973I-236J1276D01*
G03X1359306I-1297J0D01*
G03X1359417Y1140447I1297J-1D01*
G01X1359456Y1140358D01*
X1358728Y1138977D01*
X1353635D01*
G02X1353281Y1139564I0J400D01*
G01X1353343Y1139679D01*
X1353438Y1139697D01*
G03X1354500Y1140973I-236J1276D01*
G03X1351906I-1297J0D01*
G03X1352017Y1140447I1297J-1D01*
G01X1352056Y1140358D01*
X1351328Y1138977D01*
X1346235D01*
G02X1345881Y1139564I0J400D01*
G01X1345943Y1139679D01*
X1346038Y1139697D01*
G03X1347100Y1140973I-236J1276D01*
G03X1344506I-1297J0D01*
G03X1344617Y1140447I1297J-1D01*
G01X1344656Y1140358D01*
X1343928Y1138977D01*
X1338835D01*
G02X1338481Y1139564I0J400D01*
G01X1338543Y1139679D01*
X1338638Y1139697D01*
G03X1339700Y1140973I-236J1276D01*
G03X1337106I-1297J0D01*
G03X1337217Y1140447I1297J-1D01*
G01X1337256Y1140358D01*
X1336528Y1138977D01*
X1300799D01*
X1270587Y1169189D01*
Y1306571D01*
X1272064Y1308048D01*
G37*
G36*
G01X1456804Y1030435D02*
G03X1457538Y1030664I0J1291D01*
G01X1459769D01*
G03X1461237I734J1062D01*
G01X1463470D01*
G03X1464938I734J1062D01*
G01X1467170D01*
G03X1468638I734J1062D01*
G01X1470869D01*
G03X1471603Y1030435I734J1062D01*
G01X1471604D01*
G03X1472291Y1030633I0J1292D01*
G01X1472340Y1030664D01*
X1472614D01*
X1476098Y1027180D01*
Y1022860D01*
G03Y1021368I1056J-746D01*
G01Y1016449D01*
G03Y1014961I1055J-744D01*
G01Y1010043D01*
G03Y1008551I1056J-746D01*
G01Y1003634D01*
G03Y1002142I1056J-746D01*
G01Y983888D01*
G03Y981624I621J-1132D01*
G01Y977479D01*
G03Y975215I621J-1132D01*
G01Y971071D01*
G03Y968807I621J-1132D01*
G01Y964662D01*
G03Y962398I623J-1132D01*
G01Y958254D01*
G03Y955990I621J-1132D01*
G01Y951845D01*
G03Y949581I621J-1132D01*
G01Y945436D01*
G03X1475428Y944304I621J-1132D01*
G03X1475663Y943561I1292J0D01*
G01X1475760Y943424D01*
X1474721Y942385D01*
X1474658Y942374D01*
G03X1473597Y941313I213J-1274D01*
G01X1473586Y941250D01*
X1468141Y935805D01*
X1468014Y935863D01*
G03X1467471Y935983I-544J-1172D01*
G03X1466179Y934691I0J-1292D01*
G03X1466299Y934148I1292J1D01*
G01X1466357Y934021D01*
X1464890Y932554D01*
X1464876Y932545D01*
G03X1464563Y932232I744J-1057D01*
G01X1464554Y932218D01*
X1458642Y926306D01*
X1458532Y926333D01*
G03X1458222Y926371I-311J-1254D01*
G01X1458220D01*
G03X1456928Y925079I0J-1292D01*
G01Y925077D01*
G03X1456966Y924767I1292J1D01*
G01X1456993Y924657D01*
X1449091Y916755D01*
X1449005Y916758D01*
X1448970D01*
G03X1447678Y915466I0J-1292D01*
G01Y915431D01*
X1447681Y915345D01*
X1442398Y910062D01*
X1442263Y910148D01*
G03X1441571Y910349I-692J-1091D01*
G03X1440279Y909057I0J-1292D01*
G03X1440480Y908365I1292J0D01*
G01X1440566Y908230D01*
X1439455Y907119D01*
X1439401Y907105D01*
G03X1438468Y906172I319J-1252D01*
G01X1438454Y906118D01*
X1432928Y900592D01*
X1432806Y900642D01*
G03X1432320Y900737I-486J-1196D01*
G03X1431028Y899445I0J-1292D01*
G03X1431123Y898959I1291J0D01*
G01X1431173Y898837D01*
X1429607Y897271D01*
G03X1429391Y896950I706J-708D01*
G03X1429179Y896242I1080J-709D01*
G01Y896240D01*
G03X1429296Y895703I1291J0D01*
G01X1429314Y895663D01*
Y890409D01*
X1429296Y890369D01*
G03Y889295I1174J-537D01*
G01X1429314Y889255D01*
Y884012D01*
X1429295Y883972D01*
G03X1429174Y883423I1176J-547D01*
G03X1429295Y882874I1297J-2D01*
G01X1429314Y882834D01*
Y881433D01*
X1429080D01*
X1429048Y881444D01*
G03X1428861Y881494I-428J-1225D01*
G01X1428771Y881511D01*
X1427965Y882908D01*
X1427996Y882994D01*
G03X1428068Y883423I-1225J426D01*
G03X1425474I-1297J0D01*
G03X1426529Y882148I1298J0D01*
G01X1426619Y882131D01*
X1427426Y880733D01*
X1427396Y880646D01*
G03X1427324Y880221I1225J-426D01*
G01Y880219D01*
G03X1428621Y878922I1297J0D01*
G03X1428845Y878941I3J1297D01*
G02X1429314Y878547I69J-394D01*
G01Y877591D01*
X1429296Y877551D01*
G03Y876477I1174J-537D01*
G01X1429314Y876437D01*
Y871195D01*
X1429295Y871155D01*
G03X1429174Y870606I1176J-547D01*
G03X1429246Y870178I1297J-2D01*
G01X1429277Y870091D01*
X1428470Y868693D01*
X1428380Y868676D01*
G03X1427322Y867401I239J-1275D01*
G03X1428620Y866104I1297J0D01*
G03X1428845Y866123I4J1297D01*
G02X1429314Y865729I69J-394D01*
G01Y864774D01*
X1429296Y864734D01*
G03Y863660I1174J-537D01*
G01X1429314Y863620D01*
Y858378D01*
X1429295Y858338D01*
G03X1429174Y857789I1176J-547D01*
G03X1429246Y857361I1297J-2D01*
G01X1429277Y857274D01*
X1428470Y855876D01*
X1428380Y855859D01*
G03X1427322Y854584I239J-1275D01*
G03X1428620Y853286I1298J0D01*
G03X1428845Y853306I-2J1298D01*
G02X1429314Y852912I69J-394D01*
G01Y851959D01*
X1429296Y851919D01*
G03X1429178Y851380I1174J-539D01*
G03X1429296Y850841I1292J0D01*
G01X1429314Y850801D01*
Y792111D01*
G03X1429607Y791404I999J0D01*
G01X1566088Y654923D01*
G03X1566795Y654630I707J706D01*
G01X1612780D01*
X1614042Y653368D01*
Y622013D01*
X1612228Y620199D01*
X1469197D01*
X1401940Y687456D01*
Y740712D01*
G03X1401647Y741419I-999J0D01*
G01X1399127Y743939D01*
G03X1398420Y744232I-707J-706D01*
G01X1377194D01*
X1375542Y745884D01*
Y840015D01*
G02X1376149Y840357I400J0D01*
G03X1376819Y840170I671J1110D01*
G01X1376821D01*
G03X1378118Y841467I0J1297D01*
G03X1378007Y841994I-1297J2D01*
G01X1377968Y842082D01*
X1378809Y843677D01*
X1378904Y843695D01*
G03X1379966Y844971I-236J1276D01*
G03X1377372I-1297J0D01*
G03X1377483Y844444I1297J-2D01*
G01X1377522Y844356D01*
X1376681Y842761D01*
X1376586Y842743D01*
G03X1376149Y842577I235J-1276D01*
G02X1375542Y842919I-207J342D01*
G01Y843807D01*
G03Y846135I-574J1164D01*
G01Y850221D01*
G03Y852539I-571J1159D01*
G01Y853132D01*
G02X1376149Y853474I400J0D01*
G03X1376820Y853286I673J1110D01*
G03X1378118Y854584I0J1298D01*
G03X1377062Y855859I-1298J0D01*
G01X1376972Y855876D01*
X1376165Y857274D01*
X1376196Y857360D01*
G03X1376268Y857789I-1225J426D01*
G03X1375542Y858954I-1298J0D01*
G01Y862106D01*
X1379773Y866337D01*
X1379904Y866266D01*
G03X1380521Y866109I617J1134D01*
G03X1381813Y867401I0J1292D01*
G03X1381656Y868018I-1291J0D01*
G01X1381585Y868149D01*
X1382045Y868609D01*
G02X1382674Y868526I283J-283D01*
G01X1383026Y867916D01*
X1382995Y867830D01*
G03X1382922Y867401I1224J-429D01*
G03X1385518I1298J0D01*
G03X1384462Y868676I-1298J0D01*
G01X1384372Y868693D01*
X1383563Y870094D01*
G03X1383586Y870150I-1188J521D01*
G01X1386384Y872948D01*
G02X1386962Y872935I283J-283D01*
G03X1387678Y872535I958J875D01*
G01X1387768Y872518D01*
X1388576Y871119D01*
X1388545Y871032D01*
G03X1388474Y870606I1226J-423D01*
G03X1391068I1297J0D01*
G03X1390010Y871881I-1297J0D01*
G01X1389920Y871898D01*
X1389114Y873295D01*
X1389145Y873381D01*
G03X1389218Y873810I-1224J429D01*
G03X1387920Y875108I-1298J0D01*
G03X1387500Y875038I0J-1298D01*
G02X1386971Y875416I-129J378D01*
G01Y876087D01*
G03Y877941I-900J927D01*
G01Y882488D01*
G03X1387368Y883423I-900J934D01*
G03X1387296Y883851I-1297J2D01*
G01X1387265Y883938D01*
X1388072Y885335D01*
X1388162Y885352D01*
G03X1389218Y886627I-242J1275D01*
G03X1387920Y887924I-1297J0D01*
G03X1387500Y887855I-3J-1297D01*
G02X1386971Y888233I-129J378D01*
G01Y888905D01*
G03Y890759I-900J927D01*
G01Y895313D01*
G03X1387363Y896240I-900J927D01*
G03X1386071Y897532I-1292J0D01*
G03X1385928Y897524I1J-1292D01*
G01X1385833Y897513D01*
X1378010Y905336D01*
X1378048Y905452D01*
G03X1378112Y905853I-1228J402D01*
G03X1376820Y907145I-1292J0D01*
G03X1376419Y907081I1J-1292D01*
G01X1376303Y907043D01*
X1370630Y912716D01*
X1370615Y912753D01*
G03X1369911Y913457I-1195J-491D01*
G01X1369874Y913472D01*
X1368632Y914714D01*
X1368704Y914845D01*
G03X1368863Y915466I-1133J621D01*
G03X1367571Y916758I-1292J0D01*
G03X1366950Y916599I0J-1292D01*
G01X1366819Y916527D01*
X1361465Y921881D01*
X1361460Y921956D01*
G03X1360252Y923164I-1289J-81D01*
G01X1360177Y923169D01*
X1357978Y925368D01*
Y998966D01*
G03Y1000402I-1073J718D01*
G01Y1005375D01*
G03Y1006811I-1073J718D01*
G01Y1011783D01*
G03Y1013219I-1073J718D01*
G01Y1018192D01*
G03Y1019628I-1073J718D01*
G01Y1024603D01*
G03X1358194Y1025318I-1075J715D01*
G03X1358192Y1025390I-1292J0D01*
G01X1358187Y1025479D01*
X1359572Y1026864D01*
X1379400D01*
X1379952Y1026312D01*
X1379967Y1026280D01*
G03X1380599Y1025648I1173J541D01*
G01X1380631Y1025633D01*
X1381014Y1025250D01*
Y1023724D01*
X1380856Y1023690D01*
G03Y1021164I272J-1263D01*
G01X1381014Y1021130D01*
Y1008406D01*
X1380888Y1008355D01*
G03X1380077Y1007156I481J-1199D01*
G03X1380426Y1006273I1292J0D01*
G02X1380427Y1005728I-292J-273D01*
G03X1380081Y1004848I946J-880D01*
G03X1380889Y1003650I1292J0D01*
G01X1381014Y1003600D01*
Y996551D01*
X1380872Y996508D01*
G03X1379951Y995271I370J-1237D01*
G03X1380295Y994393I1292J0D01*
G02Y993849I-293J-272D01*
G03X1379951Y992971I948J-878D01*
G03X1380872Y991734I1291J0D01*
G01X1381014Y991691D01*
Y978364D01*
G03X1381307Y977657I999J0D01*
G01X1383207Y975757D01*
G03X1383914Y975464I707J706D01*
G01X1387100D01*
X1389014Y973550D01*
Y969678D01*
X1388300Y968964D01*
X1383914D01*
G03X1383207Y968671I0J-999D01*
G01X1381665Y967129D01*
X1381557Y967154D01*
G03X1381264Y967188I-294J-1258D01*
G03X1379972Y965896I0J-1292D01*
G03X1380316Y965018I1292J0D01*
G02Y964474I-293J-272D01*
G03X1379972Y963596I948J-878D01*
G03X1380701Y962433I1292J0D01*
G01X1380814Y962378D01*
Y949748D01*
X1380704Y949692D01*
G03X1379995Y948539I583J-1153D01*
G03X1380339Y947661I1292J0D01*
G02Y947117I-293J-272D01*
G03X1379995Y946239I948J-878D01*
G03X1380704Y945086I1292J0D01*
G01X1380814Y945030D01*
Y943299D01*
G03X1380138Y942163I617J-1136D01*
G03X1381430Y940871I1292J0D01*
G01X1381432D01*
G03X1381922Y940968I-1J1292D01*
G01X1382045Y941019D01*
X1386407Y936657D01*
G03X1387114Y936364I707J706D01*
G01X1402718D01*
X1402751Y936205D01*
G03X1405281I1265J264D01*
G01X1405314Y936364D01*
X1430214D01*
G03X1430921Y936657I0J999D01*
G01X1432921Y938657D01*
G03X1433214Y939364I-706J707D01*
G01Y944550D01*
X1440128Y951464D01*
X1450414D01*
G03X1451121Y951757I0J999D01*
G01X1453321Y953957D01*
G03X1453614Y954664I-706J707D01*
G01Y957964D01*
G03X1453321Y958671I-999J0D01*
G01X1452221Y959771D01*
G03X1451514Y960064I-707J-706D01*
G01X1449328D01*
X1444814Y964578D01*
Y971550D01*
X1452732Y979468D01*
X1452787Y979482D01*
G03X1453749Y980513I-311J1254D01*
G03X1453914Y981062I-835J550D01*
G01Y1023966D01*
G03X1453901Y1024126I-1000J-1D01*
G01X1453884Y1024227D01*
X1454768Y1025110D01*
G03X1454914Y1025462I-354J353D01*
G01Y1030257D01*
X1455400Y1030743D01*
G02X1455948Y1030760I283J-283D01*
G03X1456804Y1030435I857J967D01*
G37*
G36*
G01X1448007Y1065764D02*
X1449048D01*
G03X1449914Y1065264I866J500D01*
G01X1495600D01*
X1496403Y1064461D01*
X1496341Y1064333D01*
G03X1496212Y1063770I1164J-563D01*
G03X1497504Y1062478I1292J0D01*
G03X1498067Y1062607I0J1293D01*
G01X1498195Y1062669D01*
X1503615Y1057249D01*
X1503624Y1057182D01*
G03X1504725Y1056081I1280J179D01*
G01X1504792Y1056072D01*
X1505817Y1055047D01*
G03X1505461Y1054157I936J-891D01*
G03X1506753Y1052865I1292J0D01*
G03X1507643Y1053221I-1J1292D01*
G01X1524398Y1036466D01*
G02X1524385Y1035887I-282J-283D01*
G03X1523962Y1034931I869J-956D01*
G03X1524962Y1033672I1293J0D01*
G01X1525117Y1033636D01*
Y1017000D01*
X1524962Y1016964D01*
G03Y1014446I293J-1259D01*
G01X1525117Y1014410D01*
Y1001918D01*
X1524981Y1001872D01*
G03Y999424I416J-1224D01*
G01X1525117Y999378D01*
Y963492D01*
G03Y961380I743J-1056D01*
G01Y950883D01*
X1524984Y950835D01*
G03Y948403I436J-1216D01*
G01X1525117Y948355D01*
Y922181D01*
X1510082Y907146D01*
X1510001Y907145D01*
G03X1508729Y905873I20J-1292D01*
G01X1508728Y905792D01*
X1503413Y900477D01*
X1503280Y900556D01*
G03X1502621Y900737I-659J-1111D01*
G03X1501329Y899445I0J-1292D01*
G03X1501595Y898659I1292J-1D01*
G01X1500420Y897484D01*
X1500375Y897470D01*
G03X1499541Y896636I396J-1230D01*
G01X1499527Y896591D01*
X1497800Y894864D01*
X1484914D01*
G03X1484207Y894571I0J-999D01*
G01X1483955Y894319D01*
X1483893Y894308D01*
G03X1482848Y893263I227J-1272D01*
G01X1482837Y893201D01*
X1477907Y888271D01*
G03X1477722Y888016I706J-707D01*
G02X1477213Y887827I-357J181D01*
G03X1476720Y887924I-492J-1200D01*
G03X1475422Y886627I0J-1298D01*
G03X1475495Y886199I1298J1D01*
G01X1475526Y886112D01*
X1474719Y884715D01*
X1474629Y884698D01*
G03X1473574Y883423I243J-1275D01*
G03X1476168I1297J0D01*
G03X1476096Y883851I-1297J2D01*
G01X1476065Y883938D01*
X1476872Y885335D01*
X1476962Y885352D01*
G03X1477098Y885386I-246J1274D01*
G02X1477614Y885003I116J-383D01*
G01Y884299D01*
G03X1477274Y883423I957J-875D01*
G03X1477614Y882547I1297J-1D01*
G01Y877882D01*
G03Y876146I957J-868D01*
G01Y875434D01*
G02X1477098Y875051I-400J0D01*
G03X1476720Y875108I-380J-1241D01*
G03X1475422Y873810I0J-1298D01*
G03X1476478Y872535I1298J0D01*
G01X1476568Y872518D01*
X1477376Y871119D01*
X1477345Y871032D01*
G03X1477274Y870606I1226J-423D01*
G03X1477614Y869730I1297J-1D01*
G01Y865065D01*
G03Y863329I957J-868D01*
G01Y862617D01*
G02X1477098Y862234I-400J0D01*
G03X1476720Y862290I-377J-1241D01*
G03X1475422Y860993I0J-1298D01*
G03X1476478Y859718I1298J0D01*
G01X1476568Y859701D01*
X1477376Y858302D01*
X1477345Y858215D01*
G03X1477274Y857789I1226J-423D01*
G03X1477614Y856913I1297J-1D01*
G01Y852248D01*
G03Y850512I957J-868D01*
G01Y847564D01*
G03X1477907Y846857I999J0D01*
G01X1479807Y844957D01*
G03X1480514Y844664I707J706D01*
G01X1503167D01*
X1503191Y844492D01*
G03X1505751I1280J180D01*
G01X1505775Y844664D01*
X1510567D01*
X1510591Y844492D01*
G03X1513151I1280J180D01*
G01X1513175Y844664D01*
X1611824D01*
X1614042Y842446D01*
Y757503D01*
G03Y754895I747J-1304D01*
G01Y661765D01*
X1614041Y661752D01*
G03X1614033Y661630I992J-126D01*
G03X1614041Y661508I1000J4D01*
G01X1614042Y661495D01*
Y657925D01*
X1612747Y656630D01*
X1567209D01*
X1431314Y792525D01*
Y850402D01*
G03Y852358I-844J978D01*
G01Y856803D01*
G03Y858775I-844J986D01*
G01Y859407D01*
G02X1431857Y859781I400J0D01*
G03X1432078Y859718I465J1211D01*
G01X1432168Y859701D01*
X1432976Y858302D01*
X1432945Y858215D01*
G03X1432874Y857789I1226J-423D01*
G03X1435468I1297J0D01*
G03X1434410Y859064I-1297J0D01*
G01X1434320Y859081D01*
X1433514Y860478D01*
X1433545Y860564D01*
G03X1433618Y860993I-1224J429D01*
G03X1432320Y862290I-1297J0D01*
G03X1431857Y862205I-1J-1297D01*
G02X1431314Y862579I-143J374D01*
G01Y863218D01*
G03Y865176I-843J979D01*
G01Y869620D01*
G03Y871592I-844J986D01*
G01Y872224D01*
G02X1431857Y872598I400J0D01*
G03X1432078Y872535I465J1211D01*
G01X1432168Y872518D01*
X1432976Y871119D01*
X1432945Y871032D01*
G03X1432874Y870606I1226J-423D01*
G03X1435468I1297J0D01*
G03X1434410Y871881I-1297J0D01*
G01X1434320Y871898D01*
X1433514Y873295D01*
X1433545Y873381D01*
G03X1433618Y873810I-1224J429D01*
G03X1432320Y875108I-1298J0D01*
G03X1431857Y875022I2J-1298D01*
G02X1431314Y875396I-143J374D01*
G01Y876035D01*
G03Y877993I-843J979D01*
G01Y882437D01*
G03X1431768Y883423I-844J986D01*
G03X1431696Y883851I-1297J2D01*
G01X1431665Y883938D01*
X1432472Y885335D01*
X1432562Y885352D01*
G03X1433618Y886627I-242J1275D01*
G03X1432320Y887924I-1297J0D01*
G03X1431857Y887839I-1J-1297D01*
G02X1431314Y888213I-143J374D01*
G01Y888853D01*
G03Y890811I-843J979D01*
G01Y895261D01*
G03X1431763Y896240I-843J979D01*
G03X1431744Y896460I-1292J-1D01*
G01X1431726Y896562D01*
X1439723Y904559D01*
X1439798Y904563D01*
G03X1441010Y905775I-78J1290D01*
G01X1441014Y905850D01*
X1446367Y911203D01*
X1446499Y911130D01*
G03X1447122Y910970I623J1133D01*
G03X1448414Y912262I0J1292D01*
G03X1448254Y912885I-1293J0D01*
G01X1448181Y913017D01*
X1449417Y914253D01*
X1449455Y914268D01*
G03X1450168Y914981I-485J1198D01*
G01X1450183Y915019D01*
X1455850Y920686D01*
X1455967Y920648D01*
G03X1456371Y920583I405J1227D01*
G03X1457663Y921875I0J1292D01*
G03X1457598Y922279I-1292J-1D01*
G01X1457560Y922396D01*
X1465379Y930215D01*
X1465475Y930204D01*
G03X1465620Y930196I144J1284D01*
G03X1466912Y931488I0J1292D01*
G03X1466904Y931633I-1292J1D01*
G01X1466893Y931729D01*
X1472119Y936955D01*
X1472257Y936854D01*
G03X1473021Y936604I764J1042D01*
G03X1474313Y937896I0J1292D01*
G03X1473954Y938790I-1293J0D01*
G01X1474974Y939810D01*
X1475041Y939819D01*
G03X1476152Y940930I-170J1281D01*
G01X1476161Y940997D01*
X1477805Y942641D01*
G03X1478098Y943348I-706J707D01*
G01Y1002007D01*
G03Y1003769I-945J881D01*
G01Y1008416D01*
G03Y1010178I-945J881D01*
G01Y1014823D01*
G03Y1016587I-944J882D01*
G01Y1021233D01*
G03Y1022995I-945J881D01*
G01Y1027642D01*
G03X1478445Y1028523I-945J881D01*
G03X1477153Y1029815I-1292J0D01*
G03X1476602Y1029692I-1J-1292D01*
G01X1476475Y1029631D01*
X1473735Y1032371D01*
G03X1473028Y1032664I-707J-706D01*
G01X1472493D01*
G03X1470713I-890J-938D01*
G01X1468794D01*
G03X1467014I-890J-938D01*
G01X1465094D01*
G03X1463314I-890J-938D01*
G01X1461393D01*
G03X1459613I-890J-938D01*
G01X1457694D01*
G03X1456804Y1033019I-890J-938D01*
G03X1455588Y1032163I0J-1292D01*
G03X1455260Y1032018I25J-500D01*
G01X1454908Y1031666D01*
X1454906D01*
X1453912Y1030672D01*
Y1029851D01*
G03Y1027195I1042J-1328D01*
G01Y1025671D01*
X1453566Y1025325D01*
X1452967D01*
X1451921Y1026371D01*
G03X1451214Y1026664I-707J-706D01*
G01X1444386D01*
X1443814Y1027236D01*
Y1035643D01*
X1443951Y1035689D01*
G03Y1038139I-410J1225D01*
G01X1443814Y1038185D01*
Y1063057D01*
X1446521Y1065764D01*
X1447099D01*
X1447131Y1065753D01*
G03X1447553Y1065682I422J1221D01*
G03X1447975Y1065753I0J1292D01*
G01X1448007Y1065764D01*
G37*
G36*
G01X1607838Y1383825D02*
X1689953D01*
X1690360Y1383418D01*
G03X1690010Y1382492I1052J-927D01*
G03X1690402Y1381519I1402J-1D01*
G02Y1380965I-288J-277D01*
G03X1690010Y1379992I1010J-972D01*
G03X1690402Y1379019I1402J-1D01*
G02Y1378465I-288J-277D01*
G03X1690010Y1377492I1010J-972D01*
G03X1690402Y1376519I1402J-1D01*
G02Y1375965I-288J-277D01*
G03X1690010Y1374992I1010J-972D01*
G03X1690402Y1374019I1402J-1D01*
G02Y1373465I-288J-277D01*
G03X1690010Y1372492I1010J-972D01*
G03X1690402Y1371519I1402J-1D01*
G02Y1370965I-288J-277D01*
G03X1690010Y1369992I1010J-972D01*
G03X1690402Y1369019I1402J-1D01*
G02Y1368465I-288J-277D01*
G03X1690010Y1367492I1010J-972D01*
G03X1691058Y1366136I1401J0D01*
G01X1691207Y1366096D01*
Y1298471D01*
X1688707Y1295971D01*
G03X1688414Y1295264I706J-707D01*
G01Y1274513D01*
G03Y1272175I774J-1169D01*
G01Y848521D01*
X1686557Y846664D01*
X1480928D01*
X1479614Y847978D01*
Y850617D01*
G03X1479863Y851380I-1043J763D01*
G03X1479614Y852143I-1292J0D01*
G01Y852936D01*
G02X1480110Y853324I400J0D01*
G03X1480420Y853286I312J1260D01*
G03X1481718Y854584I0J1298D01*
G03X1481645Y855011I-1298J-2D01*
G01X1481615Y855098D01*
X1482423Y856497D01*
X1482513Y856514D01*
G03X1483568Y857789I-243J1275D01*
G03X1480974I-1297J0D01*
G03X1481046Y857361I1297J-2D01*
G01X1481077Y857274D01*
X1480270Y855876D01*
X1480180Y855859D01*
G03X1480110Y855844I237J-1276D01*
G02X1479614Y856232I-96J388D01*
G01Y857017D01*
G03X1479868Y857789I-1043J771D01*
G03X1479614Y858561I-1297J1D01*
G01Y863434D01*
G03X1479863Y864197I-1043J763D01*
G03X1479614Y864960I-1292J0D01*
G01Y865753D01*
G02X1480110Y866141I400J0D01*
G03X1480420Y866104I308J1260D01*
G03X1481718Y867401I0J1298D01*
G03X1481645Y867828I-1298J-2D01*
G01X1481615Y867915D01*
X1482423Y869314D01*
X1482513Y869331D01*
G03X1483568Y870606I-243J1275D01*
G03X1480974I-1297J0D01*
G03X1481046Y870178I1297J-2D01*
G01X1481077Y870091D01*
X1480270Y868693D01*
X1480180Y868676D01*
G03X1480110Y868661I237J-1276D01*
G02X1479614Y869049I-96J388D01*
G01Y869834D01*
G03X1479868Y870606I-1043J771D01*
G03X1479614Y871378I-1297J1D01*
G01Y876251D01*
G03X1479863Y877014I-1043J763D01*
G03X1479614Y877777I-1292J0D01*
G01Y878571D01*
G02X1480110Y878959I400J0D01*
G03X1480420Y878922I308J1260D01*
G03X1481718Y880219I0J1298D01*
G03X1480661Y881494I-1297J0D01*
G01X1480571Y881511D01*
X1479765Y882908D01*
X1479796Y882994D01*
G03X1479868Y883423I-1225J426D01*
G03X1479614Y884195I-1297J1D01*
G01Y887150D01*
X1481362Y888898D01*
X1481500Y888795D01*
G03X1482271Y888540I771J1038D01*
G03X1483563Y889832I0J1292D01*
G03X1483308Y890603I-1293J0D01*
G01X1483205Y890741D01*
X1484209Y891745D01*
X1484278Y891754D01*
G03X1485371Y892714I-158J1282D01*
G01X1485410Y892864D01*
X1486530D01*
X1486569Y892714D01*
G03X1489071I1251J322D01*
G01X1489110Y892864D01*
X1490231D01*
X1490270Y892714D01*
G03X1492772I1251J322D01*
G01X1492811Y892864D01*
X1493930D01*
X1493969Y892714D01*
G03X1496471I1251J322D01*
G01X1496510Y892864D01*
X1498214D01*
G03X1498921Y893157I0J999D01*
G01X1500711Y894947D01*
X1500792Y894948D01*
G03X1502063Y896219I-21J1292D01*
G01X1502064Y896300D01*
X1507380Y901616D01*
X1507513Y901537D01*
G03X1508171Y901357I658J1113D01*
G03X1509463Y902649I0J1292D01*
G03X1509283Y903307I-1293J0D01*
G01X1509204Y903440D01*
X1510373Y904609D01*
X1510419Y904624D01*
G03X1511250Y905455I-398J1229D01*
G01X1511265Y905501D01*
X1526824Y921060D01*
G03X1527117Y921767I-706J707D01*
G01Y962132D01*
X1527122Y962154D01*
G03X1527153Y962436I-1261J281D01*
G03X1527122Y962718I-1292J1D01*
G01X1527117Y962740D01*
Y971337D01*
X1527253Y971383D01*
G03Y973833I-410J1225D01*
G01X1527117Y973879D01*
Y1030423D01*
X1527288Y1030447D01*
G03Y1033005I-185J1279D01*
G01X1527117Y1033029D01*
Y1036161D01*
G03X1526824Y1036868I-999J0D01*
G01X1513414Y1050278D01*
X1513473Y1050405D01*
G03X1513595Y1050952I-1170J548D01*
G03X1512303Y1052244I-1292J0D01*
G03X1511756Y1052122I1J-1292D01*
G01X1511629Y1052063D01*
X1506190Y1057502D01*
X1506180Y1057566D01*
G03X1505109Y1058637I-1276J-205D01*
G01X1505045Y1058647D01*
X1504003Y1059689D01*
G03X1504345Y1060565I-951J876D01*
G03X1503053Y1061857I-1292J0D01*
G03X1502177Y1061515I0J-1293D01*
G01X1496931Y1066761D01*
X1496939Y1066855D01*
G03X1496945Y1066974I-1286J124D01*
G03X1495653Y1068266I-1292J0D01*
G03X1494433Y1067398I0J-1291D01*
G01X1494386Y1067264D01*
X1493220D01*
X1493173Y1067398D01*
G03X1490733I-1220J-423D01*
G01X1490686Y1067264D01*
X1489520D01*
X1489473Y1067398D01*
G03X1487033I-1220J-423D01*
G01X1486986Y1067264D01*
X1485820D01*
X1485773Y1067398D01*
G03X1483333I-1220J-423D01*
G01X1483286Y1067264D01*
X1482120D01*
X1482073Y1067398D01*
G03X1479633I-1220J-423D01*
G01X1479586Y1067264D01*
X1478420D01*
X1478373Y1067398D01*
G03X1475933I-1220J-423D01*
G01X1475886Y1067264D01*
X1474720D01*
X1474673Y1067398D01*
G03X1472233I-1220J-423D01*
G01X1472186Y1067264D01*
X1471020D01*
X1470973Y1067398D01*
G03X1468533I-1220J-423D01*
G01X1468486Y1067264D01*
X1467320D01*
X1467273Y1067398D01*
G03X1464833I-1220J-423D01*
G01X1464786Y1067264D01*
X1463620D01*
X1463573Y1067398D01*
G03X1461133I-1220J-423D01*
G01X1461086Y1067264D01*
X1459921D01*
X1459874Y1067398D01*
G03X1457434I-1220J-423D01*
G01X1457387Y1067264D01*
X1456220D01*
X1456173Y1067398D01*
G03X1453733I-1220J-423D01*
G01X1453686Y1067264D01*
X1452520D01*
X1452473Y1067398D01*
G03X1451253Y1068266I-1220J-423D01*
G03X1449993Y1067261I0J-1292D01*
G03X1449049Y1066766I-79J-997D01*
G01X1446106D01*
X1442812Y1063472D01*
Y1061892D01*
G03Y1059238I1043J-1327D01*
G01Y1055484D01*
G03Y1052830I1043J-1327D01*
G01Y1048516D01*
G03X1442561Y1047750I1041J-765D01*
G03X1442812Y1046984I1292J-1D01*
G01Y1042106D01*
G03X1442561Y1041340I1041J-765D01*
G03X1442812Y1040574I1292J-1D01*
G01Y1037981D01*
G03Y1035847I730J-1067D01*
G01Y1027170D01*
X1442307Y1026664D01*
X1435928D01*
X1433914Y1028678D01*
Y1040772D01*
X1433932Y1040811D01*
G03X1434045Y1041340I-1179J528D01*
G03X1433932Y1041869I-1292J1D01*
G01X1433914Y1041908D01*
Y1047181D01*
X1433932Y1047220D01*
G03X1434045Y1047749I-1179J528D01*
G03X1433932Y1048278I-1292J1D01*
G01X1433914Y1048317D01*
Y1053589D01*
X1433932Y1053628D01*
G03X1434045Y1054157I-1179J528D01*
G03X1433932Y1054686I-1292J1D01*
G01X1433914Y1054725D01*
Y1059997D01*
X1433932Y1060036D01*
G03X1434045Y1060565I-1179J528D01*
G03X1433932Y1061094I-1292J1D01*
G01X1433914Y1061133D01*
Y1066406D01*
X1433932Y1066445D01*
G03X1434045Y1066974I-1179J528D01*
G03X1433932Y1067503I-1292J1D01*
G01X1433914Y1067542D01*
Y1072815D01*
X1433932Y1072854D01*
G03X1434045Y1073383I-1179J528D01*
G03X1433932Y1073912I-1292J1D01*
G01X1433914Y1073951D01*
Y1079220D01*
X1433932Y1079260D01*
G03X1434046Y1079791I-1178J531D01*
G03X1433932Y1080322I-1292J0D01*
G01X1433914Y1080362D01*
Y1085632D01*
X1433932Y1085671D01*
G03X1434045Y1086200I-1179J528D01*
G03X1433932Y1086729I-1292J1D01*
G01X1433914Y1086768D01*
Y1092036D01*
X1433932Y1092076D01*
G03X1434046Y1092607I-1178J531D01*
G03X1433932Y1093138I-1292J0D01*
G01X1433914Y1093178D01*
Y1098449D01*
X1433932Y1098488D01*
G03X1433975Y1098597I-1179J528D01*
G01X1433981Y1098615D01*
X1435535Y1101325D01*
X1435551Y1101342D01*
G03X1435841Y1101848I-947J879D01*
G01X1435848Y1101870D01*
X1437356Y1104501D01*
X1437374Y1104519D01*
G03X1437701Y1105090I-921J906D01*
G01X1437708Y1105115D01*
X1439178Y1107678D01*
X1439199Y1107698D01*
G03X1439560Y1108328I-895J931D01*
G01X1439567Y1108356D01*
X1441002Y1110859D01*
X1441025Y1110880D01*
G03X1441418Y1111564I-870J955D01*
G01X1441424Y1111595D01*
X1442828Y1114043D01*
X1442854Y1114066D01*
G03X1443273Y1114797I-850J973D01*
G01X1443280Y1114830D01*
X1444655Y1117230D01*
X1444683Y1117253D01*
G03X1445127Y1118027I-830J990D01*
G01X1445133Y1118062D01*
X1446475Y1120402D01*
X1446505Y1120426D01*
G03X1446990Y1121271I-801J1021D01*
G01X1446995Y1121310D01*
X1448303Y1123592D01*
X1448336Y1123616D01*
G03X1448841Y1124498I-784J1034D01*
G01X1448846Y1124538D01*
X1449285Y1125304D01*
G02X1449979Y1125305I347J-199D01*
G01X1450059Y1125166D01*
X1450028Y1125080D01*
G03X1449956Y1124651I1225J-426D01*
G03X1452550I1297J0D01*
G03X1451495Y1125926I-1298J0D01*
G01X1451405Y1125943D01*
X1450598Y1127341D01*
X1450629Y1127427D01*
G03X1450695Y1127727I-1225J427D01*
G01X1450699Y1127770D01*
X1451969Y1129983D01*
X1452004Y1130009D01*
G03X1452540Y1130943I-751J1052D01*
G01X1452544Y1130986D01*
X1453792Y1133163D01*
X1453830Y1133189D01*
G03X1454399Y1134180I-726J1076D01*
G01X1454402Y1134227D01*
X1455623Y1136356D01*
X1455663Y1136382D01*
G03X1456144Y1136953I-710J1086D01*
G01X1456197Y1137073D01*
X1457411D01*
X1457464Y1136953D01*
G03X1459844I1190J516D01*
G01X1459897Y1137073D01*
X1460536D01*
G02X1460882Y1136473I0J-400D01*
G01X1460353Y1135556D01*
X1460263Y1135539D01*
G03X1459206Y1134264I240J-1275D01*
G03X1461802I1298J0D01*
G03X1461729Y1134692I-1298J-1D01*
G01X1461699Y1134779D01*
X1462506Y1136177D01*
X1462596Y1136194D01*
G03X1463544Y1136953I-243J1275D01*
G01X1463597Y1137073D01*
X1464811D01*
X1464864Y1136953D01*
G03X1467244I1190J516D01*
G01X1467297Y1137073D01*
X1467936D01*
G02X1468282Y1136473I0J-400D01*
G01X1467753Y1135556D01*
X1467663Y1135539D01*
G03X1466606Y1134264I240J-1275D01*
G03X1469202I1298J0D01*
G03X1469129Y1134692I-1298J-1D01*
G01X1469099Y1134779D01*
X1469906Y1136177D01*
X1469996Y1136194D01*
G03X1470944Y1136953I-243J1275D01*
G01X1470997Y1137073D01*
X1472211D01*
X1472264Y1136953D01*
G03X1474644I1190J516D01*
G01X1474697Y1137073D01*
X1475336D01*
G02X1475682Y1136473I0J-400D01*
G01X1475153Y1135556D01*
X1475063Y1135539D01*
G03X1474006Y1134264I240J-1275D01*
G03X1476602I1298J0D01*
G03X1476529Y1134692I-1298J-1D01*
G01X1476499Y1134779D01*
X1477306Y1136177D01*
X1477396Y1136194D01*
G03X1478344Y1136953I-243J1275D01*
G01X1478397Y1137073D01*
X1479611D01*
X1479664Y1136953D01*
G03X1482044I1190J516D01*
G01X1482097Y1137073D01*
X1482736D01*
G02X1483082Y1136473I0J-400D01*
G01X1482553Y1135556D01*
X1482463Y1135539D01*
G03X1481406Y1134264I240J-1275D01*
G03X1484002I1298J0D01*
G03X1483929Y1134692I-1298J-1D01*
G01X1483899Y1134779D01*
X1484706Y1136177D01*
X1484796Y1136194D01*
G03X1485744Y1136953I-243J1275D01*
G01X1485797Y1137073D01*
X1487011D01*
X1487064Y1136953D01*
G03X1489444I1190J516D01*
G01X1489497Y1137073D01*
X1490136D01*
G02X1490482Y1136473I0J-400D01*
G01X1489953Y1135556D01*
X1489863Y1135539D01*
G03X1488806Y1134264I240J-1275D01*
G03X1491402I1298J0D01*
G03X1491329Y1134692I-1298J-1D01*
G01X1491299Y1134779D01*
X1492106Y1136177D01*
X1492196Y1136194D01*
G03X1493144Y1136953I-243J1275D01*
G01X1493197Y1137073D01*
X1494411D01*
X1494464Y1136953D01*
G03X1496844I1190J516D01*
G01X1496897Y1137073D01*
X1497536D01*
G02X1497882Y1136473I0J-400D01*
G01X1497353Y1135556D01*
X1497263Y1135539D01*
G03X1496206Y1134264I240J-1275D01*
G03X1498802I1298J0D01*
G03X1498729Y1134692I-1298J-1D01*
G01X1498699Y1134779D01*
X1499506Y1136177D01*
X1499596Y1136194D01*
G03X1500544Y1136953I-243J1275D01*
G01X1500597Y1137073D01*
X1501811D01*
X1501864Y1136953D01*
G03X1504244I1190J516D01*
G01X1504297Y1137073D01*
X1505517D01*
X1505570Y1136953D01*
G03X1507938I1184J515D01*
G01X1507991Y1137073D01*
X1508635D01*
G02X1508982Y1136473I1J-400D01*
G01X1508452Y1135556D01*
X1508362Y1135539D01*
G03X1507306Y1134264I242J-1275D01*
G03X1509902I1298J0D01*
G03X1509829Y1134692I-1298J-1D01*
G01X1509798Y1134779D01*
X1510606Y1136177D01*
X1510696Y1136194D01*
G03X1511644Y1136953I-243J1275D01*
G01X1511697Y1137073D01*
X1518575D01*
G03X1519282Y1137366I0J999D01*
G01X1547414Y1165498D01*
G03X1547707Y1166205I-706J707D01*
G01Y1298441D01*
X1549081Y1299815D01*
X1559647D01*
G03X1560354Y1300108I0J999D01*
G01X1561985Y1301739D01*
G03X1562278Y1302446I-706J707D01*
G01Y1338265D01*
X1607838Y1383825D01*
G37*
G36*
G01X1740860Y1230665D02*
X1742033D01*
X1744457Y1228241D01*
Y1225984D01*
G03Y1224542I1083J-721D01*
G01Y1219291D01*
G03Y1217849I1083J-721D01*
G01Y1212598D01*
G03Y1211156I1083J-721D01*
G01Y1205905D01*
G03Y1204463I1083J-721D01*
G01Y1199212D01*
G03Y1197770I1083J-721D01*
G01Y1189173D01*
G03Y1187731I1083J-721D01*
G01Y1182480D01*
G03Y1181038I1083J-721D01*
G01Y1175787D01*
G03Y1174345I1083J-721D01*
G01Y1169094D01*
G03Y1167652I1083J-721D01*
G01Y1162401D01*
G03Y1160959I1083J-721D01*
G01Y1152362D01*
G03Y1150920I1083J-721D01*
G01Y1145669D01*
G03Y1144227I1083J-721D01*
G01Y1138976D01*
G03Y1137534I1083J-721D01*
G01Y1132283D01*
G03Y1130841I1083J-721D01*
G01Y1125590D01*
G03Y1124148I1083J-721D01*
G01Y1115550D01*
G03Y1114108I1083J-721D01*
G01Y1108858D01*
G03Y1107416I1083J-721D01*
G01Y1102165D01*
G03Y1100723I1083J-721D01*
G01Y1095472D01*
G03Y1094030I1083J-721D01*
G01Y1088779D01*
G03Y1087337I1083J-721D01*
G01Y1078739D01*
G03Y1077297I1083J-721D01*
G01Y1072047D01*
G03Y1070605I1083J-721D01*
G01Y1065354D01*
G03Y1063912I1083J-721D01*
G01Y1058661D01*
G03Y1057219I1083J-721D01*
G01Y1055296D01*
G03Y1053890I1084J-703D01*
G01Y1051968D01*
G03Y1050526I1083J-721D01*
G01Y1045275D01*
G03Y1043833I1083J-721D01*
G01Y1038582D01*
G03Y1037140I1083J-721D01*
G01Y1031889D01*
G03Y1030447I1083J-721D01*
G01Y1025196D01*
G03Y1023754I1083J-721D01*
G01Y1018503D01*
G03Y1017061I1083J-721D01*
G01Y991732D01*
G03Y990290I1083J-721D01*
G01Y985039D01*
G03Y983597I1083J-721D01*
G01Y978346D01*
G03Y976904I1083J-721D01*
G01Y971653D01*
G03Y970211I1083J-721D01*
G01Y968288D01*
G03Y966882I1084J-703D01*
G01Y964960D01*
G03Y963518I1083J-721D01*
G01Y961595D01*
G03Y960189I1084J-703D01*
G01Y958249D01*
G03Y956843I1084J-703D01*
G01Y954921D01*
G03Y953479I1083J-721D01*
G01Y948228D01*
G03Y946786I1083J-721D01*
G01Y941535D01*
G03Y940093I1083J-721D01*
G01Y931495D01*
G03Y930053I1083J-721D01*
G01Y924802D01*
G03Y923360I1083J-721D01*
G01Y918110D01*
G03Y916668I1083J-721D01*
G01Y911417D01*
G03Y909975I1083J-721D01*
G01Y904724D01*
G03Y903282I1083J-721D01*
G01Y894684D01*
G03Y893242I1083J-721D01*
G01Y887991D01*
G03Y886549I1083J-721D01*
G01Y881298D01*
G03Y879856I1083J-721D01*
G01Y874606D01*
G03Y873164I1083J-721D01*
G01Y867913D01*
G03Y866471I1083J-721D01*
G01Y857873D01*
G03Y856431I1083J-721D01*
G01Y851180D01*
G03Y849738I1083J-721D01*
G01Y844487D01*
G03Y843045I1083J-721D01*
G01Y837795D01*
G03Y836353I1083J-721D01*
G01Y831102D01*
G03Y829660I1083J-721D01*
G01Y821062D01*
G03Y819620I1083J-721D01*
G01Y814369D01*
G03Y812927I1083J-721D01*
G01Y807676D01*
G03Y806234I1083J-721D01*
G01Y800984D01*
G03Y799542I1083J-721D01*
G01Y794291D01*
G03Y792849I1083J-721D01*
G01Y784251D01*
G03Y782809I1083J-721D01*
G01Y777558D01*
G03Y776116I1083J-721D01*
G01Y770865D01*
G03Y769423I1083J-721D01*
G01Y767687D01*
G03Y765909I1084J-889D01*
G01Y671819D01*
X1742503Y669865D01*
X1686202D01*
X1686162Y670012D01*
G03X1679602I-3280J-903D01*
G01X1679562Y669865D01*
X1659408D01*
G03X1658701Y669572I0J-999D01*
G01X1656995Y667866D01*
G03X1656702Y667159I706J-707D01*
G01Y639742D01*
X1656700Y639726D01*
G03X1656683Y639511I1385J-218D01*
G03X1656700Y639296I1402J3D01*
G01X1656702Y639280D01*
Y621971D01*
X1656592Y621915D01*
G03Y619409I627J-1253D01*
G01X1656702Y619353D01*
Y612578D01*
X1656555Y612538D01*
G03Y609642I400J-1448D01*
G01X1656702Y609602D01*
Y594014D01*
G02X1656289Y593614I-400J0D01*
G03X1656238Y593615I-55J-1501D01*
G03X1654736Y592113I0J-1502D01*
G03X1654945Y591349I1501J0D01*
G01X1655024Y591216D01*
X1648907Y585099D01*
X1617942D01*
G03X1617849Y585206I-799J-601D01*
G01X1616042Y587013D01*
Y648762D01*
X1616159Y648815D01*
G03Y651369I-579J1277D01*
G01X1616042Y651422D01*
Y656432D01*
X1616159Y656485D01*
G03X1616982Y657762I-579J1277D01*
G03X1616551Y658773I-1401J0D01*
G02Y659351I277J289D01*
G03X1616982Y660362I-970J1011D01*
G03X1616159Y661639I-1402J0D01*
G01X1616042Y661692D01*
Y682762D01*
X1616159Y682815D01*
G03Y685369I-579J1277D01*
G01X1616042Y685422D01*
Y690432D01*
X1616159Y690485D01*
G03X1616982Y691762I-579J1277D01*
G03X1616551Y692773I-1401J0D01*
G02Y693351I277J289D01*
G03X1616982Y694362I-970J1011D01*
G03X1616159Y695639I-1402J0D01*
G01X1616042Y695692D01*
Y716762D01*
X1616159Y716815D01*
G03Y719369I-579J1277D01*
G01X1616042Y719422D01*
Y755372D01*
G03Y757026I-1255J827D01*
G01Y842496D01*
X1618210Y844664D01*
X1686971D01*
G03X1687678Y844957I0J999D01*
G01X1690121Y847400D01*
G03X1690414Y848107I-706J707D01*
G01Y1229239D01*
X1690505Y1229299D01*
G03X1690668Y1229431I-544J839D01*
G01X1691902Y1230665D01*
X1702106D01*
X1702119Y1230663D01*
G03X1702283Y1230653I161J1292D01*
G03X1702447Y1230663I3J1302D01*
G01X1702460Y1230665D01*
X1710806D01*
X1710819Y1230663D01*
G03X1710983Y1230653I161J1292D01*
G03X1711147Y1230663I3J1302D01*
G01X1711160Y1230665D01*
X1715774D01*
G03X1715841Y1230663I72J1290D01*
G03X1715908Y1230665I-5J1292D01*
G01X1731806D01*
X1731819Y1230663D01*
G03X1731983Y1230653I161J1292D01*
G03X1732147Y1230663I3J1302D01*
G01X1732160Y1230665D01*
X1740506D01*
X1740519Y1230663D01*
G03X1740683Y1230653I161J1292D01*
G03X1740847Y1230663I3J1302D01*
G01X1740860Y1230665D01*
G37*
%LPD*%
G75*
G36*
G01X447117Y1378173D02*
X455023Y1386079D01*
G02X455730Y1386372I707J-706D01*
G01X472770D01*
G02X473477Y1386079I0J-999D01*
G01X479906Y1379650D01*
X550054D01*
G02X550761Y1379357I0J-999D01*
G01X564488Y1365630D01*
G02X564781Y1364923I-706J-707D01*
G01Y1350314D01*
G02X564488Y1349607I-999J0D01*
G01X563295Y1348414D01*
G02X562588Y1348121I-707J706D01*
G01X552415D01*
X552360Y1348009D01*
G02X549722I-1319J642D01*
G01X549667Y1348121D01*
X543973D01*
X543918Y1348008D01*
G02X542597Y1347179I-1321J638D01*
G02X541576Y1347593I0J1466D01*
G03X541018I-279J-287D01*
G02X539997Y1347179I-1021J1052D01*
G02X538676Y1348008I0J1467D01*
G01X538621Y1348121D01*
X537425D01*
X535750Y1346446D01*
G02X536064Y1345539I-1153J-907D01*
G02X535297Y1344250I-1467J0D01*
G01Y1343721D01*
G02Y1341143I-700J-1289D01*
G01Y1322504D01*
G02X535004Y1321797I-999J0D01*
G01X529627Y1316420D01*
G02X528920Y1316127I-707J706D01*
G01X503719D01*
X502027Y1314435D01*
Y1305702D01*
G02X501734Y1304995I-999J0D01*
G01X499899Y1303160D01*
G02X499192Y1302867I-707J706D01*
G01X493526D01*
G02X492155Y1301978I-1371J613D01*
G02X491128Y1302384I0J1502D01*
G03X490582I-273J-292D01*
G02X489555Y1301978I-1027J1096D01*
G02X488184Y1302867I0J1502D01*
G01X461936D01*
G02X459918I-1009J1114D01*
G01X459336D01*
G02X457318I-1009J1114D01*
G01X433634D01*
X433582Y1302744D01*
G02X430808I-1387J574D01*
G01X430756Y1302867D01*
X429270D01*
G02X427899Y1301978I-1371J613D01*
G02X426872Y1302384I0J1502D01*
G03X426326I-273J-292D01*
G02X425299Y1301978I-1027J1096D01*
G02X423928Y1302867I0J1502D01*
G01X401506D01*
X401454Y1302744D01*
G02X398680I-1387J574D01*
G01X398628Y1302867D01*
X397142D01*
G02X395771Y1301978I-1371J613D01*
G02X394744Y1302384I0J1502D01*
G03X394198I-273J-292D01*
G02X393171Y1301978I-1027J1096D01*
G02X391800Y1302867I0J1502D01*
G01X369378D01*
X369326Y1302744D01*
G02X367939Y1301817I-1387J574D01*
G02X366460Y1303058I0J1502D01*
G01X366449Y1303120D01*
X364379Y1305190D01*
X364254Y1305134D01*
G02X363643Y1305004I-611J1371D01*
G02X362141Y1306506I0J1502D01*
G02X362271Y1307117I1501J0D01*
G01X362327Y1307242D01*
X361779Y1307790D01*
X361654Y1307734D01*
G02X361043Y1307604I-611J1371D01*
G02X359541Y1309106I0J1502D01*
G02X359671Y1309717I1501J0D01*
G01X359727Y1309842D01*
X359385Y1310184D01*
G02X359092Y1310891I706J707D01*
G01Y1315406D01*
X358313Y1316185D01*
X337603D01*
G02X336896Y1316478I0J999D01*
G01X328045Y1325329D01*
G02X327819Y1325677I707J706D01*
G02X327413Y1326704I1096J1027D01*
G02X327752Y1327654I1501J0D01*
G01Y1328354D01*
G02Y1330254I1162J950D01*
G01Y1330954D01*
G02Y1332854I1162J950D01*
G01Y1333554D01*
G02Y1335454I1162J950D01*
G01Y1336154D01*
G02X327413Y1337104I1162J950D01*
G02X327596Y1337823I1502J0D01*
G01X327668Y1337954D01*
X326844Y1338778D01*
X303992D01*
G02X303285Y1339071I0J999D01*
G01X299553Y1342803D01*
G02X299260Y1343510I706J707D01*
G01Y1368455D01*
G02X299553Y1369162I999J0D01*
G01X306125Y1375734D01*
G02X306832Y1376027I707J-706D01*
G01X337511D01*
X346741Y1385257D01*
G02X347448Y1385550I707J-706D01*
G01X377355D01*
G02X378062Y1385257I0J-999D01*
G01X380365Y1382954D01*
X380417Y1382940D01*
G02X381475Y1381882I-392J-1450D01*
G01X381489Y1381830D01*
X385146Y1378173D01*
X447117D01*
G37*
G36*
G01X1394374Y172851D02*
G02X1395334Y173198I960J-1154D01*
G01X1398734D01*
G02X1400236Y171696I0J-1502D01*
G02X1398743Y170194I-1502J0D01*
G02X1398182Y170076I-561J1276D01*
G02X1397656Y170179I0J1394D01*
G01X1397620Y170194D01*
X1395334D01*
G02X1394882Y170264I1J1502D01*
G02X1394184Y170076I-699J1206D01*
G01X1394182D01*
G02Y172864I0J1394D01*
G02X1394374Y172851I2J-1394D01*
G37*
G36*
G01X1358624Y283142D02*
X1355224D01*
G02Y286146I0J1502D01*
G01X1358624D01*
G02Y283142I0J-1502D01*
G37*
G36*
G01X1348084Y278756D02*
X1344684D01*
G02Y281762I0J1503D01*
G01X1348084D01*
G02Y278756I0J-1503D01*
G37*
G36*
G01X1368524Y281242D02*
X1365124D01*
G02Y284246I0J1502D01*
G01X1368524D01*
G02Y281242I0J-1502D01*
G37*
G36*
G01X1328480Y322400D02*
X1325080D01*
G02Y325404I0J1502D01*
G01X1328480D01*
G02Y322400I0J-1502D01*
G37*
G36*
G01X613970Y190254D02*
X617370D01*
G02Y187250I0J-1502D01*
G01X613970D01*
G02Y190254I0J1502D01*
G37*
G36*
G01X626640D02*
X630040D01*
G02Y187250I0J-1502D01*
G01X626640D01*
G02Y190254I0J1502D01*
G37*
G36*
G01X1400985Y242432D02*
X1404385D01*
G02Y239426I0J-1503D01*
G01X1400985D01*
G02Y242432I0J1503D01*
G37*
G36*
G01X1307442Y305496D02*
X1304042D01*
G02Y308500I0J1502D01*
G01X1307442D01*
G02Y305496I0J-1502D01*
G37*
G36*
G01X1307042Y291134D02*
X1303642D01*
G02Y294138I0J1502D01*
G01X1307042D01*
G02Y291134I0J-1502D01*
G37*
G36*
G01X1418630Y221520D02*
X1422030D01*
G02Y218516I0J-1502D01*
G01X1418630D01*
G02Y221520I0J1502D01*
G37*
G36*
G01X1407420D02*
X1410820D01*
G02Y218516I0J-1502D01*
G01X1407420D01*
G02Y221520I0J1502D01*
G37*
G36*
G01X1432660D02*
X1436060D01*
G02Y218516I0J-1502D01*
G01X1432660D01*
G02Y221520I0J1502D01*
G37*
G36*
G01X1348824Y327478D02*
X1345424D01*
G02Y330484I0J1503D01*
G01X1348824D01*
G02Y327478I0J-1503D01*
G37*
G36*
G01X1341431Y321190D02*
X1338031D01*
G02Y324196I0J1503D01*
G01X1341431D01*
G02Y321190I0J-1503D01*
G37*
G36*
G01X1335145Y331114D02*
X1331745D01*
G02Y334118I0J1502D01*
G01X1335145D01*
G02Y331114I0J-1502D01*
G37*
G36*
G01X1319618Y316570D02*
X1316218D01*
G02Y319576I0J1503D01*
G01X1319618D01*
G02Y316570I0J-1503D01*
G37*
G36*
G01X1311077Y321494D02*
X1307677D01*
G02Y324498I0J1502D01*
G01X1311077D01*
G02Y321494I0J-1502D01*
G37*
G36*
G01X1380602Y199170D02*
X1384002D01*
G02Y196166I0J-1502D01*
G01X1380602D01*
G02Y199170I0J1502D01*
G37*
G36*
G01X1398006D02*
X1401406D01*
G02Y196166I0J-1502D01*
G01X1398006D01*
G02Y199170I0J1502D01*
G37*
G36*
G01X1373591Y177932D02*
X1376991D01*
G02Y174928I0J-1502D01*
G01X1373591D01*
G02Y177932I0J1502D01*
G37*
G36*
G01X1406970Y140244D02*
X1410370D01*
G02Y137240I0J-1502D01*
G01X1406970D01*
G02Y140244I0J1502D01*
G37*
G36*
G01X1323303Y297674D02*
X1319903D01*
G02Y300678I0J1502D01*
G01X1323303D01*
G02Y297674I0J-1502D01*
G37*
G36*
G01X1361771Y330772D02*
X1358371D01*
G02Y333778I0J1503D01*
G01X1361771D01*
G02Y330772I0J-1503D01*
G37*
G36*
G01X1404829Y185766D02*
X1408229D01*
G02Y182760I0J-1503D01*
G01X1404829D01*
G02Y185766I0J1503D01*
G37*
G36*
G01X1412284Y173198D02*
X1415684D01*
G02Y170194I0J-1502D01*
G01X1412284D01*
G02Y173198I0J1502D01*
G37*
G36*
G01X1355200Y336340D02*
X1351800D01*
G02Y339346I0J1503D01*
G01X1355200D01*
G02Y336340I0J-1503D01*
G37*
G36*
G01X1328814Y292054D02*
X1325414D01*
G02Y295058I0J1502D01*
G01X1328814D01*
G02Y292054I0J-1502D01*
G37*
G36*
G01X1340161Y291902D02*
X1336761D01*
G02Y294906I0J1502D01*
G01X1340161D01*
G02Y291902I0J-1502D01*
G37*
G36*
G01X1413950Y185766D02*
X1417350D01*
G02Y182760I0J-1503D01*
G01X1413950D01*
G02Y185766I0J1503D01*
G37*
G36*
G01X1423110D02*
X1426510D01*
G02Y182760I0J-1503D01*
G01X1423110D01*
G02Y185766I0J1503D01*
G37*
G36*
G01X1401341Y178662D02*
X1404741D01*
G02Y175656I0J-1503D01*
G01X1401341D01*
G02Y178662I0J1503D01*
G37*
G36*
G01X1403778Y173186D02*
X1407178D01*
G02Y170182I0J-1502D01*
G01X1403778D01*
G02Y173186I0J1502D01*
G37*
G36*
G01X1389256Y199170D02*
X1392656D01*
G02Y196166I0J-1502D01*
G01X1389256D01*
G02Y199170I0J1502D01*
G37*
G36*
G01X987440Y432696D02*
X990840D01*
G02Y429690I0J-1503D01*
G01X987440D01*
G02Y432696I0J1503D01*
G37*
G36*
G01X934047Y459364D02*
X937447D01*
G02Y456360I0J-1502D01*
G01X934047D01*
G02Y459364I0J1502D01*
G37*
G36*
G01X942047Y464514D02*
X945447D01*
G02Y461510I0J-1502D01*
G01X942047D01*
G02Y464514I0J1502D01*
G37*
G36*
G01X909584Y459638D02*
X912984D01*
G02Y456632I0J-1503D01*
G01X909584D01*
G02Y459638I0J1503D01*
G37*
G36*
G01X1406786Y199170D02*
X1410186D01*
G02Y196166I0J-1502D01*
G01X1406786D01*
G02Y199170I0J1502D01*
G37*
G36*
G01X1312136Y283446D02*
X1308736D01*
G02Y286450I0J1502D01*
G01X1312136D01*
G02Y283446I0J-1502D01*
G37*
G36*
G01X921047Y464514D02*
X924447D01*
G02Y461510I0J-1502D01*
G01X921047D01*
G02Y464514I0J1502D01*
G37*
G36*
G01X1012861Y434390D02*
X1016261D01*
G02Y431386I0J-1502D01*
G01X1012861D01*
G02Y434390I0J1502D01*
G37*
G36*
G01X247175Y197050D02*
X253476D01*
G02X264218Y190154I0J-11814D01*
G03X264953Y190170I364J166D01*
G02X277098Y198346I12146J-4933D01*
G02Y172126I0J-13110D01*
G02X264953Y180302I1J13109D01*
G03X264218Y180318I-371J-150D01*
G02X253477Y173422I-10742J4918D01*
G01X247176D01*
G02X247175Y197050I0J11814D01*
G37*
G36*
G01X365287D02*
X371587D01*
G02X382329Y190155I0J-11815D01*
G03X383063Y190171I364J167D01*
G02X395208Y198346I12145J-4934D01*
G02Y172126I0J-13110D01*
G02X383063Y180301I0J13109D01*
G03X382329Y180317I-370J-151D01*
G02X371587Y173422I-10742J4920D01*
G01X365287D01*
G02Y197050I0J11814D01*
G37*
G36*
G01X351817Y1105941D02*
X351010Y1107338D01*
X350920Y1107355D01*
G02X349864Y1108630I242J1275D01*
G02X352460I1298J0D01*
G01Y1108628D01*
G02X352387Y1108201I-1298J2D01*
G01X352357Y1108115D01*
X353164Y1106718D01*
X353254Y1106701D01*
G02X354308Y1105426I-244J-1275D01*
G02X353011Y1104128I-1297J-1D01*
G02X351714Y1105426I1J1298D01*
G02X351787Y1105855I1297J0D01*
G01X351817Y1105941D01*
G37*
G36*
G01X366153Y886198D02*
G02X366080Y886625I1225J429D01*
G01Y886627D01*
G02X368676I1298J0D01*
G02X367620Y885352I-1298J0D01*
G01X367530Y885335D01*
X366724Y883938D01*
X366754Y883852D01*
G02X366826Y883425I-1226J-426D01*
G01Y883423D01*
G02X364232I-1297J0D01*
G02X365287Y884698I1298J0D01*
G01X365377Y884715D01*
X366183Y886112D01*
X366153Y886198D01*
G37*
G36*
G01X342567Y1109144D02*
X341760Y1110542D01*
X341670Y1110559D01*
G02X340614Y1111834I242J1275D01*
G02X343210I1298J0D01*
G02X343137Y1111406I-1299J1D01*
G01X343107Y1111320D01*
X343914Y1109922D01*
X344004Y1109905D01*
G02X345060Y1108630I-242J-1275D01*
G02X342464I-1298J0D01*
G02X342537Y1109058I1299J-1D01*
G01X342567Y1109144D01*
G37*
G36*
G01X362483Y880733D02*
X361677Y882131D01*
X361587Y882148D01*
G02X360532Y883423I243J1275D01*
G02X363126I1297J0D01*
G01Y883421D01*
G02X363054Y882994I-1298J-1D01*
G01X363024Y882908D01*
X363830Y881511D01*
X363920Y881494D01*
G02X364976Y880219I-242J-1275D01*
G02X362380I-1298J0D01*
G02X362453Y880647I1299J-1D01*
G01X362483Y880733D01*
G37*
G36*
G01X359217Y1112348D02*
X358409Y1113747D01*
X358319Y1113764D01*
G02X357264Y1115039I243J1275D01*
G02X359858I1297J0D01*
G01Y1115037D01*
G02X359786Y1114610I-1298J-1D01*
G01X359756Y1114524D01*
X360563Y1113126D01*
X360653Y1113109D01*
G02X361710Y1111834I-240J-1275D01*
G02X359114I-1298J0D01*
G02X359187Y1112262I1299J-1D01*
G01X359217Y1112348D01*
G37*
G36*
G01X342949Y1106204D02*
X344573D01*
G02X345611Y1106724I1038J-776D01*
G02Y1104128I0J-1298D01*
G02X344573Y1104648I0J1296D01*
G01X342949D01*
G02X341911Y1104128I-1038J776D01*
G02Y1106724I0J1298D01*
G02X342949Y1106204I0J-1296D01*
G37*
G36*
G01X358753Y886198D02*
G02X358680Y886625I1225J429D01*
G01Y886627D01*
G02X361276I1298J0D01*
G02X360220Y885352I-1298J0D01*
G01X360130Y885335D01*
X359324Y883938D01*
X359354Y883852D01*
G02X359426Y883425I-1226J-426D01*
G01Y883423D01*
G02X356832I-1297J0D01*
G02X357887Y884698I1298J0D01*
G01X357977Y884715D01*
X358783Y886112D01*
X358753Y886198D01*
G37*
G36*
G01X350350Y1112612D02*
X351974D01*
G02X353012Y1113132I1038J-776D01*
G02Y1110536I0J-1298D01*
G02X351974Y1111056I0J1296D01*
G01X350350D01*
G02X349312Y1110536I-1038J776D01*
G02Y1113132I0J1298D01*
G02X350350Y1112612I0J-1296D01*
G37*
G36*
G01X355083Y880733D02*
X354277Y882131D01*
X354187Y882148D01*
G02X353132Y883423I243J1275D01*
G02X355726I1297J0D01*
G01Y883421D01*
G02X355654Y882994I-1298J-1D01*
G01X355624Y882908D01*
X356430Y881511D01*
X356520Y881494D01*
G02X357576Y880219I-242J-1275D01*
G02X354980I-1298J0D01*
G02X355053Y880647I1299J-1D01*
G01X355083Y880733D01*
G37*
G36*
G01X346266Y1121961D02*
X345459Y1123359D01*
X345369Y1123376D01*
G02X344314Y1124651I243J1275D01*
G02X346908I1297J0D01*
G02X346836Y1124223I-1298J-2D01*
G01X346806Y1124137D01*
X347613Y1122739D01*
X347703Y1122722D01*
G02X348758Y1121447I-243J-1275D01*
G02X346164I-1297J0D01*
G02X346236Y1121875I1298J2D01*
G01X346266Y1121961D01*
G37*
G36*
G01X344799Y1128634D02*
X346423D01*
G02X347461Y1129154I1038J-776D01*
G02Y1126558I0J-1298D01*
G02X346423Y1127078I0J1296D01*
G01X344799D01*
G02X343761Y1126558I-1038J776D01*
G02Y1129154I0J1298D01*
G02X344799Y1128634I0J-1296D01*
G37*
G36*
G01X363959Y1106718D02*
X364766Y1108116D01*
X364736Y1108202D01*
G02X364664Y1108630I1226J426D01*
G02X367258I1297J0D01*
G02X366203Y1107355I-1298J0D01*
G01X366113Y1107338D01*
X365306Y1105941D01*
X365336Y1105855D01*
G02X365409Y1105426I-1224J-429D01*
G02X364112Y1104128I-1297J-1D01*
G02X362814Y1105426I0J1298D01*
G02X363869Y1106701I1298J0D01*
G01X363959Y1106718D01*
G37*
G36*
G01X337399Y1122224D02*
X339023D01*
G02X340061Y1122744I1038J-776D01*
G02Y1120150I0J-1297D01*
G02X339023Y1120670I0J1296D01*
G01X337399D01*
G02X336361Y1120150I-1038J776D01*
G02Y1122744I0J1297D01*
G02X337399Y1122224I0J-1296D01*
G37*
G36*
G01X355084Y867916D02*
X354277Y869314D01*
X354187Y869331D01*
G02X353132Y870606I243J1275D01*
G02X355726I1297J0D01*
G02X355654Y870177I-1297J-3D01*
G01X355623Y870091D01*
X356430Y868693D01*
X356520Y868676D01*
G02X357576Y867401I-242J-1275D01*
G02X354980I-1298J0D01*
G02X355053Y867830I1297J0D01*
G01X355084Y867916D01*
G37*
G36*
G01X362484D02*
X361677Y869314D01*
X361587Y869331D01*
G02X360532Y870606I243J1275D01*
G02X363126I1297J0D01*
G02X363054Y870177I-1297J-3D01*
G01X363023Y870091D01*
X363830Y868693D01*
X363920Y868676D01*
G02X364976Y867401I-242J-1275D01*
G02X362380I-1298J0D01*
G02X362453Y867830I1297J0D01*
G01X362484Y867916D01*
G37*
G36*
G01X369884D02*
X369077Y869314D01*
X368987Y869331D01*
G02X367932Y870606I243J1275D01*
G02X370526I1297J0D01*
G02X370454Y870177I-1297J-3D01*
G01X370423Y870091D01*
X371230Y868693D01*
X371320Y868676D01*
G02X372376Y867401I-242J-1275D01*
G02X369780I-1298J0D01*
G02X369853Y867830I1297J0D01*
G01X369884Y867916D01*
G37*
G36*
G01X350577Y871898D02*
X351384Y873295D01*
X351353Y873382D01*
G02X351280Y873810I1225J429D01*
G02X353876I1298J0D01*
G02X352820Y872535I-1298J0D01*
G01X352730Y872518D01*
X351923Y871121D01*
X351954Y871034D01*
G02X352026Y870606I-1225J-426D01*
G02X349432I-1297J0D01*
G02X350487Y871881I1298J0D01*
G01X350577Y871898D01*
G37*
G36*
G01X357977D02*
X358784Y873295D01*
X358753Y873382D01*
G02X358680Y873810I1225J429D01*
G02X361276I1298J0D01*
G02X360220Y872535I-1298J0D01*
G01X360130Y872518D01*
X359323Y871121D01*
X359354Y871034D01*
G02X359426Y870606I-1225J-426D01*
G02X356832I-1297J0D01*
G02X357887Y871881I1298J0D01*
G01X357977Y871898D01*
G37*
G36*
G01X365377D02*
X366184Y873295D01*
X366153Y873382D01*
G02X366080Y873810I1225J429D01*
G02X368676I1298J0D01*
G02X367620Y872535I-1298J0D01*
G01X367530Y872518D01*
X366723Y871121D01*
X366754Y871034D01*
G02X366826Y870606I-1225J-426D01*
G02X364232I-1297J0D01*
G02X365287Y871881I1298J0D01*
G01X365377Y871898D01*
G37*
G36*
G01X372777D02*
X373584Y873295D01*
X373553Y873382D01*
G02X373480Y873810I1225J429D01*
G02X376076I1298J0D01*
G02X375020Y872535I-1298J0D01*
G01X374930Y872518D01*
X374123Y871121D01*
X374154Y871034D01*
G02X374226Y870606I-1225J-426D01*
G02X371632I-1297J0D01*
G02X372687Y871881I1298J0D01*
G01X372777Y871898D01*
G37*
G36*
G01X369883Y880734D02*
X369077Y882131D01*
X368987Y882148D01*
G02X367932Y883423I243J1275D01*
G02X370526I1297J0D01*
G02X370454Y882994I-1297J-3D01*
G01X370423Y882908D01*
X371229Y881511D01*
X371319Y881494D01*
G02X372376Y880219I-240J-1275D01*
G02X369780I-1298J0D01*
G02X369853Y880647I1298J-1D01*
G01X369883Y880734D01*
G37*
G36*
G01X377283D02*
X376477Y882131D01*
X376387Y882148D01*
G02X375332Y883423I243J1275D01*
G02X377926I1297J0D01*
G02X377854Y882994I-1297J-3D01*
G01X377823Y882908D01*
X378629Y881511D01*
X378719Y881494D01*
G02X379776Y880219I-240J-1275D01*
G02X377180I-1298J0D01*
G02X377253Y880647I1298J-1D01*
G01X377283Y880734D01*
G37*
G36*
G01X372777Y884715D02*
X373584Y886112D01*
X373553Y886199D01*
G02X373480Y886627I1225J429D01*
G02X376076I1298J0D01*
G02X375020Y885352I-1298J0D01*
G01X374930Y885335D01*
X374123Y883938D01*
X374154Y883851D01*
G02X374226Y883423I-1225J-426D01*
G02X371632I-1297J0D01*
G02X372687Y884698I1298J0D01*
G01X372777Y884715D01*
G37*
G36*
G01X404001Y1082218D02*
G02X402962Y1081698I-1039J778D01*
G02Y1084292I0J1297D01*
G02X404001Y1083772I0J-1298D01*
G01X405623D01*
G02X406662Y1084292I1039J-778D01*
G02Y1081698I0J-1297D01*
G02X405623Y1082218I0J1298D01*
G01X404001D01*
G37*
G36*
G01X408361Y1081083D02*
X409168Y1082480D01*
X409137Y1082567D01*
G02X409064Y1082995I1225J429D01*
G02X411660I1298J0D01*
G02X410604Y1081720I-1298J0D01*
G01X410514Y1081703D01*
X409706Y1080304D01*
X409736Y1080218D01*
G02X409808Y1079791I-1225J-426D01*
G02X407214I-1297J0D01*
G02X408271Y1081066I1297J0D01*
G01X408361Y1081083D01*
G37*
G36*
G01X412867Y1083509D02*
X412059Y1084908D01*
X411969Y1084925D01*
G02X410914Y1086200I243J1275D01*
G02X413508I1297J0D01*
G02X413436Y1085772I-1297J-2D01*
G01X413405Y1085685D01*
X414212Y1084287D01*
X414303Y1084270D01*
G02X415360Y1082995I-240J-1275D01*
G02X412764I-1298J0D01*
G02X412837Y1083422I1298J-2D01*
G01X412867Y1083509D01*
G37*
G36*
G01X403616Y1086714D02*
X402809Y1088112D01*
X402719Y1088129D01*
G02X401664Y1089404I243J1275D01*
G02X404258I1297J0D01*
G02X404186Y1088976I-1297J-2D01*
G01X404155Y1088889D01*
X404962Y1087492D01*
X405052Y1087475D01*
G02X406108Y1086200I-242J-1275D01*
G02X403514I-1297J0D01*
G02X403586Y1086628I1297J2D01*
G01X403616Y1086714D01*
G37*
G36*
G01X411401Y1088626D02*
G02X410362Y1088106I-1039J778D01*
G02Y1090702I0J1298D01*
G02X411401Y1090182I0J-1298D01*
G01X413023D01*
G02X414062Y1090702I1039J-778D01*
G02Y1088106I0J-1298D01*
G02X413023Y1088626I0J1298D01*
G01X411401D01*
G37*
G36*
G01X406510Y1090696D02*
X407317Y1092093D01*
X407286Y1092180D01*
G02X407214Y1092608I1225J426D01*
G02X409808I1297J0D01*
G02X408753Y1091333I-1298J0D01*
G01X408663Y1091316D01*
X407856Y1089919D01*
X407887Y1089833D01*
G02X407960Y1089404I-1224J-429D01*
G02X405364I-1298J0D01*
G02X406420Y1090679I1298J0D01*
G01X406510Y1090696D01*
G37*
G36*
G01X420267Y1089917D02*
X419459Y1091316D01*
X419369Y1091333D01*
G02X418314Y1092608I243J1275D01*
G02X420908I1297J0D01*
G02X420836Y1092180I-1297J-2D01*
G01X420805Y1092093D01*
X421612Y1090696D01*
X421702Y1090679D01*
G02X422760Y1089404I-239J-1275D01*
G02X420164I-1298J0D01*
G02X420237Y1089831I1298J-2D01*
G01X420267Y1089917D01*
G37*
G36*
G01X405850Y1098240D02*
G02X404811Y1097720I-1039J778D01*
G02Y1100314I0J1297D01*
G02X405850Y1099794I0J-1298D01*
G01X407472D01*
G02X408511Y1100314I1039J-778D01*
G02Y1097720I0J-1297D01*
G02X407472Y1098240I0J1298D01*
G01X405850D01*
G37*
G36*
G01X352200Y1101444D02*
G02X351161Y1100924I-1039J778D01*
G02Y1103518I0J1297D01*
G02X352200Y1102998I0J-1298D01*
G01X353822D01*
G02X354861Y1103518I1039J-778D01*
G02Y1100924I0J-1297D01*
G02X353822Y1101444I0J1298D01*
G01X352200D01*
G37*
G36*
G01X400961Y1100309D02*
X401768Y1101706D01*
X401737Y1101793D01*
G02X401664Y1102221I1225J429D01*
G02X404260I1298J0D01*
G02X403204Y1100946I-1298J0D01*
G01X403114Y1100929D01*
X402306Y1099530D01*
X402336Y1099444D01*
G02X402408Y1099017I-1225J-426D01*
G02X399814I-1297J0D01*
G02X400871Y1100292I1297J0D01*
G01X400961Y1100309D01*
G37*
G36*
G01X376250Y1104648D02*
G02X375211Y1104128I-1039J778D01*
G02Y1106724I0J1298D01*
G02X376250Y1106204I0J-1298D01*
G01X377873D01*
G02X378912Y1106724I1039J-778D01*
G02Y1104128I0J-1298D01*
G02X377873Y1104648I0J1298D01*
G01X376250D01*
G37*
G36*
G01X380609Y1103513D02*
X381417Y1104911D01*
X381386Y1104998D01*
G02X381314Y1105426I1225J426D01*
G02X383908I1297J0D01*
G02X382853Y1104151I-1298J0D01*
G01X382763Y1104134D01*
X381956Y1102737D01*
X381986Y1102650D01*
G02X382060Y1102221I-1223J-432D01*
G02X379464I-1298J0D01*
G02X380519Y1103496I1298J0D01*
G01X380609Y1103513D01*
G37*
G36*
G01X412867Y1102735D02*
X412059Y1104134D01*
X411969Y1104151D01*
G02X410914Y1105426I243J1275D01*
G02X413508I1297J0D01*
G02X413436Y1104998I-1297J-2D01*
G01X413405Y1104911D01*
X414212Y1103513D01*
X414303Y1103496D01*
G02X415360Y1102221I-240J-1275D01*
G02X412764I-1298J0D01*
G02X412837Y1102648I1298J-2D01*
G01X412867Y1102735D01*
G37*
G36*
G01X359600Y1107852D02*
G02X358561Y1107332I-1039J778D01*
G02Y1109928I0J1298D01*
G02X359600Y1109408I0J-1298D01*
G01X361222D01*
G02X362261Y1109928I1039J-778D01*
G02Y1107332I0J-1298D01*
G02X361222Y1107852I0J1298D01*
G01X359600D01*
G37*
G36*
G01X385117Y1105941D02*
X384310Y1107338D01*
X384220Y1107355D01*
G02X383164Y1108630I242J1275D01*
G02X385760I1298J0D01*
G02X385687Y1108202I-1298J1D01*
G01X385656Y1108115D01*
X386463Y1106718D01*
X386553Y1106701D01*
G02X387608Y1105426I-243J-1275D01*
G02X385014I-1297J0D01*
G02X385086Y1105855I1297J3D01*
G01X385117Y1105941D01*
G37*
G36*
G01X392901Y1107852D02*
G02X391862Y1107332I-1039J778D01*
G02Y1109928I0J1298D01*
G02X392901Y1109408I0J-1298D01*
G01X394523D01*
G02X395562Y1109928I1039J-778D01*
G02Y1107332I0J-1298D01*
G02X394523Y1107852I0J1298D01*
G01X392901D01*
G37*
G36*
G01X397261Y1106718D02*
X398068Y1108115D01*
X398037Y1108202D01*
G02X397964Y1108630I1225J429D01*
G02X400560I1298J0D01*
G02X399504Y1107355I-1298J0D01*
G01X399414Y1107338D01*
X398606Y1105939D01*
X398636Y1105853D01*
G02X398708Y1105426I-1225J-426D01*
G02X396114I-1297J0D01*
G02X397171Y1106701I1297J0D01*
G01X397261Y1106718D01*
G37*
G36*
G01X408361D02*
X409168Y1108115D01*
X409137Y1108202D01*
G02X409064Y1108630I1225J429D01*
G02X411660I1298J0D01*
G02X410604Y1107355I-1298J0D01*
G01X410514Y1107338D01*
X409706Y1105939D01*
X409736Y1105853D01*
G02X409808Y1105426I-1225J-426D01*
G02X407214I-1297J0D01*
G02X408271Y1106701I1297J0D01*
G01X408361Y1106718D01*
G37*
G36*
G01X368467Y1109145D02*
X367660Y1110542D01*
X367570Y1110559D01*
G02X366514Y1111834I242J1275D01*
G02X369110I1298J0D01*
G02X369037Y1111406I-1298J1D01*
G01X369006Y1111319D01*
X369813Y1109922D01*
X369903Y1109905D01*
G02X370958Y1108630I-243J-1275D01*
G02X368364I-1297J0D01*
G02X368436Y1109059I1297J3D01*
G01X368467Y1109145D01*
G37*
G36*
G01X375867Y1109143D02*
X375059Y1110542D01*
X374969Y1110559D01*
G02X373914Y1111834I243J1275D01*
G02X376508I1297J0D01*
G02X376436Y1111406I-1297J-2D01*
G01X376405Y1111319D01*
X377212Y1109922D01*
X377302Y1109905D01*
G02X378360Y1108630I-239J-1275D01*
G02X375764I-1298J0D01*
G02X375837Y1109057I1298J-2D01*
G01X375867Y1109143D01*
G37*
G36*
G01X383650Y1111056D02*
G02X382611Y1110536I-1039J778D01*
G02Y1113132I0J1298D01*
G02X383650Y1112612I0J-1298D01*
G01X385272D01*
G02X386311Y1113132I1039J-778D01*
G02Y1110536I0J-1298D01*
G02X385272Y1111056I0J1298D01*
G01X383650D01*
G37*
G36*
G01X401767Y1109143D02*
X400959Y1110542D01*
X400869Y1110559D01*
G02X399814Y1111834I243J1275D01*
G02X402408I1297J0D01*
G02X402336Y1111406I-1297J-2D01*
G01X402305Y1111319D01*
X403112Y1109922D01*
X403202Y1109905D01*
G02X404260Y1108630I-239J-1275D01*
G02X401664I-1298J0D01*
G02X401737Y1109057I1298J-2D01*
G01X401767Y1109143D01*
G37*
G36*
G01X409550Y1111056D02*
G02X408511Y1110536I-1039J778D01*
G02Y1113132I0J1298D01*
G02X409550Y1112612I0J-1298D01*
G01X411172D01*
G02X412211Y1113132I1039J-778D01*
G02Y1110536I0J-1298D01*
G02X411172Y1111056I0J1298D01*
G01X409550D01*
G37*
G36*
G01X345459Y1113126D02*
X346267Y1114524D01*
X346236Y1114611D01*
G02X346164Y1115039I1225J426D01*
G02X348758I1297J0D01*
G02X347703Y1113764I-1298J0D01*
G01X347613Y1113747D01*
X346805Y1112349D01*
X346836Y1112262D01*
G02X346908Y1111834I-1225J-426D01*
G02X344314I-1297J0D01*
G02X345369Y1113109I1298J0D01*
G01X345459Y1113126D01*
G37*
G36*
G01X367000Y1114262D02*
G02X365961Y1113742I-1039J778D01*
G02Y1116336I0J1297D01*
G02X367000Y1115816I0J-1298D01*
G01X368622D01*
G02X369661Y1116336I1039J-778D01*
G02Y1113742I0J-1297D01*
G02X368622Y1114262I0J1298D01*
G01X367000D01*
G37*
G36*
G01X378761Y1113126D02*
X379568Y1114524D01*
X379537Y1114611D01*
G02X379464Y1115039I1225J429D01*
G02X382060I1298J0D01*
G02X381004Y1113764I-1298J0D01*
G01X380914Y1113747D01*
X380106Y1112348D01*
X380136Y1112261D01*
G02X380208Y1111834I-1225J-426D01*
G02X377614I-1297J0D01*
G02X378670Y1113109I1298J0D01*
G01X378761Y1113126D01*
G37*
G36*
G01X392517Y1112350D02*
X391710Y1113747D01*
X391620Y1113764D01*
G02X390564Y1115039I242J1275D01*
G02X393160I1298J0D01*
G02X393087Y1114611I-1298J1D01*
G01X393056Y1114524D01*
X393864Y1113126D01*
X393954Y1113109D01*
G02X395008Y1111834I-244J-1275D01*
G02X392414I-1297J0D01*
G02X392487Y1112263I1297J0D01*
G01X392517Y1112350D01*
G37*
G36*
G01X400301Y1114262D02*
G02X399262Y1113742I-1039J778D01*
G02Y1116336I0J1297D01*
G02X400301Y1115816I0J-1298D01*
G01X401923D01*
G02X402962Y1116336I1039J-778D01*
G02Y1113742I0J-1297D01*
G02X401923Y1114262I0J1298D01*
G01X400301D01*
G37*
G36*
G01X341760Y1119535D02*
X342567Y1120932D01*
X342536Y1121019D01*
G02X342464Y1121447I1225J426D01*
G02X345058I1297J0D01*
G02X344003Y1120172I-1298J0D01*
G01X343913Y1120155D01*
X343106Y1118758D01*
X343137Y1118671D01*
G02X343210Y1118243I-1225J-429D01*
G02X340614I-1298J0D01*
G02X341670Y1119518I1298J0D01*
G01X341760Y1119535D01*
G37*
G36*
G01X357367Y1121962D02*
X356560Y1123359D01*
X356470Y1123376D01*
G02X355414Y1124651I242J1275D01*
G02X358010I1298J0D01*
G02X357937Y1124223I-1298J1D01*
G01X357906Y1124136D01*
X358713Y1122739D01*
X358803Y1122722D01*
G02X359858Y1121447I-243J-1275D01*
G02X357264I-1297J0D01*
G02X357336Y1121876I1297J3D01*
G01X357367Y1121962D01*
G37*
G36*
G01X364767Y1121960D02*
X363959Y1123359D01*
X363869Y1123376D01*
G02X362814Y1124651I243J1275D01*
G02X365408I1297J0D01*
G02X365336Y1124223I-1297J-2D01*
G01X365305Y1124136D01*
X366112Y1122739D01*
X366202Y1122722D01*
G02X367260Y1121447I-239J-1275D01*
G02X364664I-1298J0D01*
G02X364737Y1121874I1298J-2D01*
G01X364767Y1121960D01*
G37*
G36*
G01X372167D02*
X371359Y1123359D01*
X371269Y1123376D01*
G02X370214Y1124651I243J1275D01*
G02X372808I1297J0D01*
G02X372736Y1124223I-1297J-2D01*
G01X372705Y1124136D01*
X373512Y1122739D01*
X373602Y1122722D01*
G02X374660Y1121447I-239J-1275D01*
G02X372064I-1298J0D01*
G02X372137Y1121874I1298J-2D01*
G01X372167Y1121960D01*
G37*
G36*
G01X379567D02*
X378759Y1123359D01*
X378669Y1123376D01*
G02X377614Y1124651I243J1275D01*
G02X380208I1297J0D01*
G02X380136Y1124223I-1297J-2D01*
G01X380105Y1124136D01*
X380912Y1122739D01*
X381002Y1122722D01*
G02X382060Y1121447I-239J-1275D01*
G02X379464I-1298J0D01*
G02X379537Y1121874I1298J-2D01*
G01X379567Y1121960D01*
G37*
G36*
G01X386967D02*
X386159Y1123359D01*
X386069Y1123376D01*
G02X385014Y1124651I243J1275D01*
G02X387608I1297J0D01*
G02X387536Y1124223I-1297J-2D01*
G01X387505Y1124136D01*
X388312Y1122739D01*
X388402Y1122722D01*
G02X389460Y1121447I-239J-1275D01*
G02X386864I-1298J0D01*
G02X386937Y1121874I1298J-2D01*
G01X386967Y1121960D01*
G37*
G36*
G01X394367D02*
X393559Y1123359D01*
X393469Y1123376D01*
G02X392414Y1124651I243J1275D01*
G02X395008I1297J0D01*
G02X394936Y1124223I-1297J-2D01*
G01X394905Y1124136D01*
X395712Y1122739D01*
X395802Y1122722D01*
G02X396860Y1121447I-239J-1275D01*
G02X394264I-1298J0D01*
G02X394337Y1121874I1298J-2D01*
G01X394367Y1121960D01*
G37*
G36*
G01X401767D02*
X400959Y1123359D01*
X400869Y1123376D01*
G02X399814Y1124651I243J1275D01*
G02X402408I1297J0D01*
G02X402336Y1124223I-1297J-2D01*
G01X402305Y1124136D01*
X403112Y1122739D01*
X403202Y1122722D01*
G02X404260Y1121447I-239J-1275D01*
G02X401664I-1298J0D01*
G02X401737Y1121874I1298J-2D01*
G01X401767Y1121960D01*
G37*
G36*
G01X352859Y1125943D02*
X353667Y1127341D01*
X353636Y1127428D01*
G02X353564Y1127856I1225J426D01*
G02X356158I1297J0D01*
G02X355103Y1126581I-1298J0D01*
G01X355013Y1126564D01*
X354205Y1125166D01*
X354236Y1125079D01*
G02X354308Y1124651I-1225J-426D01*
G02X351714I-1297J0D01*
G02X352769Y1125926I1298J0D01*
G01X352859Y1125943D01*
G37*
G36*
G01X360260D02*
X361068Y1127341D01*
X361037Y1127428D01*
G02X360964Y1127856I1225J429D01*
G02X363560I1298J0D01*
G02X362504Y1126581I-1298J0D01*
G01X362414Y1126564D01*
X361606Y1125166D01*
X361637Y1125079D01*
G02X361710Y1124651I-1225J-429D01*
G02X359114I-1298J0D01*
G02X360170Y1125926I1298J0D01*
G01X360260Y1125943D01*
G37*
G36*
G01X367661D02*
X368468Y1127341D01*
X368437Y1127428D01*
G02X368364Y1127856I1225J429D01*
G02X370960I1298J0D01*
G02X369904Y1126581I-1298J0D01*
G01X369814Y1126564D01*
X369006Y1125165D01*
X369036Y1125078D01*
G02X369108Y1124651I-1225J-426D01*
G02X366514I-1297J0D01*
G02X367570Y1125926I1298J0D01*
G01X367661Y1125943D01*
G37*
G36*
G01X375061D02*
X375868Y1127341D01*
X375837Y1127428D01*
G02X375764Y1127856I1225J429D01*
G02X378360I1298J0D01*
G02X377304Y1126581I-1298J0D01*
G01X377214Y1126564D01*
X376406Y1125165D01*
X376436Y1125078D01*
G02X376508Y1124651I-1225J-426D01*
G02X373914I-1297J0D01*
G02X374970Y1125926I1298J0D01*
G01X375061Y1125943D01*
G37*
G36*
G01X382461D02*
X383268Y1127341D01*
X383237Y1127428D01*
G02X383164Y1127856I1225J429D01*
G02X385760I1298J0D01*
G02X384704Y1126581I-1298J0D01*
G01X384614Y1126564D01*
X383806Y1125165D01*
X383836Y1125078D01*
G02X383908Y1124651I-1225J-426D01*
G02X381314I-1297J0D01*
G02X382370Y1125926I1298J0D01*
G01X382461Y1125943D01*
G37*
G36*
G01X389861D02*
X390668Y1127341D01*
X390637Y1127428D01*
G02X390564Y1127856I1225J429D01*
G02X393160I1298J0D01*
G02X392104Y1126581I-1298J0D01*
G01X392014Y1126564D01*
X391206Y1125165D01*
X391236Y1125078D01*
G02X391308Y1124651I-1225J-426D01*
G02X388714I-1297J0D01*
G02X389770Y1125926I1298J0D01*
G01X389861Y1125943D01*
G37*
G36*
G01X397261D02*
X398068Y1127341D01*
X398037Y1127428D01*
G02X397964Y1127856I1225J429D01*
G02X400560I1298J0D01*
G02X399504Y1126581I-1298J0D01*
G01X399414Y1126564D01*
X398606Y1125165D01*
X398636Y1125078D01*
G02X398708Y1124651I-1225J-426D01*
G02X396114I-1297J0D01*
G02X397170Y1125926I1298J0D01*
G01X397261Y1125943D01*
G37*
G36*
G01X404661D02*
X405468Y1127341D01*
X405437Y1127428D01*
G02X405364Y1127856I1225J429D01*
G02X407960I1298J0D01*
G02X406904Y1126581I-1298J0D01*
G01X406814Y1126564D01*
X406006Y1125165D01*
X406036Y1125078D01*
G02X406108Y1124651I-1225J-426D01*
G02X403514I-1297J0D01*
G02X404570Y1125926I1298J0D01*
G01X404661Y1125943D01*
G37*
G36*
G01X339909Y1129148D02*
X340716Y1130546D01*
X340686Y1130632D01*
G02X340614Y1131060I1225J426D01*
G02X343208I1297J0D01*
G02X342153Y1129785I-1298J0D01*
G01X342063Y1129768D01*
X341256Y1128370D01*
X341286Y1128284D01*
G02X341358Y1127856I-1225J-426D01*
G02X338764I-1297J0D01*
G02X339819Y1129131I1298J0D01*
G01X339909Y1129148D01*
G37*
G36*
G01X459739Y842761D02*
X460580Y844356D01*
X460541Y844444D01*
G02X460430Y844971I1186J525D01*
G02X463024I1297J0D01*
G02X461962Y843695I-1298J0D01*
G01X461867Y843677D01*
X461026Y842082D01*
X461065Y841994D01*
G02X461176Y841467I-1186J-525D01*
G02X458582I-1297J0D01*
G02X459644Y842743I1298J0D01*
G01X459739Y842761D01*
G37*
G36*
G01X467139D02*
X467980Y844356D01*
X467941Y844444D01*
G02X467830Y844971I1186J525D01*
G02X470424I1297J0D01*
G02X469362Y843695I-1298J0D01*
G01X469267Y843677D01*
X468426Y842082D01*
X468465Y841994D01*
G02X468576Y841467I-1186J-525D01*
G02X465982I-1297J0D01*
G02X467044Y842743I1298J0D01*
G01X467139Y842761D01*
G37*
G36*
G01X474539D02*
X475380Y844356D01*
X475341Y844444D01*
G02X475230Y844971I1186J525D01*
G02X477824I1297J0D01*
G02X476762Y843695I-1298J0D01*
G01X476667Y843677D01*
X475826Y842082D01*
X475865Y841994D01*
G02X475976Y841467I-1186J-525D01*
G02X473382I-1297J0D01*
G02X474444Y842743I1298J0D01*
G01X474539Y842761D01*
G37*
G36*
G01X481939D02*
X482780Y844356D01*
X482741Y844444D01*
G02X482630Y844971I1186J525D01*
G02X485224I1297J0D01*
G02X484162Y843695I-1298J0D01*
G01X484067Y843677D01*
X483226Y842082D01*
X483265Y841994D01*
G02X483376Y841467I-1186J-525D01*
G02X480782I-1297J0D01*
G02X481844Y842743I1298J0D01*
G01X481939Y842761D01*
G37*
G36*
G01X489420Y842767D02*
X490213Y844297D01*
X490168Y844389D01*
G02X490030Y844971I1158J582D01*
G02X492624I1297J0D01*
G02X491519Y843688I-1297J0D01*
G01X491418Y843673D01*
X490608Y842112D01*
X490651Y842023D01*
G02X490776Y841467I-1174J-556D01*
G02X488180I-1298J0D01*
G02X489315Y842754I1297J0D01*
G01X489420Y842767D01*
G37*
G36*
G01X496739Y842761D02*
X497580Y844356D01*
X497541Y844444D01*
G02X497430Y844971I1186J525D01*
G02X500024I1297J0D01*
G02X498962Y843695I-1298J0D01*
G01X498867Y843677D01*
X498025Y842081D01*
X498064Y841993D01*
G02X498176Y841467I-1186J-527D01*
G02X495580I-1298J0D01*
G02X496644Y842743I1297J0D01*
G01X496739Y842761D01*
G37*
G36*
G01X464233Y845486D02*
X463426Y846884D01*
X463336Y846901D01*
G02X462280Y848176I242J1275D01*
G02X464876I1298J0D01*
G02X464803Y847747I-1297J0D01*
G01X464772Y847661D01*
X465579Y846263D01*
X465669Y846246D01*
G02X466724Y844971I-243J-1275D01*
G02X464130I-1297J0D01*
G02X464202Y845400I1297J3D01*
G01X464233Y845486D01*
G37*
G36*
G01X471633D02*
X470826Y846884D01*
X470736Y846901D01*
G02X469680Y848176I242J1275D01*
G02X472276I1298J0D01*
G02X472203Y847747I-1297J0D01*
G01X472172Y847661D01*
X472979Y846263D01*
X473069Y846246D01*
G02X474124Y844971I-243J-1275D01*
G02X471530I-1297J0D01*
G02X471602Y845400I1297J3D01*
G01X471633Y845486D01*
G37*
G36*
G01X479033D02*
X478226Y846884D01*
X478136Y846901D01*
G02X477080Y848176I242J1275D01*
G02X479676I1298J0D01*
G02X479603Y847747I-1297J0D01*
G01X479572Y847661D01*
X480379Y846263D01*
X480469Y846246D01*
G02X481524Y844971I-243J-1275D01*
G02X478930I-1297J0D01*
G02X479002Y845400I1297J3D01*
G01X479033Y845486D01*
G37*
G36*
G01X486433D02*
X485626Y846884D01*
X485536Y846901D01*
G02X484480Y848176I242J1275D01*
G02X487076I1298J0D01*
G02X487003Y847747I-1297J0D01*
G01X486972Y847661D01*
X487779Y846263D01*
X487869Y846246D01*
G02X488924Y844971I-243J-1275D01*
G02X486330I-1297J0D01*
G02X486402Y845400I1297J3D01*
G01X486433Y845486D01*
G37*
G36*
G01X493833D02*
X493026Y846884D01*
X492936Y846901D01*
G02X491880Y848176I242J1275D01*
G02X494476I1298J0D01*
G02X494403Y847747I-1297J0D01*
G01X494372Y847661D01*
X495179Y846263D01*
X495269Y846246D01*
G02X496324Y844971I-243J-1275D01*
G02X493730I-1297J0D01*
G02X493802Y845400I1297J3D01*
G01X493833Y845486D01*
G37*
G36*
G01X459728Y855876D02*
X460535Y857274D01*
X460504Y857361D01*
G02X460432Y857789I1225J426D01*
G02X463026I1297J0D01*
G02X461971Y856514I-1298J0D01*
G01X461881Y856497D01*
X461073Y855098D01*
X461103Y855011D01*
G02X461176Y854584I-1225J-429D01*
G02X458580I-1298J0D01*
G02X459638Y855859I1297J0D01*
G01X459728Y855876D01*
G37*
G36*
G01X467128D02*
X467935Y857274D01*
X467904Y857361D01*
G02X467832Y857789I1225J426D01*
G02X470426I1297J0D01*
G02X469371Y856514I-1298J0D01*
G01X469281Y856497D01*
X468473Y855098D01*
X468503Y855011D01*
G02X468576Y854584I-1225J-429D01*
G02X465980I-1298J0D01*
G02X467038Y855859I1297J0D01*
G01X467128Y855876D01*
G37*
G36*
G01X474528D02*
X475335Y857274D01*
X475304Y857361D01*
G02X475232Y857789I1225J426D01*
G02X477826I1297J0D01*
G02X476771Y856514I-1298J0D01*
G01X476681Y856497D01*
X475873Y855098D01*
X475903Y855011D01*
G02X475976Y854584I-1225J-429D01*
G02X473380I-1298J0D01*
G02X474438Y855859I1297J0D01*
G01X474528Y855876D01*
G37*
G36*
G01X481928D02*
X482735Y857274D01*
X482704Y857361D01*
G02X482632Y857789I1225J426D01*
G02X485226I1297J0D01*
G02X484171Y856514I-1298J0D01*
G01X484081Y856497D01*
X483273Y855098D01*
X483303Y855011D01*
G02X483376Y854584I-1225J-429D01*
G02X480780I-1298J0D01*
G02X481838Y855859I1297J0D01*
G01X481928Y855876D01*
G37*
G36*
G01X489328D02*
X490135Y857274D01*
X490104Y857361D01*
G02X490032Y857789I1225J426D01*
G02X492626I1297J0D01*
G02X491571Y856514I-1298J0D01*
G01X491481Y856497D01*
X490673Y855098D01*
X490703Y855011D01*
G02X490776Y854584I-1225J-429D01*
G02X488180I-1298J0D01*
G02X489238Y855859I1297J0D01*
G01X489328Y855876D01*
G37*
G36*
G01X496728D02*
X497535Y857274D01*
X497504Y857361D01*
G02X497432Y857789I1225J426D01*
G02X500026I1297J0D01*
G02X498971Y856514I-1298J0D01*
G01X498881Y856497D01*
X498073Y855098D01*
X498103Y855011D01*
G02X498176Y854584I-1225J-429D01*
G02X495580I-1298J0D01*
G02X496638Y855859I1297J0D01*
G01X496728Y855876D01*
G37*
G36*
G01X464234Y858302D02*
X463426Y859701D01*
X463336Y859718D01*
G02X462280Y860993I242J1275D01*
G02X464876I1298J0D01*
G02X464803Y860564I-1297J0D01*
G01X464772Y860478D01*
X465578Y859081D01*
X465668Y859064D01*
G02X466726Y857789I-239J-1275D01*
G02X464132I-1297J0D01*
G02X464203Y858215I1297J3D01*
G01X464234Y858302D01*
G37*
G36*
G01X471634D02*
X470826Y859701D01*
X470736Y859718D01*
G02X469680Y860993I242J1275D01*
G02X472276I1298J0D01*
G02X472203Y860564I-1297J0D01*
G01X472172Y860478D01*
X472978Y859081D01*
X473068Y859064D01*
G02X474126Y857789I-239J-1275D01*
G02X471532I-1297J0D01*
G02X471603Y858215I1297J3D01*
G01X471634Y858302D01*
G37*
G36*
G01X479034D02*
X478226Y859701D01*
X478136Y859718D01*
G02X477080Y860993I242J1275D01*
G02X479676I1298J0D01*
G02X479603Y860564I-1297J0D01*
G01X479572Y860478D01*
X480378Y859081D01*
X480468Y859064D01*
G02X481526Y857789I-239J-1275D01*
G02X478932I-1297J0D01*
G02X479003Y858215I1297J3D01*
G01X479034Y858302D01*
G37*
G36*
G01X486434D02*
X485626Y859701D01*
X485536Y859718D01*
G02X484480Y860993I242J1275D01*
G02X487076I1298J0D01*
G02X487003Y860564I-1297J0D01*
G01X486972Y860478D01*
X487778Y859081D01*
X487868Y859064D01*
G02X488926Y857789I-239J-1275D01*
G02X486332I-1297J0D01*
G02X486403Y858215I1297J3D01*
G01X486434Y858302D01*
G37*
G36*
G01X493834D02*
X493026Y859701D01*
X492936Y859718D01*
G02X491880Y860993I242J1275D01*
G02X494476I1298J0D01*
G02X494403Y860564I-1297J0D01*
G01X494372Y860478D01*
X495178Y859081D01*
X495268Y859064D01*
G02X496326Y857789I-239J-1275D01*
G02X493732I-1297J0D01*
G02X493803Y858215I1297J3D01*
G01X493834Y858302D01*
G37*
G36*
G01X459728Y868693D02*
X460535Y870091D01*
X460504Y870178D01*
G02X460432Y870606I1225J426D01*
G02X463026I1297J0D01*
G02X461971Y869331I-1298J0D01*
G01X461881Y869314D01*
X461073Y867915D01*
X461103Y867828D01*
G02X461176Y867401I-1225J-429D01*
G02X458580I-1298J0D01*
G02X459638Y868676I1297J0D01*
G01X459728Y868693D01*
G37*
G36*
G01X467128D02*
X467935Y870091D01*
X467904Y870178D01*
G02X467832Y870606I1225J426D01*
G02X470426I1297J0D01*
G02X469371Y869331I-1298J0D01*
G01X469281Y869314D01*
X468473Y867915D01*
X468503Y867828D01*
G02X468576Y867401I-1225J-429D01*
G02X465980I-1298J0D01*
G02X467038Y868676I1297J0D01*
G01X467128Y868693D01*
G37*
G36*
G01X474528D02*
X475335Y870091D01*
X475304Y870178D01*
G02X475232Y870606I1225J426D01*
G02X477826I1297J0D01*
G02X476771Y869331I-1298J0D01*
G01X476681Y869314D01*
X475873Y867915D01*
X475903Y867828D01*
G02X475976Y867401I-1225J-429D01*
G02X473380I-1298J0D01*
G02X474438Y868676I1297J0D01*
G01X474528Y868693D01*
G37*
G36*
G01X481928D02*
X482735Y870091D01*
X482704Y870178D01*
G02X482632Y870606I1225J426D01*
G02X485226I1297J0D01*
G02X484171Y869331I-1298J0D01*
G01X484081Y869314D01*
X483273Y867915D01*
X483303Y867828D01*
G02X483376Y867401I-1225J-429D01*
G02X480780I-1298J0D01*
G02X481838Y868676I1297J0D01*
G01X481928Y868693D01*
G37*
G36*
G01X489328D02*
X490135Y870091D01*
X490104Y870178D01*
G02X490032Y870606I1225J426D01*
G02X492626I1297J0D01*
G02X491571Y869331I-1298J0D01*
G01X491481Y869314D01*
X490673Y867915D01*
X490703Y867828D01*
G02X490776Y867401I-1225J-429D01*
G02X488180I-1298J0D01*
G02X489238Y868676I1297J0D01*
G01X489328Y868693D01*
G37*
G36*
G01X496728D02*
X497535Y870091D01*
X497504Y870178D01*
G02X497432Y870606I1225J426D01*
G02X500026I1297J0D01*
G02X498971Y869331I-1298J0D01*
G01X498881Y869314D01*
X498073Y867915D01*
X498103Y867828D01*
G02X498176Y867401I-1225J-429D01*
G02X495580I-1298J0D01*
G02X496638Y868676I1297J0D01*
G01X496728Y868693D01*
G37*
G36*
G01X464234Y871119D02*
X463426Y872518D01*
X463336Y872535D01*
G02X462280Y873810I242J1275D01*
G02X464876I1298J0D01*
G02X464803Y873381I-1297J0D01*
G01X464772Y873295D01*
X465578Y871898D01*
X465668Y871881D01*
G02X466726Y870606I-239J-1275D01*
G02X464132I-1297J0D01*
G02X464203Y871032I1297J3D01*
G01X464234Y871119D01*
G37*
G36*
G01X479034D02*
X478226Y872518D01*
X478136Y872535D01*
G02X477080Y873810I242J1275D01*
G02X479676I1298J0D01*
G02X479603Y873381I-1297J0D01*
G01X479572Y873295D01*
X480378Y871898D01*
X480468Y871881D01*
G02X481526Y870606I-239J-1275D01*
G02X478932I-1297J0D01*
G02X479003Y871032I1297J3D01*
G01X479034Y871119D01*
G37*
G36*
G01X486434D02*
X485626Y872518D01*
X485536Y872535D01*
G02X484480Y873810I242J1275D01*
G02X487076I1298J0D01*
G02X487003Y873381I-1297J0D01*
G01X486972Y873295D01*
X487778Y871898D01*
X487868Y871881D01*
G02X488926Y870606I-239J-1275D01*
G02X486332I-1297J0D01*
G02X486403Y871032I1297J3D01*
G01X486434Y871119D01*
G37*
G36*
G01X493834D02*
X493026Y872518D01*
X492936Y872535D01*
G02X491880Y873810I242J1275D01*
G02X494476I1298J0D01*
G02X494403Y873381I-1297J0D01*
G01X494372Y873295D01*
X495178Y871898D01*
X495268Y871881D01*
G02X496326Y870606I-239J-1275D01*
G02X493732I-1297J0D01*
G02X493803Y871032I1297J3D01*
G01X493834Y871119D01*
G37*
G36*
G01X458683Y880734D02*
X457877Y882131D01*
X457787Y882148D01*
G02X456732Y883423I243J1275D01*
G02X459326I1297J0D01*
G02X459254Y882994I-1297J-3D01*
G01X459223Y882908D01*
X460029Y881511D01*
X460119Y881494D01*
G02X461176Y880219I-240J-1275D01*
G02X458580I-1298J0D01*
G02X458653Y880647I1298J-1D01*
G01X458683Y880734D01*
G37*
G36*
G01X466083D02*
X465277Y882131D01*
X465187Y882148D01*
G02X464132Y883423I243J1275D01*
G02X466726I1297J0D01*
G02X466654Y882994I-1297J-3D01*
G01X466623Y882908D01*
X467429Y881511D01*
X467519Y881494D01*
G02X468576Y880219I-240J-1275D01*
G02X465980I-1298J0D01*
G02X466053Y880647I1298J-1D01*
G01X466083Y880734D01*
G37*
G36*
G01X473483D02*
X472677Y882131D01*
X472587Y882148D01*
G02X471532Y883423I243J1275D01*
G02X474126I1297J0D01*
G02X474054Y882994I-1297J-3D01*
G01X474023Y882908D01*
X474829Y881511D01*
X474919Y881494D01*
G02X475976Y880219I-240J-1275D01*
G02X473380I-1298J0D01*
G02X473453Y880647I1298J-1D01*
G01X473483Y880734D01*
G37*
G36*
G01X480883D02*
X480077Y882131D01*
X479987Y882148D01*
G02X478932Y883423I243J1275D01*
G02X481526I1297J0D01*
G02X481454Y882994I-1297J-3D01*
G01X481423Y882908D01*
X482229Y881511D01*
X482319Y881494D01*
G02X483376Y880219I-240J-1275D01*
G02X480780I-1298J0D01*
G02X480853Y880647I1298J-1D01*
G01X480883Y880734D01*
G37*
G36*
G01X488283D02*
X487477Y882131D01*
X487387Y882148D01*
G02X486332Y883423I243J1275D01*
G02X488926I1297J0D01*
G02X488854Y882994I-1297J-3D01*
G01X488823Y882908D01*
X489629Y881511D01*
X489719Y881494D01*
G02X490776Y880219I-240J-1275D01*
G02X488180I-1298J0D01*
G02X488253Y880647I1298J-1D01*
G01X488283Y880734D01*
G37*
G36*
G01X495683D02*
X494877Y882131D01*
X494787Y882148D01*
G02X493732Y883423I243J1275D01*
G02X496326I1297J0D01*
G02X496254Y882994I-1297J-3D01*
G01X496223Y882908D01*
X497029Y881511D01*
X497119Y881494D01*
G02X498176Y880219I-240J-1275D01*
G02X495580I-1298J0D01*
G02X495653Y880647I1298J-1D01*
G01X495683Y880734D01*
G37*
G36*
G01X461577Y884715D02*
X462384Y886112D01*
X462353Y886199D01*
G02X462280Y886627I1225J429D01*
G02X464876I1298J0D01*
G02X463820Y885352I-1298J0D01*
G01X463730Y885335D01*
X462923Y883938D01*
X462954Y883851D01*
G02X463026Y883423I-1225J-426D01*
G02X460432I-1297J0D01*
G02X461487Y884698I1298J0D01*
G01X461577Y884715D01*
G37*
G36*
G01X468977D02*
X469784Y886112D01*
X469753Y886199D01*
G02X469680Y886627I1225J429D01*
G02X472276I1298J0D01*
G02X471220Y885352I-1298J0D01*
G01X471130Y885335D01*
X470323Y883938D01*
X470354Y883851D01*
G02X470426Y883423I-1225J-426D01*
G02X467832I-1297J0D01*
G02X468887Y884698I1298J0D01*
G01X468977Y884715D01*
G37*
G36*
G01X476377D02*
X477184Y886112D01*
X477153Y886199D01*
G02X477080Y886627I1225J429D01*
G02X479676I1298J0D01*
G02X478620Y885352I-1298J0D01*
G01X478530Y885335D01*
X477723Y883938D01*
X477754Y883851D01*
G02X477826Y883423I-1225J-426D01*
G02X475232I-1297J0D01*
G02X476287Y884698I1298J0D01*
G01X476377Y884715D01*
G37*
G36*
G01X483777D02*
X484584Y886112D01*
X484553Y886199D01*
G02X484480Y886627I1225J429D01*
G02X487076I1298J0D01*
G02X486020Y885352I-1298J0D01*
G01X485930Y885335D01*
X485123Y883938D01*
X485154Y883851D01*
G02X485226Y883423I-1225J-426D01*
G02X482632I-1297J0D01*
G02X483687Y884698I1298J0D01*
G01X483777Y884715D01*
G37*
G36*
G01X491177D02*
X491984Y886112D01*
X491953Y886199D01*
G02X491880Y886627I1225J429D01*
G02X494476I1298J0D01*
G02X493420Y885352I-1298J0D01*
G01X493330Y885335D01*
X492523Y883938D01*
X492554Y883851D01*
G02X492626Y883423I-1225J-426D01*
G02X490032I-1297J0D01*
G02X491087Y884698I1298J0D01*
G01X491177Y884715D01*
G37*
G36*
G01X444266Y843894D02*
G02X443227Y843374I-1039J778D01*
G02Y845968I0J1297D01*
G02X444266Y845448I0J-1298D01*
G01X445888D01*
G02X446927Y845968I1039J-778D01*
G02Y843374I0J-1297D01*
G02X445888Y843894I0J1298D01*
G01X444266D01*
G37*
G36*
G01X400539Y842761D02*
X401380Y844356D01*
X401341Y844444D01*
G02X401230Y844971I1186J525D01*
G02X403824I1297J0D01*
G02X402762Y843695I-1298J0D01*
G01X402667Y843677D01*
X401826Y842082D01*
X401865Y841994D01*
G02X401976Y841467I-1186J-525D01*
G02X399382I-1297J0D01*
G02X400444Y842743I1298J0D01*
G01X400539Y842761D01*
G37*
G36*
G01X407939D02*
X408780Y844356D01*
X408741Y844444D01*
G02X408630Y844971I1186J525D01*
G02X411224I1297J0D01*
G02X410162Y843695I-1298J0D01*
G01X410067Y843677D01*
X409226Y842082D01*
X409265Y841994D01*
G02X409376Y841467I-1186J-525D01*
G02X406782I-1297J0D01*
G02X407844Y842743I1298J0D01*
G01X407939Y842761D01*
G37*
G36*
G01X415339D02*
X416180Y844356D01*
X416141Y844444D01*
G02X416030Y844971I1186J525D01*
G02X418624I1297J0D01*
G02X417562Y843695I-1298J0D01*
G01X417467Y843677D01*
X416626Y842082D01*
X416665Y841994D01*
G02X416776Y841467I-1186J-525D01*
G02X414182I-1297J0D01*
G02X415244Y842743I1298J0D01*
G01X415339Y842761D01*
G37*
G36*
G01X422739D02*
X423580Y844356D01*
X423541Y844444D01*
G02X423430Y844971I1186J525D01*
G02X426024I1297J0D01*
G02X424962Y843695I-1298J0D01*
G01X424867Y843677D01*
X424026Y842082D01*
X424065Y841994D01*
G02X424176Y841467I-1186J-525D01*
G02X421582I-1297J0D01*
G02X422644Y842743I1298J0D01*
G01X422739Y842761D01*
G37*
G36*
G01X405033Y845486D02*
X404226Y846884D01*
X404136Y846901D01*
G02X403080Y848176I242J1275D01*
G02X405676I1298J0D01*
G02X405603Y847747I-1297J0D01*
G01X405572Y847661D01*
X406379Y846263D01*
X406469Y846246D01*
G02X407524Y844971I-243J-1275D01*
G02X404930I-1297J0D01*
G02X405002Y845400I1297J3D01*
G01X405033Y845486D01*
G37*
G36*
G01X412433D02*
X411626Y846884D01*
X411536Y846901D01*
G02X410480Y848176I242J1275D01*
G02X413076I1298J0D01*
G02X413003Y847747I-1297J0D01*
G01X412972Y847661D01*
X413779Y846263D01*
X413869Y846246D01*
G02X414924Y844971I-243J-1275D01*
G02X412330I-1297J0D01*
G02X412402Y845400I1297J3D01*
G01X412433Y845486D01*
G37*
G36*
G01X419833D02*
X419026Y846884D01*
X418936Y846901D01*
G02X417880Y848176I242J1275D01*
G02X420476I1298J0D01*
G02X420403Y847747I-1297J0D01*
G01X420372Y847661D01*
X421179Y846263D01*
X421269Y846246D01*
G02X422324Y844971I-243J-1275D01*
G02X419730I-1297J0D01*
G02X419802Y845400I1297J3D01*
G01X419833Y845486D01*
G37*
G36*
G01X427233D02*
X426426Y846884D01*
X426336Y846901D01*
G02X425280Y848176I242J1275D01*
G02X427876I1298J0D01*
G02X427803Y847747I-1297J0D01*
G01X427772Y847661D01*
X428579Y846263D01*
X428669Y846246D01*
G02X429724Y844971I-243J-1275D01*
G02X427130I-1297J0D01*
G02X427202Y845400I1297J3D01*
G01X427233Y845486D01*
G37*
G36*
G01X431317Y847398D02*
G02X430278Y846878I-1039J778D01*
G02Y849474I0J1298D01*
G02X431317Y848954I0J-1298D01*
G01X432939D01*
G02X433978Y849474I1039J-778D01*
G02Y846878I0J-1298D01*
G02X432939Y847398I0J1298D01*
G01X431317D01*
G37*
G36*
G01X435689Y845965D02*
X436531Y847561D01*
X436492Y847650D01*
G02X436380Y848176I1186J527D01*
G02X438976I1298J0D01*
G02X437913Y846900I-1297J0D01*
G01X437818Y846882D01*
X436976Y845286D01*
X437015Y845197D01*
G02X437126Y844671I-1186J-525D01*
G02X434532I-1297J0D01*
G02X435594Y845947I1298J0D01*
G01X435689Y845965D01*
G37*
G36*
G01X449434Y845486D02*
X448626Y846884D01*
X448536Y846901D01*
G02X447480Y848176I242J1275D01*
G02X450076I1298J0D01*
G02X450003Y847748I-1298J1D01*
G01X449972Y847661D01*
X450780Y846263D01*
X450870Y846246D01*
G02X451926Y844971I-242J-1275D01*
G02X449330I-1298J0D01*
G02X449403Y845399I1298J-1D01*
G01X449434Y845486D01*
G37*
G36*
G01X406884Y855099D02*
X406077Y856497D01*
X405987Y856514D01*
G02X404932Y857789I243J1275D01*
G02X407526I1297J0D01*
G02X407454Y857360I-1297J-3D01*
G01X407423Y857274D01*
X408230Y855876D01*
X408320Y855859D01*
G02X409376Y854584I-242J-1275D01*
G02X406780I-1298J0D01*
G02X406853Y855013I1297J0D01*
G01X406884Y855099D01*
G37*
G36*
G01X414284D02*
X413477Y856497D01*
X413387Y856514D01*
G02X412332Y857789I243J1275D01*
G02X414926I1297J0D01*
G02X414854Y857360I-1297J-3D01*
G01X414823Y857274D01*
X415630Y855876D01*
X415720Y855859D01*
G02X416776Y854584I-242J-1275D01*
G02X414180I-1298J0D01*
G02X414253Y855013I1297J0D01*
G01X414284Y855099D01*
G37*
G36*
G01X421684D02*
X420877Y856497D01*
X420787Y856514D01*
G02X419732Y857789I243J1275D01*
G02X422326I1297J0D01*
G02X422254Y857360I-1297J-3D01*
G01X422223Y857274D01*
X423030Y855876D01*
X423120Y855859D01*
G02X424176Y854584I-242J-1275D01*
G02X421580I-1298J0D01*
G02X421653Y855013I1297J0D01*
G01X421684Y855099D01*
G37*
G36*
G01X429084D02*
X428277Y856497D01*
X428187Y856514D01*
G02X427132Y857789I243J1275D01*
G02X429726I1297J0D01*
G02X429654Y857360I-1297J-3D01*
G01X429623Y857274D01*
X430430Y855876D01*
X430520Y855859D01*
G02X431576Y854584I-242J-1275D01*
G02X428980I-1298J0D01*
G02X429053Y855013I1297J0D01*
G01X429084Y855099D01*
G37*
G36*
G01X436484Y855098D02*
X435677Y856497D01*
X435587Y856514D01*
G02X434532Y857789I243J1275D01*
G02X437126I1297J0D01*
G02X437054Y857360I-1297J-3D01*
G01X437023Y857274D01*
X437830Y855876D01*
X437920Y855859D01*
G02X438976Y854584I-242J-1275D01*
G02X436382I-1297J0D01*
G02X436454Y855012I1297J2D01*
G01X436484Y855098D01*
G37*
G36*
G01X444928Y855876D02*
X445735Y857274D01*
X445704Y857361D01*
G02X445632Y857789I1225J426D01*
G02X448226I1297J0D01*
G02X447171Y856514I-1298J0D01*
G01X447081Y856497D01*
X446273Y855098D01*
X446303Y855011D01*
G02X446376Y854584I-1225J-429D01*
G02X443780I-1298J0D01*
G02X444838Y855859I1297J0D01*
G01X444928Y855876D01*
G37*
G36*
G01X402377Y859081D02*
X403184Y860478D01*
X403153Y860565D01*
G02X403080Y860993I1225J429D01*
G02X405676I1298J0D01*
G02X404620Y859718I-1298J0D01*
G01X404530Y859701D01*
X403723Y858304D01*
X403754Y858217D01*
G02X403826Y857789I-1225J-426D01*
G02X401232I-1297J0D01*
G02X402287Y859064I1298J0D01*
G01X402377Y859081D01*
G37*
G36*
G01X409777D02*
X410584Y860478D01*
X410553Y860565D01*
G02X410480Y860993I1225J429D01*
G02X413076I1298J0D01*
G02X412020Y859718I-1298J0D01*
G01X411930Y859701D01*
X411123Y858304D01*
X411154Y858217D01*
G02X411226Y857789I-1225J-426D01*
G02X408632I-1297J0D01*
G02X409687Y859064I1298J0D01*
G01X409777Y859081D01*
G37*
G36*
G01X417177D02*
X417984Y860478D01*
X417953Y860565D01*
G02X417880Y860993I1225J429D01*
G02X420476I1298J0D01*
G02X419420Y859718I-1298J0D01*
G01X419330Y859701D01*
X418523Y858304D01*
X418554Y858217D01*
G02X418626Y857789I-1225J-426D01*
G02X416032I-1297J0D01*
G02X417087Y859064I1298J0D01*
G01X417177Y859081D01*
G37*
G36*
G01X424577D02*
X425384Y860478D01*
X425353Y860565D01*
G02X425280Y860993I1225J429D01*
G02X427876I1298J0D01*
G02X426820Y859718I-1298J0D01*
G01X426730Y859701D01*
X425923Y858304D01*
X425954Y858217D01*
G02X426026Y857789I-1225J-426D01*
G02X423432I-1297J0D01*
G02X424487Y859064I1298J0D01*
G01X424577Y859081D01*
G37*
G36*
G01X431978D02*
X432785Y860478D01*
X432754Y860565D01*
G02X432682Y860993I1225J426D01*
G02X435276I1297J0D01*
G02X434221Y859718I-1298J0D01*
G01X434131Y859701D01*
X433324Y858303D01*
X433354Y858217D01*
G02X433426Y857789I-1225J-426D01*
G02X430832I-1297J0D01*
G02X431888Y859064I1298J0D01*
G01X431978Y859081D01*
G37*
G36*
G01X442034Y858302D02*
X441226Y859701D01*
X441136Y859718D01*
G02X440080Y860993I242J1275D01*
G02X442676I1298J0D01*
G02X442603Y860564I-1297J0D01*
G01X442572Y860478D01*
X443378Y859081D01*
X443468Y859064D01*
G02X444526Y857789I-239J-1275D01*
G02X441932I-1297J0D01*
G02X442003Y858215I1297J3D01*
G01X442034Y858302D01*
G37*
G36*
G01X449434Y858303D02*
X448627Y859701D01*
X448537Y859718D01*
G02X447482Y860993I243J1275D01*
G02X450076I1297J0D01*
G02X450004Y860564I-1297J-3D01*
G01X449973Y860478D01*
X450779Y859081D01*
X450869Y859064D01*
G02X451926Y857789I-240J-1275D01*
G02X449332I-1297J0D01*
G02X449404Y858216I1297J1D01*
G01X449434Y858303D01*
G37*
G36*
G01X415328Y868693D02*
X416135Y870091D01*
X416104Y870178D01*
G02X416032Y870606I1225J426D01*
G02X418626I1297J0D01*
G02X417571Y869331I-1298J0D01*
G01X417481Y869314D01*
X416673Y867915D01*
X416703Y867828D01*
G02X416776Y867401I-1225J-429D01*
G02X414180I-1298J0D01*
G02X415238Y868676I1297J0D01*
G01X415328Y868693D01*
G37*
G36*
G01X422728D02*
X423535Y870091D01*
X423504Y870178D01*
G02X423432Y870606I1225J426D01*
G02X426026I1297J0D01*
G02X424971Y869331I-1298J0D01*
G01X424881Y869314D01*
X424073Y867915D01*
X424103Y867828D01*
G02X424176Y867401I-1225J-429D01*
G02X421580I-1298J0D01*
G02X422638Y868676I1297J0D01*
G01X422728Y868693D01*
G37*
G36*
G01X430128D02*
X430935Y870091D01*
X430904Y870178D01*
G02X430832Y870606I1225J426D01*
G02X433426I1297J0D01*
G02X432371Y869331I-1298J0D01*
G01X432281Y869314D01*
X431473Y867915D01*
X431503Y867828D01*
G02X431576Y867401I-1225J-429D01*
G02X428980I-1298J0D01*
G02X430038Y868676I1297J0D01*
G01X430128Y868693D01*
G37*
G36*
G01X437528D02*
X438335Y870091D01*
X438304Y870178D01*
G02X438232Y870606I1225J426D01*
G02X440826I1297J0D01*
G02X439771Y869331I-1298J0D01*
G01X439681Y869314D01*
X438873Y867915D01*
X438903Y867828D01*
G02X438976Y867401I-1225J-429D01*
G02X436380I-1298J0D01*
G02X437438Y868676I1297J0D01*
G01X437528Y868693D01*
G37*
G36*
G01X444928D02*
X445735Y870091D01*
X445704Y870178D01*
G02X445632Y870606I1225J426D01*
G02X448226I1297J0D01*
G02X447171Y869331I-1298J0D01*
G01X447081Y869314D01*
X446273Y867915D01*
X446303Y867828D01*
G02X446376Y867401I-1225J-429D01*
G02X443780I-1298J0D01*
G02X444838Y868676I1297J0D01*
G01X444928Y868693D01*
G37*
G36*
G01X412434Y871119D02*
X411626Y872518D01*
X411536Y872535D01*
G02X410480Y873810I242J1275D01*
G02X413076I1298J0D01*
G02X413003Y873381I-1297J0D01*
G01X412972Y873295D01*
X413778Y871898D01*
X413868Y871881D01*
G02X414926Y870606I-239J-1275D01*
G02X412332I-1297J0D01*
G02X412403Y871032I1297J3D01*
G01X412434Y871119D01*
G37*
G36*
G01X419834D02*
X419026Y872518D01*
X418936Y872535D01*
G02X417880Y873810I242J1275D01*
G02X420476I1298J0D01*
G02X420403Y873381I-1297J0D01*
G01X420372Y873295D01*
X421178Y871898D01*
X421268Y871881D01*
G02X422326Y870606I-239J-1275D01*
G02X419732I-1297J0D01*
G02X419803Y871032I1297J3D01*
G01X419834Y871119D01*
G37*
G36*
G01X427234D02*
X426426Y872518D01*
X426336Y872535D01*
G02X425280Y873810I242J1275D01*
G02X427876I1298J0D01*
G02X427803Y873381I-1297J0D01*
G01X427772Y873295D01*
X428578Y871898D01*
X428668Y871881D01*
G02X429726Y870606I-239J-1275D01*
G02X427132I-1297J0D01*
G02X427203Y871032I1297J3D01*
G01X427234Y871119D01*
G37*
G36*
G01X434634Y871120D02*
X433827Y872518D01*
X433737Y872535D01*
G02X432682Y873810I243J1275D01*
G02X435276I1297J0D01*
G02X435204Y873381I-1297J-3D01*
G01X435173Y873295D01*
X435979Y871898D01*
X436069Y871881D01*
G02X437126Y870606I-240J-1275D01*
G02X434532I-1297J0D01*
G02X434604Y871033I1297J1D01*
G01X434634Y871120D01*
G37*
G36*
G01X442034Y871119D02*
X441226Y872518D01*
X441136Y872535D01*
G02X440080Y873810I242J1275D01*
G02X442676I1298J0D01*
G02X442603Y873381I-1297J0D01*
G01X442572Y873295D01*
X443378Y871898D01*
X443468Y871881D01*
G02X444526Y870606I-239J-1275D01*
G02X441932I-1297J0D01*
G02X442003Y871032I1297J3D01*
G01X442034Y871119D01*
G37*
G36*
G01X449434Y871120D02*
X448627Y872518D01*
X448537Y872535D01*
G02X447482Y873810I243J1275D01*
G02X450076I1297J0D01*
G02X450004Y873381I-1297J-3D01*
G01X449973Y873295D01*
X450779Y871898D01*
X450869Y871881D01*
G02X451926Y870606I-240J-1275D01*
G02X449332I-1297J0D01*
G02X449404Y871033I1297J1D01*
G01X449434Y871120D01*
G37*
G36*
G01X414283Y880734D02*
X413477Y882131D01*
X413387Y882148D01*
G02X412332Y883423I243J1275D01*
G02X414926I1297J0D01*
G02X414854Y882994I-1297J-3D01*
G01X414823Y882908D01*
X415629Y881511D01*
X415719Y881494D01*
G02X416776Y880219I-240J-1275D01*
G02X414180I-1298J0D01*
G02X414253Y880647I1298J-1D01*
G01X414283Y880734D01*
G37*
G36*
G01X421683D02*
X420877Y882131D01*
X420787Y882148D01*
G02X419732Y883423I243J1275D01*
G02X422326I1297J0D01*
G02X422254Y882994I-1297J-3D01*
G01X422223Y882908D01*
X423029Y881511D01*
X423119Y881494D01*
G02X424176Y880219I-240J-1275D01*
G02X421580I-1298J0D01*
G02X421653Y880647I1298J-1D01*
G01X421683Y880734D01*
G37*
G36*
G01X429083D02*
X428277Y882131D01*
X428187Y882148D01*
G02X427132Y883423I243J1275D01*
G02X429726I1297J0D01*
G02X429654Y882994I-1297J-3D01*
G01X429623Y882908D01*
X430429Y881511D01*
X430519Y881494D01*
G02X431576Y880219I-240J-1275D01*
G02X428980I-1298J0D01*
G02X429053Y880647I1298J-1D01*
G01X429083Y880734D01*
G37*
G36*
G01X436483D02*
X435677Y882131D01*
X435587Y882148D01*
G02X434532Y883423I243J1275D01*
G02X437126I1297J0D01*
G02X437054Y882994I-1297J-3D01*
G01X437023Y882908D01*
X437829Y881511D01*
X437919Y881494D01*
G02X438976Y880219I-240J-1275D01*
G02X436380I-1298J0D01*
G02X436453Y880647I1298J-1D01*
G01X436483Y880734D01*
G37*
G36*
G01X443883D02*
X443077Y882131D01*
X442987Y882148D01*
G02X441932Y883423I243J1275D01*
G02X444526I1297J0D01*
G02X444454Y882994I-1297J-3D01*
G01X444423Y882908D01*
X445229Y881511D01*
X445319Y881494D01*
G02X446376Y880219I-240J-1275D01*
G02X443780I-1298J0D01*
G02X443853Y880647I1298J-1D01*
G01X443883Y880734D01*
G37*
G36*
G01X409777Y884715D02*
X410584Y886112D01*
X410553Y886199D01*
G02X410480Y886627I1225J429D01*
G02X413076I1298J0D01*
G02X412020Y885352I-1298J0D01*
G01X411930Y885335D01*
X411123Y883938D01*
X411154Y883851D01*
G02X411226Y883423I-1225J-426D01*
G02X408632I-1297J0D01*
G02X409687Y884698I1298J0D01*
G01X409777Y884715D01*
G37*
G36*
G01X417177D02*
X417984Y886112D01*
X417953Y886199D01*
G02X417880Y886627I1225J429D01*
G02X420476I1298J0D01*
G02X419420Y885352I-1298J0D01*
G01X419330Y885335D01*
X418523Y883938D01*
X418554Y883851D01*
G02X418626Y883423I-1225J-426D01*
G02X416032I-1297J0D01*
G02X417087Y884698I1298J0D01*
G01X417177Y884715D01*
G37*
G36*
G01X424577D02*
X425384Y886112D01*
X425353Y886199D01*
G02X425280Y886627I1225J429D01*
G02X427876I1298J0D01*
G02X426820Y885352I-1298J0D01*
G01X426730Y885335D01*
X425923Y883938D01*
X425954Y883851D01*
G02X426026Y883423I-1225J-426D01*
G02X423432I-1297J0D01*
G02X424487Y884698I1298J0D01*
G01X424577Y884715D01*
G37*
G36*
G01X431977D02*
X432784Y886112D01*
X432753Y886199D01*
G02X432680Y886627I1225J429D01*
G02X435276I1298J0D01*
G02X434220Y885352I-1298J0D01*
G01X434130Y885335D01*
X433323Y883938D01*
X433354Y883851D01*
G02X433426Y883423I-1225J-426D01*
G02X430832I-1297J0D01*
G02X431887Y884698I1298J0D01*
G01X431977Y884715D01*
G37*
G36*
G01X439377D02*
X440184Y886112D01*
X440153Y886199D01*
G02X440080Y886627I1225J429D01*
G02X442676I1298J0D01*
G02X441620Y885352I-1298J0D01*
G01X441530Y885335D01*
X440723Y883938D01*
X440754Y883851D01*
G02X440826Y883423I-1225J-426D01*
G02X438232I-1297J0D01*
G02X439287Y884698I1298J0D01*
G01X439377Y884715D01*
G37*
G36*
G01X446777D02*
X447584Y886112D01*
X447553Y886199D01*
G02X447480Y886627I1225J429D01*
G02X450076I1298J0D01*
G02X449020Y885352I-1298J0D01*
G01X448930Y885335D01*
X448123Y883938D01*
X448154Y883851D01*
G02X448226Y883423I-1225J-426D01*
G02X445632I-1297J0D01*
G02X446687Y884698I1298J0D01*
G01X446777Y884715D01*
G37*
G36*
G01X356139Y842761D02*
X356980Y844356D01*
X356941Y844444D01*
G02X356830Y844971I1186J525D01*
G02X359424I1297J0D01*
G02X358362Y843695I-1298J0D01*
G01X358267Y843677D01*
X357426Y842082D01*
X357465Y841994D01*
G02X357576Y841467I-1186J-525D01*
G02X354982I-1297J0D01*
G02X356044Y842743I1298J0D01*
G01X356139Y842761D01*
G37*
G36*
G01X363539D02*
X364380Y844356D01*
X364341Y844444D01*
G02X364230Y844971I1186J525D01*
G02X366824I1297J0D01*
G02X365762Y843695I-1298J0D01*
G01X365667Y843677D01*
X364826Y842082D01*
X364865Y841994D01*
G02X364976Y841467I-1186J-525D01*
G02X362382I-1297J0D01*
G02X363444Y842743I1298J0D01*
G01X363539Y842761D01*
G37*
G36*
G01X370939D02*
X371780Y844356D01*
X371741Y844444D01*
G02X371630Y844971I1186J525D01*
G02X374224I1297J0D01*
G02X373162Y843695I-1298J0D01*
G01X373067Y843677D01*
X372226Y842082D01*
X372265Y841994D01*
G02X372376Y841467I-1186J-525D01*
G02X369782I-1297J0D01*
G02X370844Y842743I1298J0D01*
G01X370939Y842761D01*
G37*
G36*
G01X378339D02*
X379180Y844356D01*
X379141Y844444D01*
G02X379030Y844971I1186J525D01*
G02X381624I1297J0D01*
G02X380562Y843695I-1298J0D01*
G01X380467Y843677D01*
X379626Y842082D01*
X379665Y841994D01*
G02X379776Y841467I-1186J-525D01*
G02X377182I-1297J0D01*
G02X378244Y842743I1298J0D01*
G01X378339Y842761D01*
G37*
G36*
G01X385739D02*
X386580Y844356D01*
X386541Y844444D01*
G02X386430Y844971I1186J525D01*
G02X389024I1297J0D01*
G02X387962Y843695I-1298J0D01*
G01X387867Y843677D01*
X387026Y842082D01*
X387065Y841994D01*
G02X387176Y841467I-1186J-525D01*
G02X384582I-1297J0D01*
G02X385644Y842743I1298J0D01*
G01X385739Y842761D01*
G37*
G36*
G01X353233Y845486D02*
X352426Y846884D01*
X352336Y846901D01*
G02X351280Y848176I242J1275D01*
G02X353876I1298J0D01*
G02X353803Y847747I-1297J0D01*
G01X353772Y847661D01*
X354579Y846263D01*
X354669Y846246D01*
G02X355724Y844971I-243J-1275D01*
G02X353130I-1297J0D01*
G02X353202Y845400I1297J3D01*
G01X353233Y845486D01*
G37*
G36*
G01X360633D02*
X359826Y846884D01*
X359736Y846901D01*
G02X358680Y848176I242J1275D01*
G02X361276I1298J0D01*
G02X361203Y847747I-1297J0D01*
G01X361172Y847661D01*
X361979Y846263D01*
X362069Y846246D01*
G02X363124Y844971I-243J-1275D01*
G02X360530I-1297J0D01*
G02X360602Y845400I1297J3D01*
G01X360633Y845486D01*
G37*
G36*
G01X368033D02*
X367226Y846884D01*
X367136Y846901D01*
G02X366080Y848176I242J1275D01*
G02X368676I1298J0D01*
G02X368603Y847747I-1297J0D01*
G01X368572Y847661D01*
X369379Y846263D01*
X369469Y846246D01*
G02X370524Y844971I-243J-1275D01*
G02X367930I-1297J0D01*
G02X368002Y845400I1297J3D01*
G01X368033Y845486D01*
G37*
G36*
G01X375433D02*
X374626Y846884D01*
X374536Y846901D01*
G02X373480Y848176I242J1275D01*
G02X376076I1298J0D01*
G02X376003Y847747I-1297J0D01*
G01X375972Y847661D01*
X376779Y846263D01*
X376869Y846246D01*
G02X377924Y844971I-243J-1275D01*
G02X375330I-1297J0D01*
G02X375402Y845400I1297J3D01*
G01X375433Y845486D01*
G37*
G36*
G01X382833D02*
X382026Y846884D01*
X381936Y846901D01*
G02X380880Y848176I242J1275D01*
G02X383476I1298J0D01*
G02X383403Y847747I-1297J0D01*
G01X383372Y847661D01*
X384179Y846263D01*
X384269Y846246D01*
G02X385324Y844971I-243J-1275D01*
G02X382730I-1297J0D01*
G02X382802Y845400I1297J3D01*
G01X382833Y845486D01*
G37*
G36*
G01X390233D02*
X389426Y846884D01*
X389336Y846901D01*
G02X388280Y848176I242J1275D01*
G02X390876I1298J0D01*
G02X390803Y847747I-1297J0D01*
G01X390772Y847661D01*
X391579Y846263D01*
X391669Y846246D01*
G02X392724Y844971I-243J-1275D01*
G02X390130I-1297J0D01*
G02X390202Y845400I1297J3D01*
G01X390233Y845486D01*
G37*
G36*
G01X348726Y849468D02*
X349533Y850865D01*
X349502Y850952D01*
G02X349430Y851380I1225J426D01*
G02X352024I1297J0D01*
G02X350969Y850105I-1298J0D01*
G01X350879Y850088D01*
X350072Y848691D01*
X350103Y848604D01*
G02X350176Y848176I-1225J-429D01*
G02X347580I-1298J0D01*
G02X348636Y849451I1298J0D01*
G01X348726Y849468D01*
G37*
G36*
G01X384684Y855099D02*
X383877Y856497D01*
X383787Y856514D01*
G02X382732Y857789I243J1275D01*
G02X385326I1297J0D01*
G02X385254Y857360I-1297J-3D01*
G01X385223Y857274D01*
X386030Y855876D01*
X386120Y855859D01*
G02X387176Y854584I-242J-1275D01*
G02X384580I-1298J0D01*
G02X384653Y855013I1297J0D01*
G01X384684Y855099D01*
G37*
G36*
G01X392084D02*
X391277Y856497D01*
X391187Y856514D01*
G02X390132Y857789I243J1275D01*
G02X392726I1297J0D01*
G02X392654Y857360I-1297J-3D01*
G01X392623Y857274D01*
X393430Y855876D01*
X393520Y855859D01*
G02X394576Y854584I-242J-1275D01*
G02X391980I-1298J0D01*
G02X392053Y855013I1297J0D01*
G01X392084Y855099D01*
G37*
G36*
G01X380177Y859081D02*
X380984Y860478D01*
X380953Y860565D01*
G02X380880Y860993I1225J429D01*
G02X383476I1298J0D01*
G02X382420Y859718I-1298J0D01*
G01X382330Y859701D01*
X381523Y858304D01*
X381554Y858217D01*
G02X381626Y857789I-1225J-426D01*
G02X379032I-1297J0D01*
G02X380087Y859064I1298J0D01*
G01X380177Y859081D01*
G37*
G36*
G01X387577D02*
X388384Y860478D01*
X388353Y860565D01*
G02X388280Y860993I1225J429D01*
G02X390876I1298J0D01*
G02X389820Y859718I-1298J0D01*
G01X389730Y859701D01*
X388923Y858304D01*
X388954Y858217D01*
G02X389026Y857789I-1225J-426D01*
G02X386432I-1297J0D01*
G02X387487Y859064I1298J0D01*
G01X387577Y859081D01*
G37*
G36*
G01X392084Y867916D02*
X391277Y869314D01*
X391187Y869331D01*
G02X390132Y870606I243J1275D01*
G02X392726I1297J0D01*
G02X392654Y870177I-1297J-3D01*
G01X392623Y870091D01*
X393430Y868693D01*
X393520Y868676D01*
G02X394576Y867401I-242J-1275D01*
G02X391980I-1298J0D01*
G02X392053Y867830I1297J0D01*
G01X392084Y867916D01*
G37*
G36*
G01X387577Y871898D02*
X388384Y873295D01*
X388353Y873382D01*
G02X388280Y873810I1225J429D01*
G02X390876I1298J0D01*
G02X389820Y872535I-1298J0D01*
G01X389730Y872518D01*
X388923Y871121D01*
X388954Y871034D01*
G02X389026Y870606I-1225J-426D01*
G02X386432I-1297J0D01*
G02X387487Y871881I1298J0D01*
G01X387577Y871898D01*
G37*
G36*
G01X394977D02*
X395784Y873295D01*
X395753Y873382D01*
G02X395680Y873810I1225J429D01*
G02X398276I1298J0D01*
G02X397220Y872535I-1298J0D01*
G01X397130Y872518D01*
X396323Y871121D01*
X396354Y871034D01*
G02X396426Y870606I-1225J-426D01*
G02X393832I-1297J0D01*
G02X394887Y871881I1298J0D01*
G01X394977Y871898D01*
G37*
G36*
G01X392083Y880734D02*
X391277Y882131D01*
X391187Y882148D01*
G02X390132Y883423I243J1275D01*
G02X392726I1297J0D01*
G02X392654Y882994I-1297J-3D01*
G01X392623Y882908D01*
X393429Y881511D01*
X393519Y881494D01*
G02X394576Y880219I-240J-1275D01*
G02X391980I-1298J0D01*
G02X392053Y880647I1298J-1D01*
G01X392083Y880734D01*
G37*
G36*
G01X399483D02*
X398677Y882131D01*
X398587Y882148D01*
G02X397532Y883423I243J1275D01*
G02X400126I1297J0D01*
G02X400054Y882994I-1297J-3D01*
G01X400023Y882908D01*
X400829Y881511D01*
X400919Y881494D01*
G02X401976Y880219I-240J-1275D01*
G02X399380I-1298J0D01*
G02X399453Y880647I1298J-1D01*
G01X399483Y880734D01*
G37*
G36*
G01X387577Y884715D02*
X388384Y886112D01*
X388353Y886199D01*
G02X388280Y886627I1225J429D01*
G02X390876I1298J0D01*
G02X389820Y885352I-1298J0D01*
G01X389730Y885335D01*
X388923Y883938D01*
X388954Y883851D01*
G02X389026Y883423I-1225J-426D01*
G02X386432I-1297J0D01*
G02X387487Y884698I1298J0D01*
G01X387577Y884715D01*
G37*
G36*
G01X394977D02*
X395784Y886112D01*
X395753Y886199D01*
G02X395680Y886627I1225J429D01*
G02X398276I1298J0D01*
G02X397220Y885352I-1298J0D01*
G01X397130Y885335D01*
X396323Y883938D01*
X396354Y883851D01*
G02X396426Y883423I-1225J-426D01*
G02X393832I-1297J0D01*
G02X394887Y884698I1298J0D01*
G01X394977Y884715D01*
G37*
G36*
G01X428710Y1077879D02*
X429517Y1079276D01*
X429486Y1079363D01*
G02X429414Y1079791I1225J426D01*
G02X432008I1297J0D01*
G02X430953Y1078516I-1298J0D01*
G01X430863Y1078499D01*
X430056Y1077101D01*
X430086Y1077015D01*
G02X430158Y1076587I-1225J-426D01*
G02X427564I-1297J0D01*
G02X428620Y1077862I1298J0D01*
G01X428710Y1077879D01*
G37*
G36*
G01X429516Y1086715D02*
X428709Y1088112D01*
X428619Y1088129D01*
G02X427564Y1089404I243J1275D01*
G02X430158I1297J0D01*
G02X430086Y1088976I-1297J-2D01*
G01X430055Y1088889D01*
X430862Y1087492D01*
X430952Y1087475D01*
G02X432008Y1086200I-242J-1275D01*
G02X429412I-1298J0D01*
G02X429485Y1086629I1297J0D01*
G01X429516Y1086715D01*
G37*
G36*
G01X473965Y1138083D02*
X473121Y1139679D01*
X473026Y1139697D01*
G02X471964Y1140973I236J1276D01*
G02X474558I1297J0D01*
G02X474447Y1140448I-1297J0D01*
G01X474408Y1140359D01*
X475252Y1138763D01*
X475347Y1138745D01*
G02X476410Y1137469I-234J-1276D01*
G02X473814I-1298J0D01*
G02X473926Y1137994I1297J-2D01*
G01X473965Y1138083D01*
G37*
G36*
G01X523433Y871118D02*
X522626Y872518D01*
X522536Y872535D01*
G02X521480Y873810I242J1275D01*
G02X524076I1298J0D01*
G01Y873808D01*
G02X524003Y873381I-1298J2D01*
G01X523973Y873295D01*
X524779Y871898D01*
X524869Y871881D01*
G02X525926Y870606I-240J-1275D01*
G02X523332I-1297J0D01*
G01Y870607D01*
G02X523403Y871032I1297J2D01*
G01X523433Y871118D01*
G37*
G36*
G01X517883Y880733D02*
X517077Y882131D01*
X516987Y882148D01*
G02X515932Y883423I243J1275D01*
G02X518526I1297J0D01*
G01Y883421D01*
G02X518454Y882994I-1298J-1D01*
G01X518424Y882908D01*
X519230Y881511D01*
X519320Y881494D01*
G02X520376Y880219I-242J-1275D01*
G02X517780I-1298J0D01*
G02X517853Y880647I1299J-1D01*
G01X517883Y880733D01*
G37*
G36*
G01X530833Y871118D02*
X530026Y872518D01*
X529936Y872535D01*
G02X528880Y873810I242J1275D01*
G02X531476I1298J0D01*
G01Y873808D01*
G02X531403Y873381I-1298J2D01*
G01X531373Y873295D01*
X532179Y871898D01*
X532269Y871881D01*
G02X533326Y870606I-240J-1275D01*
G02X530732I-1297J0D01*
G01Y870607D01*
G02X530803Y871032I1297J2D01*
G01X530833Y871118D01*
G37*
G36*
G01X528954Y886198D02*
G02X528882Y886625I1226J426D01*
G01Y886627D01*
G02X531476I1297J0D01*
G02X530421Y885352I-1298J0D01*
G01X530331Y885335D01*
X529524Y883937D01*
X529554Y883851D01*
G02X529626Y883423I-1226J-426D01*
G02X527032I-1297J0D01*
G02X528088Y884698I1298J0D01*
G01X528178Y884715D01*
X528984Y886112D01*
X528954Y886198D01*
G37*
G36*
G01X525284Y880732D02*
X524477Y882131D01*
X524387Y882148D01*
G02X523332Y883423I243J1275D01*
G02X525926I1297J0D01*
G01Y883421D01*
G02X525854Y882994I-1298J-1D01*
G01X525824Y882908D01*
X526630Y881511D01*
X526720Y881494D01*
G02X527776Y880219I-242J-1275D01*
G02X525182I-1297J0D01*
G02X525254Y880646I1297J1D01*
G01X525284Y880732D01*
G37*
G36*
G01X511528Y855876D02*
X512335Y857274D01*
X512304Y857361D01*
G02X512232Y857789I1225J426D01*
G02X514826I1297J0D01*
G02X513771Y856514I-1298J0D01*
G01X513681Y856497D01*
X512873Y855098D01*
X512903Y855011D01*
G02X512976Y854584I-1225J-429D01*
G02X510380I-1298J0D01*
G02X511438Y855859I1297J0D01*
G01X511528Y855876D01*
G37*
G36*
G01X518928D02*
X519735Y857274D01*
X519704Y857361D01*
G02X519632Y857789I1225J426D01*
G02X522226I1297J0D01*
G02X521171Y856514I-1298J0D01*
G01X521081Y856497D01*
X520273Y855098D01*
X520303Y855011D01*
G02X520376Y854584I-1225J-429D01*
G02X517780I-1298J0D01*
G02X518838Y855859I1297J0D01*
G01X518928Y855876D01*
G37*
G36*
G01X526328D02*
X527135Y857274D01*
X527104Y857361D01*
G02X527032Y857789I1225J426D01*
G02X529626I1297J0D01*
G02X528571Y856514I-1298J0D01*
G01X528481Y856497D01*
X527673Y855098D01*
X527703Y855011D01*
G02X527776Y854584I-1225J-429D01*
G02X525180I-1298J0D01*
G02X526238Y855859I1297J0D01*
G01X526328Y855876D01*
G37*
G36*
G01X508634Y858302D02*
X507826Y859701D01*
X507736Y859718D01*
G02X506680Y860993I242J1275D01*
G02X509276I1298J0D01*
G02X509203Y860564I-1297J0D01*
G01X509172Y860478D01*
X509978Y859081D01*
X510068Y859064D01*
G02X511126Y857789I-239J-1275D01*
G02X508532I-1297J0D01*
G02X508603Y858215I1297J3D01*
G01X508634Y858302D01*
G37*
G36*
G01X516034D02*
X515226Y859701D01*
X515136Y859718D01*
G02X514080Y860993I242J1275D01*
G02X516676I1298J0D01*
G02X516603Y860564I-1297J0D01*
G01X516572Y860478D01*
X517378Y859081D01*
X517468Y859064D01*
G02X518526Y857789I-239J-1275D01*
G02X515932I-1297J0D01*
G02X516003Y858215I1297J3D01*
G01X516034Y858302D01*
G37*
G36*
G01X523434D02*
X522626Y859701D01*
X522536Y859718D01*
G02X521480Y860993I242J1275D01*
G02X524076I1298J0D01*
G02X524003Y860564I-1297J0D01*
G01X523972Y860478D01*
X524778Y859081D01*
X524868Y859064D01*
G02X525926Y857789I-239J-1275D01*
G02X523332I-1297J0D01*
G02X523403Y858215I1297J3D01*
G01X523434Y858302D01*
G37*
G36*
G01X511528Y868693D02*
X512335Y870091D01*
X512304Y870178D01*
G02X512232Y870606I1225J426D01*
G02X514826I1297J0D01*
G02X513771Y869331I-1298J0D01*
G01X513681Y869314D01*
X512873Y867915D01*
X512903Y867828D01*
G02X512976Y867401I-1225J-429D01*
G02X510380I-1298J0D01*
G02X511438Y868676I1297J0D01*
G01X511528Y868693D01*
G37*
G36*
G01X518928D02*
X519735Y870091D01*
X519704Y870178D01*
G02X519632Y870606I1225J426D01*
G02X522226I1297J0D01*
G02X521171Y869331I-1298J0D01*
G01X521081Y869314D01*
X520273Y867915D01*
X520303Y867828D01*
G02X520376Y867401I-1225J-429D01*
G02X517780I-1298J0D01*
G02X518838Y868676I1297J0D01*
G01X518928Y868693D01*
G37*
G36*
G01X526328D02*
X527135Y870091D01*
X527104Y870178D01*
G02X527032Y870606I1225J426D01*
G02X529626I1297J0D01*
G02X528571Y869331I-1298J0D01*
G01X528481Y869314D01*
X527674Y867916D01*
X527704Y867829D01*
G02X527776Y867401I-1225J-426D01*
G02X525182I-1297J0D01*
G02X526238Y868676I1298J0D01*
G01X526328Y868693D01*
G37*
G36*
G01X508634Y871119D02*
X507826Y872518D01*
X507736Y872535D01*
G02X506680Y873810I242J1275D01*
G02X509276I1298J0D01*
G02X509203Y873381I-1297J0D01*
G01X509172Y873295D01*
X509978Y871898D01*
X510068Y871881D01*
G02X511126Y870606I-239J-1275D01*
G02X508532I-1297J0D01*
G02X508603Y871032I1297J3D01*
G01X508634Y871119D01*
G37*
G36*
G01X516034D02*
X515226Y872518D01*
X515136Y872535D01*
G02X514080Y873810I242J1275D01*
G02X516676I1298J0D01*
G02X516603Y873381I-1297J0D01*
G01X516572Y873295D01*
X517378Y871898D01*
X517468Y871881D01*
G02X518526Y870606I-239J-1275D01*
G02X515932I-1297J0D01*
G02X516003Y871032I1297J3D01*
G01X516034Y871119D01*
G37*
G36*
G01X510483Y880734D02*
X509677Y882131D01*
X509587Y882148D01*
G02X508532Y883423I243J1275D01*
G02X511126I1297J0D01*
G02X511054Y882994I-1297J-3D01*
G01X511023Y882908D01*
X511829Y881511D01*
X511919Y881494D01*
G02X512976Y880219I-240J-1275D01*
G02X510380I-1298J0D01*
G02X510453Y880647I1298J-1D01*
G01X510483Y880734D01*
G37*
G36*
G01X505977Y884715D02*
X506784Y886112D01*
X506753Y886199D01*
G02X506680Y886627I1225J429D01*
G02X509276I1298J0D01*
G02X508220Y885352I-1298J0D01*
G01X508130Y885335D01*
X507323Y883938D01*
X507354Y883851D01*
G02X507426Y883423I-1225J-426D01*
G02X504832I-1297J0D01*
G02X505887Y884698I1298J0D01*
G01X505977Y884715D01*
G37*
G36*
G01X513377D02*
X514184Y886112D01*
X514153Y886199D01*
G02X514080Y886627I1225J429D01*
G02X516676I1298J0D01*
G02X515620Y885352I-1298J0D01*
G01X515530Y885335D01*
X514723Y883938D01*
X514754Y883851D01*
G02X514826Y883423I-1225J-426D01*
G02X512232I-1297J0D01*
G02X513287Y884698I1298J0D01*
G01X513377Y884715D01*
G37*
G36*
G01X520777D02*
X521584Y886112D01*
X521553Y886199D01*
G02X521480Y886627I1225J429D01*
G02X524076I1298J0D01*
G02X523020Y885352I-1298J0D01*
G01X522930Y885335D01*
X522123Y883938D01*
X522154Y883851D01*
G02X522226Y883423I-1225J-426D01*
G02X519632I-1297J0D01*
G02X520687Y884698I1298J0D01*
G01X520777Y884715D01*
G37*
G36*
G01X476810Y1122739D02*
X477617Y1124136D01*
X477586Y1124223D01*
G02X477514Y1124651I1225J426D01*
G02X480108I1297J0D01*
G02X479053Y1123376I-1298J0D01*
G01X478963Y1123359D01*
X478156Y1121962D01*
X478187Y1121875D01*
G02X478260Y1121447I-1225J-429D01*
G02X475664I-1298J0D01*
G02X476720Y1122722I1298J0D01*
G01X476810Y1122739D01*
G37*
G36*
G01X484210D02*
X485017Y1124136D01*
X484986Y1124223D01*
G02X484914Y1124651I1225J426D01*
G02X487508I1297J0D01*
G02X486453Y1123376I-1298J0D01*
G01X486363Y1123359D01*
X485556Y1121962D01*
X485587Y1121875D01*
G02X485660Y1121447I-1225J-429D01*
G02X483064I-1298J0D01*
G02X484120Y1122722I1298J0D01*
G01X484210Y1122739D01*
G37*
G36*
G01X491610D02*
X492417Y1124136D01*
X492386Y1124223D01*
G02X492314Y1124651I1225J426D01*
G02X494908I1297J0D01*
G02X493853Y1123376I-1298J0D01*
G01X493763Y1123359D01*
X492956Y1121962D01*
X492987Y1121875D01*
G02X493060Y1121447I-1225J-429D01*
G02X490464I-1298J0D01*
G02X491520Y1122722I1298J0D01*
G01X491610Y1122739D01*
G37*
G36*
G01X499010D02*
X499817Y1124136D01*
X499786Y1124223D01*
G02X499714Y1124651I1225J426D01*
G02X502308I1297J0D01*
G02X501253Y1123376I-1298J0D01*
G01X501163Y1123359D01*
X500356Y1121962D01*
X500387Y1121875D01*
G02X500460Y1121447I-1225J-429D01*
G02X497864I-1298J0D01*
G02X498920Y1122722I1298J0D01*
G01X499010Y1122739D01*
G37*
G36*
G01X506410D02*
X507217Y1124136D01*
X507186Y1124223D01*
G02X507114Y1124651I1225J426D01*
G02X509708I1297J0D01*
G02X508653Y1123376I-1298J0D01*
G01X508563Y1123359D01*
X507756Y1121962D01*
X507787Y1121875D01*
G02X507860Y1121447I-1225J-429D01*
G02X505264I-1298J0D01*
G02X506320Y1122722I1298J0D01*
G01X506410Y1122739D01*
G37*
G36*
G01X513810D02*
X514617Y1124136D01*
X514586Y1124223D01*
G02X514514Y1124651I1225J426D01*
G02X517108I1297J0D01*
G02X516053Y1123376I-1298J0D01*
G01X515963Y1123359D01*
X515156Y1121962D01*
X515187Y1121875D01*
G02X515260Y1121447I-1225J-429D01*
G02X512664I-1298J0D01*
G02X513720Y1122722I1298J0D01*
G01X513810Y1122739D01*
G37*
G36*
G01X521210D02*
X522017Y1124136D01*
X521986Y1124223D01*
G02X521914Y1124651I1225J426D01*
G02X524508I1297J0D01*
G02X523453Y1123376I-1298J0D01*
G01X523363Y1123359D01*
X522556Y1121962D01*
X522587Y1121875D01*
G02X522660Y1121447I-1225J-429D01*
G02X520064I-1298J0D01*
G02X521120Y1122722I1298J0D01*
G01X521210Y1122739D01*
G37*
G36*
G01X481317Y1125166D02*
X480510Y1126564D01*
X480420Y1126581D01*
G02X479364Y1127856I242J1275D01*
G02X481960I1298J0D01*
G02X481887Y1127427I-1297J0D01*
G01X481856Y1127341D01*
X482663Y1125943D01*
X482753Y1125926D01*
G02X483808Y1124651I-243J-1275D01*
G02X481214I-1297J0D01*
G02X481286Y1125080I1297J3D01*
G01X481317Y1125166D01*
G37*
G36*
G01X488717D02*
X487910Y1126564D01*
X487820Y1126581D01*
G02X486764Y1127856I242J1275D01*
G02X489360I1298J0D01*
G02X489287Y1127427I-1297J0D01*
G01X489256Y1127341D01*
X490063Y1125943D01*
X490153Y1125926D01*
G02X491208Y1124651I-243J-1275D01*
G02X488614I-1297J0D01*
G02X488686Y1125080I1297J3D01*
G01X488717Y1125166D01*
G37*
G36*
G01X496117D02*
X495310Y1126564D01*
X495220Y1126581D01*
G02X494164Y1127856I242J1275D01*
G02X496760I1298J0D01*
G02X496687Y1127427I-1297J0D01*
G01X496656Y1127341D01*
X497463Y1125943D01*
X497553Y1125926D01*
G02X498608Y1124651I-243J-1275D01*
G02X496014I-1297J0D01*
G02X496086Y1125080I1297J3D01*
G01X496117Y1125166D01*
G37*
G36*
G01X503517D02*
X502710Y1126564D01*
X502620Y1126581D01*
G02X501564Y1127856I242J1275D01*
G02X504160I1298J0D01*
G02X504087Y1127427I-1297J0D01*
G01X504056Y1127341D01*
X504863Y1125943D01*
X504953Y1125926D01*
G02X506008Y1124651I-243J-1275D01*
G02X503414I-1297J0D01*
G02X503486Y1125080I1297J3D01*
G01X503517Y1125166D01*
G37*
G36*
G01X510917D02*
X510110Y1126564D01*
X510020Y1126581D01*
G02X508964Y1127856I242J1275D01*
G02X511560I1298J0D01*
G02X511487Y1127427I-1297J0D01*
G01X511456Y1127341D01*
X512263Y1125943D01*
X512353Y1125926D01*
G02X513408Y1124651I-243J-1275D01*
G02X510814I-1297J0D01*
G02X510886Y1125080I1297J3D01*
G01X510917Y1125166D01*
G37*
G36*
G01X518317D02*
X517510Y1126564D01*
X517420Y1126581D01*
G02X516364Y1127856I242J1275D01*
G02X518960I1298J0D01*
G02X518887Y1127427I-1297J0D01*
G01X518856Y1127341D01*
X519663Y1125943D01*
X519753Y1125926D01*
G02X520808Y1124651I-243J-1275D01*
G02X518214I-1297J0D01*
G02X518286Y1125080I1297J3D01*
G01X518317Y1125166D01*
G37*
G36*
G01X525717D02*
X524910Y1126564D01*
X524820Y1126581D01*
G02X523764Y1127856I242J1275D01*
G02X526360I1298J0D01*
G02X526287Y1127427I-1297J0D01*
G01X526256Y1127341D01*
X527063Y1125943D01*
X527153Y1125926D01*
G02X528208Y1124651I-243J-1275D01*
G02X525614I-1297J0D01*
G02X525686Y1125080I1297J3D01*
G01X525717Y1125166D01*
G37*
G36*
G01X1422586Y1378172D02*
X1430753Y1386339D01*
G02X1431460Y1386632I707J-706D01*
G01X1448630D01*
G02X1449337Y1386339I0J-999D01*
G01X1455996Y1379680D01*
X1526164D01*
G02X1526871Y1379387I0J-999D01*
G01X1540629Y1365629D01*
G02X1540922Y1364922I-706J-707D01*
G01Y1350313D01*
G02X1540629Y1349606I-999J0D01*
G01X1539436Y1348413D01*
G02X1538729Y1348120I-707J706D01*
G01X1528555D01*
X1528500Y1348008D01*
G02X1525864I-1318J642D01*
G01X1525809Y1348120D01*
X1520113D01*
X1520059Y1348007D01*
G02X1518738Y1347179I-1321J640D01*
G02X1517717Y1347593I0J1466D01*
G03X1517159I-279J-287D01*
G02X1516138Y1347179I-1021J1052D01*
G02X1514817Y1348007I0J1468D01*
G01X1514763Y1348120D01*
X1513566D01*
X1511891Y1346445D01*
G02X1512205Y1345539I-1153J-907D01*
G02X1511438Y1344250I-1467J0D01*
G01Y1343721D01*
G02Y1341143I-700J-1289D01*
G01Y1322503D01*
G02X1511145Y1321796I-999J0D01*
G01X1505768Y1316419D01*
G02X1505061Y1316126I-707J706D01*
G01X1479860D01*
X1478168Y1314434D01*
Y1305701D01*
G02X1477875Y1304994I-999J0D01*
G01X1476040Y1303159D01*
G02X1475333Y1302866I-707J706D01*
G01X1469667D01*
G02X1468296Y1301978I-1371J614D01*
G02X1467269Y1302384I0J1502D01*
G03X1466723I-273J-292D01*
G02X1465696Y1301978I-1027J1096D01*
G02X1464325Y1302866I0J1502D01*
G01X1437891D01*
X1437849Y1302845D01*
G02X1437182Y1302689I-667J1346D01*
G02X1436515Y1302845I0J1502D01*
G01X1436473Y1302866D01*
X1435291D01*
X1435249Y1302845D01*
G02X1434582Y1302689I-667J1346D01*
G02X1433915Y1302845I0J1502D01*
G01X1433873Y1302866D01*
X1409774D01*
X1409723Y1302743D01*
G02X1406949I-1387J576D01*
G01X1406898Y1302866D01*
X1405411D01*
G02X1404040Y1301978I-1371J614D01*
G02X1403013Y1302384I0J1502D01*
G03X1402467I-273J-292D01*
G02X1401440Y1301978I-1027J1096D01*
G02X1400069Y1302866I0J1502D01*
G01X1377646D01*
X1377595Y1302743D01*
G02X1374821I-1387J576D01*
G01X1374770Y1302866D01*
X1373283D01*
G02X1371912Y1301978I-1371J614D01*
G02X1370885Y1302384I0J1502D01*
G03X1370339I-273J-292D01*
G02X1369312Y1301978I-1027J1096D01*
G02X1367941Y1302866I0J1502D01*
G01X1343257D01*
G02X1342550Y1303159I0J999D01*
G01X1340520Y1305189D01*
X1340394Y1305134D01*
G02X1339784Y1305004I-611J1372D01*
G02X1338282Y1306506I0J1502D01*
G02X1338412Y1307116I1502J-1D01*
G01X1338467Y1307242D01*
X1337920Y1307789D01*
X1337794Y1307734D01*
G02X1337184Y1307604I-611J1372D01*
G02X1335682Y1309106I0J1502D01*
G02X1335812Y1309716I1502J-1D01*
G01X1335867Y1309842D01*
X1335526Y1310183D01*
G02X1335233Y1310890I706J707D01*
G01Y1315405D01*
X1334454Y1316184D01*
X1313744D01*
G02X1313037Y1316477I0J999D01*
G01X1304186Y1325328D01*
G02X1303959Y1325678I707J707D01*
G02X1303554Y1326704I1097J1026D01*
G02X1303893Y1327654I1501J0D01*
G01Y1328354D01*
G02Y1330254I1162J950D01*
G01Y1330954D01*
G02Y1332854I1162J950D01*
G01Y1333554D01*
G02Y1335454I1162J950D01*
G01Y1336154D01*
G02X1303554Y1337104I1162J950D01*
G02X1303814Y1337948I1502J-1D01*
G01X1302985Y1338777D01*
X1281004D01*
G02X1280135Y1338500I-869J1225D01*
G02X1278648Y1339791I0J1502D01*
G01X1278638Y1339858D01*
X1275694Y1342802D01*
G02X1275401Y1343509I706J707D01*
G01Y1356660D01*
X1275278Y1356712D01*
G02Y1359484I577J1386D01*
G01X1275401Y1359536D01*
Y1362701D01*
X1275400Y1362713D01*
G02X1275389Y1362891I1491J181D01*
G02X1275400Y1363069I1502J-3D01*
G01X1275401Y1363081D01*
Y1368454D01*
G02X1275694Y1369161I999J0D01*
G01X1282266Y1375733D01*
G02X1282973Y1376026I707J-706D01*
G01X1313652D01*
X1322882Y1385256D01*
G02X1323589Y1385549I707J-706D01*
G01X1353496D01*
G02X1354203Y1385256I0J-999D01*
G01X1361287Y1378172D01*
X1422586D01*
G37*
G36*
G01X1338625Y880733D02*
X1337819Y882131D01*
X1337729Y882148D01*
G02X1336674Y883423I243J1275D01*
G02X1339268I1297J0D01*
G01Y883421D01*
G02X1339196Y882994I-1298J-1D01*
G01X1339166Y882908D01*
X1339972Y881511D01*
X1340062Y881494D01*
G02X1341118Y880219I-242J-1275D01*
G02X1338522I-1298J0D01*
G02X1338595Y880647I1299J-1D01*
G01X1338625Y880733D01*
G37*
G36*
G01X1313541Y1122224D02*
X1315165D01*
G02X1316203Y1122744I1038J-776D01*
G02Y1120150I0J-1297D01*
G02X1315165Y1120670I0J1296D01*
G01X1313541D01*
G02X1312503Y1120150I-1038J776D01*
G02Y1122744I0J1297D01*
G02X1313541Y1122224I0J-1296D01*
G37*
G36*
G01X1331225Y880733D02*
X1330419Y882131D01*
X1330329Y882148D01*
G02X1329274Y883423I243J1275D01*
G02X1331868I1297J0D01*
G01Y883421D01*
G02X1331796Y882994I-1298J-1D01*
G01X1331766Y882908D01*
X1332572Y881511D01*
X1332662Y881494D01*
G02X1333718Y880219I-242J-1275D01*
G02X1331122I-1298J0D01*
G02X1331195Y880647I1299J-1D01*
G01X1331225Y880733D01*
G37*
G36*
G01X1342295Y886198D02*
G02X1342222Y886625I1225J429D01*
G01Y886627D01*
G02X1344818I1298J0D01*
G02X1343762Y885352I-1298J0D01*
G01X1343672Y885335D01*
X1342866Y883938D01*
X1342896Y883852D01*
G02X1342968Y883425I-1226J-426D01*
G01Y883423D01*
G02X1340374I-1297J0D01*
G02X1341429Y884698I1298J0D01*
G01X1341519Y884715D01*
X1342325Y886112D01*
X1342295Y886198D01*
G37*
G36*
G01X1322408Y1121961D02*
X1321601Y1123359D01*
X1321511Y1123376D01*
G02X1320456Y1124651I243J1275D01*
G02X1323050I1297J0D01*
G02X1322978Y1124223I-1298J-2D01*
G01X1322948Y1124137D01*
X1323755Y1122739D01*
X1323845Y1122722D01*
G02X1324900Y1121447I-243J-1275D01*
G02X1322306I-1297J0D01*
G02X1322378Y1121875I1298J2D01*
G01X1322408Y1121961D01*
G37*
G36*
G01X1334895Y886198D02*
G02X1334822Y886625I1225J429D01*
G01Y886627D01*
G02X1337418I1298J0D01*
G02X1336362Y885352I-1298J0D01*
G01X1336272Y885335D01*
X1335466Y883938D01*
X1335496Y883852D01*
G02X1335568Y883425I-1226J-426D01*
G01Y883423D01*
G02X1332974I-1297J0D01*
G02X1334029Y884698I1298J0D01*
G01X1334119Y884715D01*
X1334925Y886112D01*
X1334895Y886198D01*
G37*
G36*
G01X1327959Y1105941D02*
X1327152Y1107338D01*
X1327062Y1107355D01*
G02X1326006Y1108630I242J1275D01*
G02X1328602I1298J0D01*
G01Y1108628D01*
G02X1328529Y1108201I-1298J2D01*
G01X1328499Y1108115D01*
X1329306Y1106718D01*
X1329396Y1106701D01*
G02X1330450Y1105426I-244J-1275D01*
G02X1329153Y1104128I-1297J-1D01*
G02X1327856Y1105426I1J1298D01*
G02X1327929Y1105855I1297J0D01*
G01X1327959Y1105941D01*
G37*
G36*
G01X1319091Y1106204D02*
X1320715D01*
G02X1321753Y1106724I1038J-776D01*
G02Y1104128I0J-1298D01*
G02X1320715Y1104648I0J1296D01*
G01X1319091D01*
G02X1318053Y1104128I-1038J776D01*
G02Y1106724I0J1298D01*
G02X1319091Y1106204I0J-1296D01*
G37*
G36*
G01X1340101Y1106718D02*
X1340908Y1108116D01*
X1340878Y1108202D01*
G02X1340806Y1108630I1226J426D01*
G02X1343400I1297J0D01*
G02X1342345Y1107355I-1298J0D01*
G01X1342255Y1107338D01*
X1341448Y1105941D01*
X1341478Y1105855D01*
G02X1341551Y1105426I-1224J-429D01*
G02X1340254Y1104128I-1297J-1D01*
G02X1338956Y1105426I0J1298D01*
G02X1340011Y1106701I1298J0D01*
G01X1340101Y1106718D01*
G37*
G36*
G01X1320941Y1128634D02*
X1322565D01*
G02X1323603Y1129154I1038J-776D01*
G02Y1126558I0J-1298D01*
G02X1322565Y1127078I0J1296D01*
G01X1320941D01*
G02X1319903Y1126558I-1038J776D01*
G02Y1129154I0J1298D01*
G02X1320941Y1128634I0J-1296D01*
G37*
G36*
G01X1326492Y1112612D02*
X1328116D01*
G02X1329154Y1113132I1038J-776D01*
G02Y1110536I0J-1298D01*
G02X1328116Y1111056I0J1296D01*
G01X1326492D01*
G02X1325454Y1110536I-1038J776D01*
G02Y1113132I0J1298D01*
G02X1326492Y1112612I0J-1296D01*
G37*
G36*
G01X1318709Y1109144D02*
X1317902Y1110542D01*
X1317812Y1110559D01*
G02X1316756Y1111834I242J1275D01*
G02X1319352I1298J0D01*
G02X1319279Y1111406I-1299J1D01*
G01X1319249Y1111320D01*
X1320056Y1109922D01*
X1320146Y1109905D01*
G02X1321202Y1108630I-242J-1275D01*
G02X1318606I-1298J0D01*
G02X1318679Y1109058I1299J-1D01*
G01X1318709Y1109144D01*
G37*
G36*
G01X1335359Y1112348D02*
X1334551Y1113747D01*
X1334461Y1113764D01*
G02X1333406Y1115039I243J1275D01*
G02X1336000I1297J0D01*
G01Y1115037D01*
G02X1335928Y1114610I-1298J-1D01*
G01X1335898Y1114524D01*
X1336705Y1113126D01*
X1336795Y1113109D01*
G02X1337852Y1111834I-240J-1275D01*
G02X1335256I-1298J0D01*
G02X1335329Y1112262I1299J-1D01*
G01X1335359Y1112348D01*
G37*
G36*
G01X1331226Y867916D02*
X1330419Y869314D01*
X1330329Y869331D01*
G02X1329274Y870606I243J1275D01*
G02X1331868I1297J0D01*
G02X1331796Y870177I-1297J-3D01*
G01X1331765Y870091D01*
X1332572Y868693D01*
X1332662Y868676D01*
G02X1333718Y867401I-242J-1275D01*
G02X1331122I-1298J0D01*
G02X1331195Y867830I1297J0D01*
G01X1331226Y867916D01*
G37*
G36*
G01X1338626D02*
X1337819Y869314D01*
X1337729Y869331D01*
G02X1336674Y870606I243J1275D01*
G02X1339268I1297J0D01*
G02X1339196Y870177I-1297J-3D01*
G01X1339165Y870091D01*
X1339972Y868693D01*
X1340062Y868676D01*
G02X1341118Y867401I-242J-1275D01*
G02X1338522I-1298J0D01*
G02X1338595Y867830I1297J0D01*
G01X1338626Y867916D01*
G37*
G36*
G01X1346026D02*
X1345219Y869314D01*
X1345129Y869331D01*
G02X1344074Y870606I243J1275D01*
G02X1346668I1297J0D01*
G02X1346596Y870177I-1297J-3D01*
G01X1346565Y870091D01*
X1347372Y868693D01*
X1347462Y868676D01*
G02X1348518Y867401I-242J-1275D01*
G02X1345922I-1298J0D01*
G02X1345995Y867830I1297J0D01*
G01X1346026Y867916D01*
G37*
G36*
G01X1326719Y871898D02*
X1327526Y873295D01*
X1327495Y873382D01*
G02X1327422Y873810I1225J429D01*
G02X1330018I1298J0D01*
G02X1328962Y872535I-1298J0D01*
G01X1328872Y872518D01*
X1328065Y871121D01*
X1328096Y871034D01*
G02X1328168Y870606I-1225J-426D01*
G02X1325574I-1297J0D01*
G02X1326629Y871881I1298J0D01*
G01X1326719Y871898D01*
G37*
G36*
G01X1334119D02*
X1334926Y873295D01*
X1334895Y873382D01*
G02X1334822Y873810I1225J429D01*
G02X1337418I1298J0D01*
G02X1336362Y872535I-1298J0D01*
G01X1336272Y872518D01*
X1335465Y871121D01*
X1335496Y871034D01*
G02X1335568Y870606I-1225J-426D01*
G02X1332974I-1297J0D01*
G02X1334029Y871881I1298J0D01*
G01X1334119Y871898D01*
G37*
G36*
G01X1341519D02*
X1342326Y873295D01*
X1342295Y873382D01*
G02X1342222Y873810I1225J429D01*
G02X1344818I1298J0D01*
G02X1343762Y872535I-1298J0D01*
G01X1343672Y872518D01*
X1342865Y871121D01*
X1342896Y871034D01*
G02X1342968Y870606I-1225J-426D01*
G02X1340374I-1297J0D01*
G02X1341429Y871881I1298J0D01*
G01X1341519Y871898D01*
G37*
G36*
G01X1348919D02*
X1349726Y873295D01*
X1349695Y873382D01*
G02X1349622Y873810I1225J429D01*
G02X1352218I1298J0D01*
G02X1351162Y872535I-1298J0D01*
G01X1351072Y872518D01*
X1350265Y871121D01*
X1350296Y871034D01*
G02X1350368Y870606I-1225J-426D01*
G02X1347774I-1297J0D01*
G02X1348829Y871881I1298J0D01*
G01X1348919Y871898D01*
G37*
G36*
G01X1346025Y880734D02*
X1345219Y882131D01*
X1345129Y882148D01*
G02X1344074Y883423I243J1275D01*
G02X1346668I1297J0D01*
G02X1346596Y882994I-1297J-3D01*
G01X1346565Y882908D01*
X1347371Y881511D01*
X1347461Y881494D01*
G02X1348518Y880219I-240J-1275D01*
G02X1345922I-1298J0D01*
G02X1345995Y880647I1298J-1D01*
G01X1346025Y880734D01*
G37*
G36*
G01X1353425D02*
X1352619Y882131D01*
X1352529Y882148D01*
G02X1351474Y883423I243J1275D01*
G02X1354068I1297J0D01*
G02X1353996Y882994I-1297J-3D01*
G01X1353965Y882908D01*
X1354771Y881511D01*
X1354861Y881494D01*
G02X1355918Y880219I-240J-1275D01*
G02X1353322I-1298J0D01*
G02X1353395Y880647I1298J-1D01*
G01X1353425Y880734D01*
G37*
G36*
G01X1348919Y884715D02*
X1349726Y886112D01*
X1349695Y886199D01*
G02X1349622Y886627I1225J429D01*
G02X1352218I1298J0D01*
G02X1351162Y885352I-1298J0D01*
G01X1351072Y885335D01*
X1350265Y883938D01*
X1350296Y883851D01*
G02X1350368Y883423I-1225J-426D01*
G02X1347774I-1297J0D01*
G02X1348829Y884698I1298J0D01*
G01X1348919Y884715D01*
G37*
G36*
G01X1380143Y1082218D02*
G02X1379104Y1081698I-1039J778D01*
G02Y1084292I0J1297D01*
G02X1380143Y1083772I0J-1298D01*
G01X1381765D01*
G02X1382804Y1084292I1039J-778D01*
G02Y1081698I0J-1297D01*
G02X1381765Y1082218I0J1298D01*
G01X1380143D01*
G37*
G36*
G01X1384503Y1081083D02*
X1385310Y1082480D01*
X1385279Y1082567D01*
G02X1385206Y1082995I1225J429D01*
G02X1387802I1298J0D01*
G02X1386746Y1081720I-1298J0D01*
G01X1386656Y1081703D01*
X1385848Y1080304D01*
X1385878Y1080218D01*
G02X1385950Y1079791I-1225J-426D01*
G02X1383356I-1297J0D01*
G02X1384413Y1081066I1297J0D01*
G01X1384503Y1081083D01*
G37*
G36*
G01X1389009Y1083509D02*
X1388201Y1084908D01*
X1388111Y1084925D01*
G02X1387056Y1086200I243J1275D01*
G02X1389650I1297J0D01*
G02X1389578Y1085772I-1297J-2D01*
G01X1389547Y1085685D01*
X1390354Y1084287D01*
X1390445Y1084270D01*
G02X1391502Y1082995I-240J-1275D01*
G02X1388906I-1298J0D01*
G02X1388979Y1083422I1298J-2D01*
G01X1389009Y1083509D01*
G37*
G36*
G01X1379758Y1086714D02*
X1378951Y1088112D01*
X1378861Y1088129D01*
G02X1377806Y1089404I243J1275D01*
G02X1380400I1297J0D01*
G02X1380328Y1088976I-1297J-2D01*
G01X1380297Y1088889D01*
X1381104Y1087492D01*
X1381194Y1087475D01*
G02X1382250Y1086200I-242J-1275D01*
G02X1379656I-1297J0D01*
G02X1379728Y1086628I1297J2D01*
G01X1379758Y1086714D01*
G37*
G36*
G01X1387543Y1088626D02*
G02X1386504Y1088106I-1039J778D01*
G02Y1090702I0J1298D01*
G02X1387543Y1090182I0J-1298D01*
G01X1389165D01*
G02X1390204Y1090702I1039J-778D01*
G02Y1088106I0J-1298D01*
G02X1389165Y1088626I0J1298D01*
G01X1387543D01*
G37*
G36*
G01X1382652Y1090696D02*
X1383459Y1092093D01*
X1383428Y1092180D01*
G02X1383356Y1092608I1225J426D01*
G02X1385950I1297J0D01*
G02X1384895Y1091333I-1298J0D01*
G01X1384805Y1091316D01*
X1383998Y1089919D01*
X1384029Y1089833D01*
G02X1384102Y1089404I-1224J-429D01*
G02X1381506I-1298J0D01*
G02X1382562Y1090679I1298J0D01*
G01X1382652Y1090696D01*
G37*
G36*
G01X1396409Y1089917D02*
X1395601Y1091316D01*
X1395511Y1091333D01*
G02X1394456Y1092608I243J1275D01*
G02X1397050I1297J0D01*
G02X1396978Y1092180I-1297J-2D01*
G01X1396947Y1092093D01*
X1397754Y1090696D01*
X1397844Y1090679D01*
G02X1398902Y1089404I-239J-1275D01*
G02X1396306I-1298J0D01*
G02X1396379Y1089831I1298J-2D01*
G01X1396409Y1089917D01*
G37*
G36*
G01X1381992Y1098240D02*
G02X1380953Y1097720I-1039J778D01*
G02Y1100314I0J1297D01*
G02X1381992Y1099794I0J-1298D01*
G01X1383614D01*
G02X1384653Y1100314I1039J-778D01*
G02Y1097720I0J-1297D01*
G02X1383614Y1098240I0J1298D01*
G01X1381992D01*
G37*
G36*
G01X1328342Y1101444D02*
G02X1327303Y1100924I-1039J778D01*
G02Y1103518I0J1297D01*
G02X1328342Y1102998I0J-1298D01*
G01X1329964D01*
G02X1331003Y1103518I1039J-778D01*
G02Y1100924I0J-1297D01*
G02X1329964Y1101444I0J1298D01*
G01X1328342D01*
G37*
G36*
G01X1377103Y1100309D02*
X1377910Y1101706D01*
X1377879Y1101793D01*
G02X1377806Y1102221I1225J429D01*
G02X1380402I1298J0D01*
G02X1379346Y1100946I-1298J0D01*
G01X1379256Y1100929D01*
X1378448Y1099530D01*
X1378478Y1099444D01*
G02X1378550Y1099017I-1225J-426D01*
G02X1375956I-1297J0D01*
G02X1377013Y1100292I1297J0D01*
G01X1377103Y1100309D01*
G37*
G36*
G01X1352392Y1104648D02*
G02X1351353Y1104128I-1039J778D01*
G02Y1106724I0J1298D01*
G02X1352392Y1106204I0J-1298D01*
G01X1354015D01*
G02X1355054Y1106724I1039J-778D01*
G02Y1104128I0J-1298D01*
G02X1354015Y1104648I0J1298D01*
G01X1352392D01*
G37*
G36*
G01X1356751Y1103513D02*
X1357559Y1104911D01*
X1357528Y1104998D01*
G02X1357456Y1105426I1225J426D01*
G02X1360050I1297J0D01*
G02X1358995Y1104151I-1298J0D01*
G01X1358905Y1104134D01*
X1358098Y1102737D01*
X1358128Y1102650D01*
G02X1358202Y1102221I-1223J-432D01*
G02X1355606I-1298J0D01*
G02X1356661Y1103496I1298J0D01*
G01X1356751Y1103513D01*
G37*
G36*
G01X1389009Y1102735D02*
X1388201Y1104134D01*
X1388111Y1104151D01*
G02X1387056Y1105426I243J1275D01*
G02X1389650I1297J0D01*
G02X1389578Y1104998I-1297J-2D01*
G01X1389547Y1104911D01*
X1390354Y1103513D01*
X1390445Y1103496D01*
G02X1391502Y1102221I-240J-1275D01*
G02X1388906I-1298J0D01*
G02X1388979Y1102648I1298J-2D01*
G01X1389009Y1102735D01*
G37*
G36*
G01X1335742Y1107852D02*
G02X1334703Y1107332I-1039J778D01*
G02Y1109928I0J1298D01*
G02X1335742Y1109408I0J-1298D01*
G01X1337364D01*
G02X1338403Y1109928I1039J-778D01*
G02Y1107332I0J-1298D01*
G02X1337364Y1107852I0J1298D01*
G01X1335742D01*
G37*
G36*
G01X1361259Y1105941D02*
X1360452Y1107338D01*
X1360362Y1107355D01*
G02X1359306Y1108630I242J1275D01*
G02X1361902I1298J0D01*
G02X1361829Y1108202I-1298J1D01*
G01X1361798Y1108115D01*
X1362605Y1106718D01*
X1362695Y1106701D01*
G02X1363750Y1105426I-243J-1275D01*
G02X1361156I-1297J0D01*
G02X1361228Y1105855I1297J3D01*
G01X1361259Y1105941D01*
G37*
G36*
G01X1369043Y1107852D02*
G02X1368004Y1107332I-1039J778D01*
G02Y1109928I0J1298D01*
G02X1369043Y1109408I0J-1298D01*
G01X1370665D01*
G02X1371704Y1109928I1039J-778D01*
G02Y1107332I0J-1298D01*
G02X1370665Y1107852I0J1298D01*
G01X1369043D01*
G37*
G36*
G01X1373403Y1106718D02*
X1374210Y1108115D01*
X1374179Y1108202D01*
G02X1374106Y1108630I1225J429D01*
G02X1376702I1298J0D01*
G02X1375646Y1107355I-1298J0D01*
G01X1375556Y1107338D01*
X1374748Y1105939D01*
X1374778Y1105853D01*
G02X1374850Y1105426I-1225J-426D01*
G02X1372256I-1297J0D01*
G02X1373313Y1106701I1297J0D01*
G01X1373403Y1106718D01*
G37*
G36*
G01X1384503D02*
X1385310Y1108115D01*
X1385279Y1108202D01*
G02X1385206Y1108630I1225J429D01*
G02X1387802I1298J0D01*
G02X1386746Y1107355I-1298J0D01*
G01X1386656Y1107338D01*
X1385848Y1105939D01*
X1385878Y1105853D01*
G02X1385950Y1105426I-1225J-426D01*
G02X1383356I-1297J0D01*
G02X1384413Y1106701I1297J0D01*
G01X1384503Y1106718D01*
G37*
G36*
G01X1344609Y1109145D02*
X1343802Y1110542D01*
X1343712Y1110559D01*
G02X1342656Y1111834I242J1275D01*
G02X1345252I1298J0D01*
G02X1345179Y1111406I-1298J1D01*
G01X1345148Y1111319D01*
X1345955Y1109922D01*
X1346045Y1109905D01*
G02X1347100Y1108630I-243J-1275D01*
G02X1344506I-1297J0D01*
G02X1344578Y1109059I1297J3D01*
G01X1344609Y1109145D01*
G37*
G36*
G01X1352009Y1109143D02*
X1351201Y1110542D01*
X1351111Y1110559D01*
G02X1350056Y1111834I243J1275D01*
G02X1352650I1297J0D01*
G02X1352578Y1111406I-1297J-2D01*
G01X1352547Y1111319D01*
X1353354Y1109922D01*
X1353444Y1109905D01*
G02X1354502Y1108630I-239J-1275D01*
G02X1351906I-1298J0D01*
G02X1351979Y1109057I1298J-2D01*
G01X1352009Y1109143D01*
G37*
G36*
G01X1359792Y1111056D02*
G02X1358753Y1110536I-1039J778D01*
G02Y1113132I0J1298D01*
G02X1359792Y1112612I0J-1298D01*
G01X1361414D01*
G02X1362453Y1113132I1039J-778D01*
G02Y1110536I0J-1298D01*
G02X1361414Y1111056I0J1298D01*
G01X1359792D01*
G37*
G36*
G01X1377909Y1109143D02*
X1377101Y1110542D01*
X1377011Y1110559D01*
G02X1375956Y1111834I243J1275D01*
G02X1378550I1297J0D01*
G02X1378478Y1111406I-1297J-2D01*
G01X1378447Y1111319D01*
X1379254Y1109922D01*
X1379344Y1109905D01*
G02X1380402Y1108630I-239J-1275D01*
G02X1377806I-1298J0D01*
G02X1377879Y1109057I1298J-2D01*
G01X1377909Y1109143D01*
G37*
G36*
G01X1385692Y1111056D02*
G02X1384653Y1110536I-1039J778D01*
G02Y1113132I0J1298D01*
G02X1385692Y1112612I0J-1298D01*
G01X1387314D01*
G02X1388353Y1113132I1039J-778D01*
G02Y1110536I0J-1298D01*
G02X1387314Y1111056I0J1298D01*
G01X1385692D01*
G37*
G36*
G01X1321601Y1113126D02*
X1322409Y1114524D01*
X1322378Y1114611D01*
G02X1322306Y1115039I1225J426D01*
G02X1324900I1297J0D01*
G02X1323845Y1113764I-1298J0D01*
G01X1323755Y1113747D01*
X1322947Y1112349D01*
X1322978Y1112262D01*
G02X1323050Y1111834I-1225J-426D01*
G02X1320456I-1297J0D01*
G02X1321511Y1113109I1298J0D01*
G01X1321601Y1113126D01*
G37*
G36*
G01X1343142Y1114262D02*
G02X1342103Y1113742I-1039J778D01*
G02Y1116336I0J1297D01*
G02X1343142Y1115816I0J-1298D01*
G01X1344764D01*
G02X1345803Y1116336I1039J-778D01*
G02Y1113742I0J-1297D01*
G02X1344764Y1114262I0J1298D01*
G01X1343142D01*
G37*
G36*
G01X1354903Y1113126D02*
X1355710Y1114524D01*
X1355679Y1114611D01*
G02X1355606Y1115039I1225J429D01*
G02X1358202I1298J0D01*
G02X1357146Y1113764I-1298J0D01*
G01X1357056Y1113747D01*
X1356248Y1112348D01*
X1356278Y1112261D01*
G02X1356350Y1111834I-1225J-426D01*
G02X1353756I-1297J0D01*
G02X1354812Y1113109I1298J0D01*
G01X1354903Y1113126D01*
G37*
G36*
G01X1368659Y1112350D02*
X1367852Y1113747D01*
X1367762Y1113764D01*
G02X1366706Y1115039I242J1275D01*
G02X1369302I1298J0D01*
G02X1369229Y1114611I-1298J1D01*
G01X1369198Y1114524D01*
X1370006Y1113126D01*
X1370096Y1113109D01*
G02X1371150Y1111834I-244J-1275D01*
G02X1368556I-1297J0D01*
G02X1368629Y1112263I1297J0D01*
G01X1368659Y1112350D01*
G37*
G36*
G01X1376443Y1114262D02*
G02X1375404Y1113742I-1039J778D01*
G02Y1116336I0J1297D01*
G02X1376443Y1115816I0J-1298D01*
G01X1378065D01*
G02X1379104Y1116336I1039J-778D01*
G02Y1113742I0J-1297D01*
G02X1378065Y1114262I0J1298D01*
G01X1376443D01*
G37*
G36*
G01X1317902Y1119535D02*
X1318709Y1120932D01*
X1318678Y1121019D01*
G02X1318606Y1121447I1225J426D01*
G02X1321200I1297J0D01*
G02X1320145Y1120172I-1298J0D01*
G01X1320055Y1120155D01*
X1319248Y1118758D01*
X1319279Y1118671D01*
G02X1319352Y1118243I-1225J-429D01*
G02X1316756I-1298J0D01*
G02X1317812Y1119518I1298J0D01*
G01X1317902Y1119535D01*
G37*
G36*
G01X1333509Y1121962D02*
X1332702Y1123359D01*
X1332612Y1123376D01*
G02X1331556Y1124651I242J1275D01*
G02X1334152I1298J0D01*
G02X1334079Y1124223I-1298J1D01*
G01X1334048Y1124136D01*
X1334855Y1122739D01*
X1334945Y1122722D01*
G02X1336000Y1121447I-243J-1275D01*
G02X1333406I-1297J0D01*
G02X1333478Y1121876I1297J3D01*
G01X1333509Y1121962D01*
G37*
G36*
G01X1340909Y1121960D02*
X1340101Y1123359D01*
X1340011Y1123376D01*
G02X1338956Y1124651I243J1275D01*
G02X1341550I1297J0D01*
G02X1341478Y1124223I-1297J-2D01*
G01X1341447Y1124136D01*
X1342254Y1122739D01*
X1342344Y1122722D01*
G02X1343402Y1121447I-239J-1275D01*
G02X1340806I-1298J0D01*
G02X1340879Y1121874I1298J-2D01*
G01X1340909Y1121960D01*
G37*
G36*
G01X1348309D02*
X1347501Y1123359D01*
X1347411Y1123376D01*
G02X1346356Y1124651I243J1275D01*
G02X1348950I1297J0D01*
G02X1348878Y1124223I-1297J-2D01*
G01X1348847Y1124136D01*
X1349654Y1122739D01*
X1349744Y1122722D01*
G02X1350802Y1121447I-239J-1275D01*
G02X1348206I-1298J0D01*
G02X1348279Y1121874I1298J-2D01*
G01X1348309Y1121960D01*
G37*
G36*
G01X1355709D02*
X1354901Y1123359D01*
X1354811Y1123376D01*
G02X1353756Y1124651I243J1275D01*
G02X1356350I1297J0D01*
G02X1356278Y1124223I-1297J-2D01*
G01X1356247Y1124136D01*
X1357054Y1122739D01*
X1357144Y1122722D01*
G02X1358202Y1121447I-239J-1275D01*
G02X1355606I-1298J0D01*
G02X1355679Y1121874I1298J-2D01*
G01X1355709Y1121960D01*
G37*
G36*
G01X1363109D02*
X1362301Y1123359D01*
X1362211Y1123376D01*
G02X1361156Y1124651I243J1275D01*
G02X1363750I1297J0D01*
G02X1363678Y1124223I-1297J-2D01*
G01X1363647Y1124136D01*
X1364454Y1122739D01*
X1364544Y1122722D01*
G02X1365602Y1121447I-239J-1275D01*
G02X1363006I-1298J0D01*
G02X1363079Y1121874I1298J-2D01*
G01X1363109Y1121960D01*
G37*
G36*
G01X1370509D02*
X1369701Y1123359D01*
X1369611Y1123376D01*
G02X1368556Y1124651I243J1275D01*
G02X1371150I1297J0D01*
G02X1371078Y1124223I-1297J-2D01*
G01X1371047Y1124136D01*
X1371854Y1122739D01*
X1371944Y1122722D01*
G02X1373002Y1121447I-239J-1275D01*
G02X1370406I-1298J0D01*
G02X1370479Y1121874I1298J-2D01*
G01X1370509Y1121960D01*
G37*
G36*
G01X1377909D02*
X1377101Y1123359D01*
X1377011Y1123376D01*
G02X1375956Y1124651I243J1275D01*
G02X1378550I1297J0D01*
G02X1378478Y1124223I-1297J-2D01*
G01X1378447Y1124136D01*
X1379254Y1122739D01*
X1379344Y1122722D01*
G02X1380402Y1121447I-239J-1275D01*
G02X1377806I-1298J0D01*
G02X1377879Y1121874I1298J-2D01*
G01X1377909Y1121960D01*
G37*
G36*
G01X1329001Y1125943D02*
X1329809Y1127341D01*
X1329778Y1127428D01*
G02X1329706Y1127856I1225J426D01*
G02X1332300I1297J0D01*
G02X1331245Y1126581I-1298J0D01*
G01X1331155Y1126564D01*
X1330347Y1125166D01*
X1330378Y1125079D01*
G02X1330450Y1124651I-1225J-426D01*
G02X1327856I-1297J0D01*
G02X1328911Y1125926I1298J0D01*
G01X1329001Y1125943D01*
G37*
G36*
G01X1336402D02*
X1337210Y1127341D01*
X1337179Y1127428D01*
G02X1337106Y1127856I1225J429D01*
G02X1339702I1298J0D01*
G02X1338646Y1126581I-1298J0D01*
G01X1338556Y1126564D01*
X1337748Y1125166D01*
X1337779Y1125079D01*
G02X1337852Y1124651I-1225J-429D01*
G02X1335256I-1298J0D01*
G02X1336312Y1125926I1298J0D01*
G01X1336402Y1125943D01*
G37*
G36*
G01X1343803D02*
X1344610Y1127341D01*
X1344579Y1127428D01*
G02X1344506Y1127856I1225J429D01*
G02X1347102I1298J0D01*
G02X1346046Y1126581I-1298J0D01*
G01X1345956Y1126564D01*
X1345148Y1125165D01*
X1345178Y1125078D01*
G02X1345250Y1124651I-1225J-426D01*
G02X1342656I-1297J0D01*
G02X1343712Y1125926I1298J0D01*
G01X1343803Y1125943D01*
G37*
G36*
G01X1351203D02*
X1352010Y1127341D01*
X1351979Y1127428D01*
G02X1351906Y1127856I1225J429D01*
G02X1354502I1298J0D01*
G02X1353446Y1126581I-1298J0D01*
G01X1353356Y1126564D01*
X1352548Y1125165D01*
X1352578Y1125078D01*
G02X1352650Y1124651I-1225J-426D01*
G02X1350056I-1297J0D01*
G02X1351112Y1125926I1298J0D01*
G01X1351203Y1125943D01*
G37*
G36*
G01X1358603D02*
X1359410Y1127341D01*
X1359379Y1127428D01*
G02X1359306Y1127856I1225J429D01*
G02X1361902I1298J0D01*
G02X1360846Y1126581I-1298J0D01*
G01X1360756Y1126564D01*
X1359948Y1125165D01*
X1359978Y1125078D01*
G02X1360050Y1124651I-1225J-426D01*
G02X1357456I-1297J0D01*
G02X1358512Y1125926I1298J0D01*
G01X1358603Y1125943D01*
G37*
G36*
G01X1366003D02*
X1366810Y1127341D01*
X1366779Y1127428D01*
G02X1366706Y1127856I1225J429D01*
G02X1369302I1298J0D01*
G02X1368246Y1126581I-1298J0D01*
G01X1368156Y1126564D01*
X1367348Y1125165D01*
X1367378Y1125078D01*
G02X1367450Y1124651I-1225J-426D01*
G02X1364856I-1297J0D01*
G02X1365912Y1125926I1298J0D01*
G01X1366003Y1125943D01*
G37*
G36*
G01X1373403D02*
X1374210Y1127341D01*
X1374179Y1127428D01*
G02X1374106Y1127856I1225J429D01*
G02X1376702I1298J0D01*
G02X1375646Y1126581I-1298J0D01*
G01X1375556Y1126564D01*
X1374748Y1125165D01*
X1374778Y1125078D01*
G02X1374850Y1124651I-1225J-426D01*
G02X1372256I-1297J0D01*
G02X1373312Y1125926I1298J0D01*
G01X1373403Y1125943D01*
G37*
G36*
G01X1380803D02*
X1381610Y1127341D01*
X1381579Y1127428D01*
G02X1381506Y1127856I1225J429D01*
G02X1384102I1298J0D01*
G02X1383046Y1126581I-1298J0D01*
G01X1382956Y1126564D01*
X1382148Y1125165D01*
X1382178Y1125078D01*
G02X1382250Y1124651I-1225J-426D01*
G02X1379656I-1297J0D01*
G02X1380712Y1125926I1298J0D01*
G01X1380803Y1125943D01*
G37*
G36*
G01X1316051Y1129148D02*
X1316858Y1130546D01*
X1316828Y1130632D01*
G02X1316756Y1131060I1225J426D01*
G02X1319350I1297J0D01*
G02X1318295Y1129785I-1298J0D01*
G01X1318205Y1129768D01*
X1317398Y1128370D01*
X1317428Y1128284D01*
G02X1317500Y1127856I-1225J-426D01*
G02X1314906I-1297J0D01*
G02X1315961Y1129131I1298J0D01*
G01X1316051Y1129148D01*
G37*
G36*
G01X1388976Y739200D02*
G02X1390978Y737198I0J-2002D01*
G02X1389977Y735464I-2002J0D01*
G01X1386339Y733363D01*
G02X1385340Y733096I-999J1736D01*
G01X1385338D01*
G02X1383336Y735098I0J2002D01*
G02X1384337Y736832I2002J0D01*
G01X1387975Y738933D01*
G02X1388974Y739200I999J-1736D01*
G01X1388976D01*
G37*
G36*
G01X1393206Y724738D02*
G02X1395208Y722735I-1J-2003D01*
G02X1394207Y721001I-2002J0D01*
G01X1390569Y718900D01*
G02X1389570Y718632I-1001J1735D01*
G01X1389568D01*
G02X1387566Y720635I1J2003D01*
G02X1388567Y722369I2002J0D01*
G01X1392205Y724470D01*
G02X1393204Y724738I1001J-1735D01*
G01X1393206D01*
G37*
G36*
G01Y695710D02*
G02X1395208Y693708I0J-2002D01*
G02X1394207Y691974I-2002J0D01*
G01X1390569Y689873D01*
G02X1389570Y689606I-999J1736D01*
G01X1389568D01*
G02X1387566Y691608I0J2002D01*
G02X1388567Y693342I2002J0D01*
G01X1392205Y695443D01*
G02X1393204Y695710I999J-1736D01*
G01X1393206D01*
G37*
G36*
G01Y710210D02*
G02X1395208Y708208I0J-2002D01*
G02X1394207Y706474I-2002J0D01*
G01X1390569Y704373D01*
G02X1389570Y704106I-999J1736D01*
G01X1389568D01*
G02X1387566Y706108I0J2002D01*
G02X1388567Y707842I2002J0D01*
G01X1392205Y709943D01*
G02X1393204Y710210I999J-1736D01*
G01X1393206D01*
G37*
G36*
G01Y681210D02*
G02X1395208Y679208I0J-2002D01*
G02X1394207Y677474I-2002J0D01*
G01X1390569Y675373D01*
G02X1389570Y675106I-999J1736D01*
G01X1389568D01*
G02X1387566Y677108I0J2002D01*
G02X1388567Y678842I2002J0D01*
G01X1392205Y680943D01*
G02X1393204Y681210I999J-1736D01*
G01X1393206D01*
G37*
G36*
G01Y666710D02*
G02X1395208Y664708I0J-2002D01*
G02X1394207Y662974I-2002J0D01*
G01X1390569Y660873D01*
G02X1389570Y660606I-999J1736D01*
G01X1389568D01*
G02X1387566Y662608I0J2002D01*
G02X1388567Y664342I2002J0D01*
G01X1392205Y666443D01*
G02X1393204Y666710I999J-1736D01*
G01X1393206D01*
G37*
G36*
G01X1372666Y719708D02*
G02X1374668Y721710I2002J0D01*
G01X1374670D01*
G02X1375669Y721443I0J-2003D01*
G01X1379307Y719342D01*
G02X1380308Y717608I-1001J-1734D01*
G02X1378306Y715606I-2002J0D01*
G01X1378304D01*
G02X1377305Y715873I0J2003D01*
G01X1373667Y717974D01*
G02X1372666Y719708I1001J1734D01*
G37*
G36*
G01Y695708D02*
G02X1374668Y697710I2002J0D01*
G01X1374670D01*
G02X1375669Y697443I0J-2003D01*
G01X1379307Y695342D01*
G02X1380308Y693608I-1001J-1734D01*
G02X1378306Y691606I-2002J0D01*
G01X1378304D01*
G02X1377305Y691873I0J2003D01*
G01X1373667Y693974D01*
G02X1372666Y695708I1001J1734D01*
G37*
G36*
G01Y707708D02*
G02X1374668Y709710I2002J0D01*
G01X1374670D01*
G02X1375669Y709443I0J-2003D01*
G01X1379307Y707342D01*
G02X1380308Y705608I-1001J-1734D01*
G02X1378306Y703606I-2002J0D01*
G01X1378304D01*
G02X1377305Y703873I0J2003D01*
G01X1373667Y705974D01*
G02X1372666Y707708I1001J1734D01*
G37*
G36*
G01Y683708D02*
G02X1374668Y685710I2002J0D01*
G01X1374670D01*
G02X1375669Y685443I0J-2003D01*
G01X1379307Y683342D01*
G02X1380308Y681608I-1001J-1734D01*
G02X1378306Y679606I-2002J0D01*
G01X1378304D01*
G02X1377305Y679873I0J2003D01*
G01X1373667Y681974D01*
G02X1372666Y683708I1001J1734D01*
G37*
G36*
G01Y671708D02*
G02X1374668Y673710I2002J0D01*
G01X1374670D01*
G02X1375669Y673443I0J-2003D01*
G01X1379307Y671342D01*
G02X1380308Y669608I-1001J-1734D01*
G02X1378306Y667606I-2002J0D01*
G01X1378304D01*
G02X1377305Y667873I0J2003D01*
G01X1373667Y669974D01*
G02X1372666Y671708I1001J1734D01*
G37*
G36*
G01Y659708D02*
G02X1374668Y661710I2002J0D01*
G01X1374670D01*
G02X1375669Y661443I0J-2003D01*
G01X1379307Y659342D01*
G02X1380308Y657608I-1001J-1734D01*
G02X1378306Y655606I-2002J0D01*
G01X1378304D01*
G02X1377305Y655873I0J2003D01*
G01X1373667Y657974D01*
G02X1372666Y659708I1001J1734D01*
G37*
G36*
G01X1332281Y842761D02*
X1333122Y844356D01*
X1333083Y844444D01*
G02X1332972Y844971I1186J525D01*
G02X1335566I1297J0D01*
G02X1334504Y843695I-1298J0D01*
G01X1334409Y843677D01*
X1333568Y842082D01*
X1333607Y841994D01*
G02X1333718Y841467I-1186J-525D01*
G02X1331124I-1297J0D01*
G02X1332186Y842743I1298J0D01*
G01X1332281Y842761D01*
G37*
G36*
G01X1339681D02*
X1340522Y844356D01*
X1340483Y844444D01*
G02X1340372Y844971I1186J525D01*
G02X1342966I1297J0D01*
G02X1341904Y843695I-1298J0D01*
G01X1341809Y843677D01*
X1340968Y842082D01*
X1341007Y841994D01*
G02X1341118Y841467I-1186J-525D01*
G02X1338524I-1297J0D01*
G02X1339586Y842743I1298J0D01*
G01X1339681Y842761D01*
G37*
G36*
G01X1347081D02*
X1347922Y844356D01*
X1347883Y844444D01*
G02X1347772Y844971I1186J525D01*
G02X1350366I1297J0D01*
G02X1349304Y843695I-1298J0D01*
G01X1349209Y843677D01*
X1348368Y842082D01*
X1348407Y841994D01*
G02X1348518Y841467I-1186J-525D01*
G02X1345924I-1297J0D01*
G02X1346986Y842743I1298J0D01*
G01X1347081Y842761D01*
G37*
G36*
G01X1354481D02*
X1355322Y844356D01*
X1355283Y844444D01*
G02X1355172Y844971I1186J525D01*
G02X1357766I1297J0D01*
G02X1356704Y843695I-1298J0D01*
G01X1356609Y843677D01*
X1355768Y842082D01*
X1355807Y841994D01*
G02X1355918Y841467I-1186J-525D01*
G02X1353324I-1297J0D01*
G02X1354386Y842743I1298J0D01*
G01X1354481Y842761D01*
G37*
G36*
G01X1361881D02*
X1362722Y844356D01*
X1362683Y844444D01*
G02X1362572Y844971I1186J525D01*
G02X1365166I1297J0D01*
G02X1364104Y843695I-1298J0D01*
G01X1364009Y843677D01*
X1363168Y842082D01*
X1363207Y841994D01*
G02X1363318Y841467I-1186J-525D01*
G02X1360724I-1297J0D01*
G02X1361786Y842743I1298J0D01*
G01X1361881Y842761D01*
G37*
G36*
G01X1369281D02*
X1370122Y844356D01*
X1370083Y844444D01*
G02X1369972Y844971I1186J525D01*
G02X1372566I1297J0D01*
G02X1371504Y843695I-1298J0D01*
G01X1371409Y843677D01*
X1370568Y842082D01*
X1370607Y841994D01*
G02X1370718Y841467I-1186J-525D01*
G02X1368124I-1297J0D01*
G02X1369186Y842743I1298J0D01*
G01X1369281Y842761D01*
G37*
G36*
G01X1329375Y845486D02*
X1328568Y846884D01*
X1328478Y846901D01*
G02X1327422Y848176I242J1275D01*
G02X1330018I1298J0D01*
G02X1329945Y847747I-1297J0D01*
G01X1329914Y847661D01*
X1330721Y846263D01*
X1330811Y846246D01*
G02X1331866Y844971I-243J-1275D01*
G02X1329272I-1297J0D01*
G02X1329344Y845400I1297J3D01*
G01X1329375Y845486D01*
G37*
G36*
G01X1336775D02*
X1335968Y846884D01*
X1335878Y846901D01*
G02X1334822Y848176I242J1275D01*
G02X1337418I1298J0D01*
G02X1337345Y847747I-1297J0D01*
G01X1337314Y847661D01*
X1338121Y846263D01*
X1338211Y846246D01*
G02X1339266Y844971I-243J-1275D01*
G02X1336672I-1297J0D01*
G02X1336744Y845400I1297J3D01*
G01X1336775Y845486D01*
G37*
G36*
G01X1344175D02*
X1343368Y846884D01*
X1343278Y846901D01*
G02X1342222Y848176I242J1275D01*
G02X1344818I1298J0D01*
G02X1344745Y847747I-1297J0D01*
G01X1344714Y847661D01*
X1345521Y846263D01*
X1345611Y846246D01*
G02X1346666Y844971I-243J-1275D01*
G02X1344072I-1297J0D01*
G02X1344144Y845400I1297J3D01*
G01X1344175Y845486D01*
G37*
G36*
G01X1351575D02*
X1350768Y846884D01*
X1350678Y846901D01*
G02X1349622Y848176I242J1275D01*
G02X1352218I1298J0D01*
G02X1352145Y847747I-1297J0D01*
G01X1352114Y847661D01*
X1352921Y846263D01*
X1353011Y846246D01*
G02X1354066Y844971I-243J-1275D01*
G02X1351472I-1297J0D01*
G02X1351544Y845400I1297J3D01*
G01X1351575Y845486D01*
G37*
G36*
G01X1358975D02*
X1358168Y846884D01*
X1358078Y846901D01*
G02X1357022Y848176I242J1275D01*
G02X1359618I1298J0D01*
G02X1359545Y847747I-1297J0D01*
G01X1359514Y847661D01*
X1360321Y846263D01*
X1360411Y846246D01*
G02X1361466Y844971I-243J-1275D01*
G02X1358872I-1297J0D01*
G02X1358944Y845400I1297J3D01*
G01X1358975Y845486D01*
G37*
G36*
G01X1366375D02*
X1365568Y846884D01*
X1365478Y846901D01*
G02X1364422Y848176I242J1275D01*
G02X1367018I1298J0D01*
G02X1366945Y847747I-1297J0D01*
G01X1366914Y847661D01*
X1367721Y846263D01*
X1367811Y846246D01*
G02X1368866Y844971I-243J-1275D01*
G02X1366272I-1297J0D01*
G02X1366344Y845400I1297J3D01*
G01X1366375Y845486D01*
G37*
G36*
G01X1324868Y849468D02*
X1325675Y850865D01*
X1325644Y850952D01*
G02X1325572Y851380I1225J426D01*
G02X1328166I1297J0D01*
G02X1327111Y850105I-1298J0D01*
G01X1327021Y850088D01*
X1326214Y848691D01*
X1326245Y848604D01*
G02X1326318Y848176I-1225J-429D01*
G02X1323722I-1298J0D01*
G02X1324778Y849451I1298J0D01*
G01X1324868Y849468D01*
G37*
G36*
G01X1353426Y855099D02*
X1352619Y856497D01*
X1352529Y856514D01*
G02X1351474Y857789I243J1275D01*
G02X1354068I1297J0D01*
G02X1353996Y857360I-1297J-3D01*
G01X1353965Y857274D01*
X1354772Y855876D01*
X1354862Y855859D01*
G02X1355918Y854584I-242J-1275D01*
G02X1353322I-1298J0D01*
G02X1353395Y855013I1297J0D01*
G01X1353426Y855099D01*
G37*
G36*
G01X1360826D02*
X1360019Y856497D01*
X1359929Y856514D01*
G02X1358874Y857789I243J1275D01*
G02X1361468I1297J0D01*
G02X1361396Y857360I-1297J-3D01*
G01X1361365Y857274D01*
X1362172Y855876D01*
X1362262Y855859D01*
G02X1363318Y854584I-242J-1275D01*
G02X1360722I-1298J0D01*
G02X1360795Y855013I1297J0D01*
G01X1360826Y855099D01*
G37*
G36*
G01X1368226D02*
X1367419Y856497D01*
X1367329Y856514D01*
G02X1366274Y857789I243J1275D01*
G02X1368868I1297J0D01*
G02X1368796Y857360I-1297J-3D01*
G01X1368765Y857274D01*
X1369572Y855876D01*
X1369662Y855859D01*
G02X1370718Y854584I-242J-1275D01*
G02X1368122I-1298J0D01*
G02X1368195Y855013I1297J0D01*
G01X1368226Y855099D01*
G37*
G36*
G01X1356319Y859081D02*
X1357126Y860478D01*
X1357095Y860565D01*
G02X1357022Y860993I1225J429D01*
G02X1359618I1298J0D01*
G02X1358562Y859718I-1298J0D01*
G01X1358472Y859701D01*
X1357665Y858304D01*
X1357696Y858217D01*
G02X1357768Y857789I-1225J-426D01*
G02X1355174I-1297J0D01*
G02X1356229Y859064I1298J0D01*
G01X1356319Y859081D01*
G37*
G36*
G01X1363719D02*
X1364526Y860478D01*
X1364495Y860565D01*
G02X1364422Y860993I1225J429D01*
G02X1367018I1298J0D01*
G02X1365962Y859718I-1298J0D01*
G01X1365872Y859701D01*
X1365065Y858304D01*
X1365096Y858217D01*
G02X1365168Y857789I-1225J-426D01*
G02X1362574I-1297J0D01*
G02X1363629Y859064I1298J0D01*
G01X1363719Y859081D01*
G37*
G36*
G01X1368226Y867916D02*
X1367419Y869314D01*
X1367329Y869331D01*
G02X1366274Y870606I243J1275D01*
G02X1368868I1297J0D01*
G02X1368796Y870177I-1297J-3D01*
G01X1368765Y870091D01*
X1369572Y868693D01*
X1369662Y868676D01*
G02X1370718Y867401I-242J-1275D01*
G02X1368122I-1298J0D01*
G02X1368195Y867830I1297J0D01*
G01X1368226Y867916D01*
G37*
G36*
G01X1363719Y871898D02*
X1364526Y873295D01*
X1364495Y873382D01*
G02X1364422Y873810I1225J429D01*
G02X1367018I1298J0D01*
G02X1365962Y872535I-1298J0D01*
G01X1365872Y872518D01*
X1365065Y871121D01*
X1365096Y871034D01*
G02X1365168Y870606I-1225J-426D01*
G02X1362574I-1297J0D01*
G02X1363629Y871881I1298J0D01*
G01X1363719Y871898D01*
G37*
G36*
G01X1371119D02*
X1371926Y873295D01*
X1371895Y873382D01*
G02X1371822Y873810I1225J429D01*
G02X1374418I1298J0D01*
G02X1373362Y872535I-1298J0D01*
G01X1373272Y872518D01*
X1372465Y871121D01*
X1372496Y871034D01*
G02X1372568Y870606I-1225J-426D01*
G02X1369974I-1297J0D01*
G02X1371029Y871881I1298J0D01*
G01X1371119Y871898D01*
G37*
G36*
G01X1378519D02*
X1379326Y873295D01*
X1379295Y873382D01*
G02X1379222Y873810I1225J429D01*
G02X1381818I1298J0D01*
G02X1380762Y872535I-1298J0D01*
G01X1380672Y872518D01*
X1379865Y871121D01*
X1379896Y871034D01*
G02X1379968Y870606I-1225J-426D01*
G02X1377374I-1297J0D01*
G02X1378429Y871881I1298J0D01*
G01X1378519Y871898D01*
G37*
G36*
G01X1368225Y880734D02*
X1367419Y882131D01*
X1367329Y882148D01*
G02X1366274Y883423I243J1275D01*
G02X1368868I1297J0D01*
G02X1368796Y882994I-1297J-3D01*
G01X1368765Y882908D01*
X1369571Y881511D01*
X1369661Y881494D01*
G02X1370718Y880219I-240J-1275D01*
G02X1368122I-1298J0D01*
G02X1368195Y880647I1298J-1D01*
G01X1368225Y880734D01*
G37*
G36*
G01X1375625D02*
X1374819Y882131D01*
X1374729Y882148D01*
G02X1373674Y883423I243J1275D01*
G02X1376268I1297J0D01*
G02X1376196Y882994I-1297J-3D01*
G01X1376165Y882908D01*
X1376971Y881511D01*
X1377061Y881494D01*
G02X1378118Y880219I-240J-1275D01*
G02X1375522I-1298J0D01*
G02X1375595Y880647I1298J-1D01*
G01X1375625Y880734D01*
G37*
G36*
G01X1363719Y884715D02*
X1364526Y886112D01*
X1364495Y886199D01*
G02X1364422Y886627I1225J429D01*
G02X1367018I1298J0D01*
G02X1365962Y885352I-1298J0D01*
G01X1365872Y885335D01*
X1365065Y883938D01*
X1365096Y883851D01*
G02X1365168Y883423I-1225J-426D01*
G02X1362574I-1297J0D01*
G02X1363629Y884698I1298J0D01*
G01X1363719Y884715D01*
G37*
G36*
G01X1371119D02*
X1371926Y886112D01*
X1371895Y886199D01*
G02X1371822Y886627I1225J429D01*
G02X1374418I1298J0D01*
G02X1373362Y885352I-1298J0D01*
G01X1373272Y885335D01*
X1372465Y883938D01*
X1372496Y883851D01*
G02X1372568Y883423I-1225J-426D01*
G02X1369974I-1297J0D01*
G02X1371029Y884698I1298J0D01*
G01X1371119Y884715D01*
G37*
G36*
G01X1378519D02*
X1379326Y886112D01*
X1379295Y886199D01*
G02X1379222Y886627I1225J429D01*
G02X1381818I1298J0D01*
G02X1380762Y885352I-1298J0D01*
G01X1380672Y885335D01*
X1379865Y883938D01*
X1379896Y883851D01*
G02X1379968Y883423I-1225J-426D01*
G02X1377374I-1297J0D01*
G02X1378429Y884698I1298J0D01*
G01X1378519Y884715D01*
G37*
G36*
G01X1404852Y1077879D02*
X1405659Y1079276D01*
X1405628Y1079363D01*
G02X1405556Y1079791I1225J426D01*
G02X1408150I1297J0D01*
G02X1407095Y1078516I-1298J0D01*
G01X1407005Y1078499D01*
X1406198Y1077101D01*
X1406228Y1077015D01*
G02X1406300Y1076587I-1225J-426D01*
G02X1403706I-1297J0D01*
G02X1404762Y1077862I1298J0D01*
G01X1404852Y1077879D01*
G37*
G36*
G01X1405658Y1086715D02*
X1404851Y1088112D01*
X1404761Y1088129D01*
G02X1403706Y1089404I243J1275D01*
G02X1406300I1297J0D01*
G02X1406228Y1088976I-1297J-2D01*
G01X1406197Y1088889D01*
X1407004Y1087492D01*
X1407094Y1087475D01*
G02X1408150Y1086200I-242J-1275D01*
G02X1405554I-1298J0D01*
G02X1405627Y1086629I1297J0D01*
G01X1405658Y1086715D01*
G37*
G36*
G01X1450107Y1138083D02*
X1449263Y1139679D01*
X1449168Y1139697D01*
G02X1448106Y1140973I236J1276D01*
G02X1450700I1297J0D01*
G02X1450589Y1140448I-1297J0D01*
G01X1450550Y1140359D01*
X1451394Y1138763D01*
X1451489Y1138745D01*
G02X1452552Y1137469I-234J-1276D01*
G02X1449956I-1298J0D01*
G02X1450068Y1137994I1297J-2D01*
G01X1450107Y1138083D01*
G37*
G36*
G01X1474516Y730492D02*
G02X1473515Y728758I-2002J0D01*
G01X1469877Y726657D01*
G02X1468878Y726390I-999J1736D01*
G01X1468876D01*
G02X1466874Y728392I0J2002D01*
G02X1467875Y730126I2002J0D01*
G01X1471513Y732227D01*
G02X1472512Y732494I999J-1736D01*
G01X1472514D01*
G02X1474516Y730492I0J-2002D01*
G37*
G36*
G01X1477716Y717492D02*
G02X1476715Y715758I-2002J0D01*
G01X1473077Y713657D01*
G02X1472078Y713390I-999J1736D01*
G01X1472076D01*
G02X1470074Y715392I0J2002D01*
G02X1471075Y717126I2002J0D01*
G01X1474713Y719227D01*
G02X1475712Y719494I999J-1736D01*
G01X1475714D01*
G02X1477716Y717492I0J-2002D01*
G37*
G36*
G01Y702992D02*
G02X1476715Y701258I-2002J0D01*
G01X1473077Y699157D01*
G02X1472078Y698890I-999J1736D01*
G01X1472076D01*
G02X1470074Y700892I0J2002D01*
G02X1471075Y702626I2002J0D01*
G01X1474713Y704727D01*
G02X1475712Y704994I999J-1736D01*
G01X1475714D01*
G02X1477716Y702992I0J-2002D01*
G37*
G36*
G01Y688492D02*
G02X1476715Y686758I-2002J0D01*
G01X1473077Y684657D01*
G02X1472078Y684390I-999J1736D01*
G01X1472076D01*
G02X1470074Y686392I0J2002D01*
G02X1471075Y688126I2002J0D01*
G01X1474713Y690227D01*
G02X1475712Y690494I999J-1736D01*
G01X1475714D01*
G02X1477716Y688492I0J-2002D01*
G37*
G36*
G01Y673992D02*
G02X1476715Y672258I-2002J0D01*
G01X1473077Y670157D01*
G02X1472078Y669890I-999J1736D01*
G01X1472076D01*
G02X1470074Y671892I0J2002D01*
G02X1471075Y673626I2002J0D01*
G01X1474713Y675727D01*
G02X1475712Y675994I999J-1736D01*
G01X1475714D01*
G02X1477716Y673992I0J-2002D01*
G37*
G36*
G01Y659492D02*
G02X1476715Y657758I-2002J0D01*
G01X1473077Y655657D01*
G02X1472078Y655390I-999J1736D01*
G01X1472076D01*
G02X1470074Y657392I0J2002D01*
G02X1471075Y659126I2002J0D01*
G01X1474713Y661227D01*
G02X1475712Y661494I999J-1736D01*
G01X1475714D01*
G02X1477716Y659492I0J-2002D01*
G37*
G36*
G01X1455174Y716992D02*
G02X1457176Y718994I2002J0D01*
G01X1457178D01*
G02X1458177Y718727I0J-2003D01*
G01X1461815Y716626D01*
G02X1462816Y714892I-1001J-1734D01*
G02X1460814Y712890I-2002J0D01*
G01X1460812D01*
G02X1459813Y713157I0J2003D01*
G01X1456175Y715258D01*
G02X1455174Y716992I1001J1734D01*
G37*
G36*
G01Y704992D02*
G02X1457176Y706994I2002J0D01*
G01X1457178D01*
G02X1458177Y706727I0J-2003D01*
G01X1461815Y704626D01*
G02X1462816Y702892I-1001J-1734D01*
G02X1460814Y700890I-2002J0D01*
G01X1460812D01*
G02X1459813Y701157I0J2003D01*
G01X1456175Y703258D01*
G02X1455174Y704992I1001J1734D01*
G37*
G36*
G01Y692992D02*
G02X1457176Y694994I2002J0D01*
G01X1457178D01*
G02X1458177Y694727I0J-2003D01*
G01X1461815Y692626D01*
G02X1462816Y690892I-1001J-1734D01*
G02X1460814Y688890I-2002J0D01*
G01X1460812D01*
G02X1459813Y689157I0J2003D01*
G01X1456175Y691258D01*
G02X1455174Y692992I1001J1734D01*
G37*
G36*
G01Y680992D02*
G02X1457176Y682994I2002J0D01*
G01X1457178D01*
G02X1458177Y682727I0J-2003D01*
G01X1461815Y680626D01*
G02X1462816Y678892I-1001J-1734D01*
G02X1460814Y676890I-2002J0D01*
G01X1460812D01*
G02X1459813Y677157I0J2003D01*
G01X1456175Y679258D01*
G02X1455174Y680992I1001J1734D01*
G37*
G36*
G01Y668992D02*
G02X1457176Y670994I2002J0D01*
G01X1457178D01*
G02X1458177Y670727I0J-2003D01*
G01X1461815Y668626D01*
G02X1462816Y666892I-1001J-1734D01*
G02X1460814Y664890I-2002J0D01*
G01X1460812D01*
G02X1459813Y665157I0J2003D01*
G01X1456175Y667258D01*
G02X1455174Y668992I1001J1734D01*
G37*
G36*
G01Y656992D02*
G02X1457176Y658994I2002J0D01*
G01X1457178D01*
G02X1458177Y658727I0J-2003D01*
G01X1461815Y656626D01*
G02X1462816Y654892I-1001J-1734D01*
G02X1460814Y652890I-2002J0D01*
G01X1460812D01*
G02X1459813Y653157I0J2003D01*
G01X1456175Y655258D01*
G02X1455174Y656992I1001J1734D01*
G37*
G36*
G01X1471460Y631900D02*
X1468060D01*
G02Y634904I0J1502D01*
G01X1471460D01*
G02Y631900I0J-1502D01*
G37*
G36*
G01X1384772Y844971D02*
G02X1387366I1297J0D01*
G02X1386304Y843695I-1298J0D01*
G01X1386209Y843677D01*
X1385368Y842082D01*
X1385407Y841994D01*
G02X1385518Y841467I-1186J-525D01*
G02X1382924I-1297J0D01*
G02X1383986Y842743I1298J0D01*
G01X1384081Y842761D01*
X1384922Y844356D01*
X1384883Y844444D01*
G02X1384772Y844971I1186J525D01*
G37*
G36*
G01X1392172D02*
G02X1394766I1297J0D01*
G02X1393704Y843695I-1298J0D01*
G01X1393609Y843677D01*
X1392768Y842082D01*
X1392807Y841994D01*
G02X1392918Y841467I-1186J-525D01*
G02X1390324I-1297J0D01*
G02X1391386Y842743I1298J0D01*
G01X1391481Y842761D01*
X1392322Y844356D01*
X1392283Y844444D01*
G02X1392172Y844971I1186J525D01*
G37*
G36*
G01X1399572D02*
G02X1402166I1297J0D01*
G02X1401104Y843695I-1298J0D01*
G01X1401009Y843677D01*
X1400168Y842082D01*
X1400207Y841994D01*
G02X1400318Y841467I-1186J-525D01*
G02X1397724I-1297J0D01*
G02X1398786Y842743I1298J0D01*
G01X1398881Y842761D01*
X1399722Y844356D01*
X1399683Y844444D01*
G02X1399572Y844971I1186J525D01*
G37*
G36*
G01X1379222Y848176D02*
G02X1381818I1298J0D01*
G02X1381745Y847747I-1297J0D01*
G01X1381714Y847661D01*
X1382521Y846263D01*
X1382611Y846246D01*
G02X1383666Y844971I-243J-1275D01*
G02X1381072I-1297J0D01*
G02X1381144Y845400I1297J3D01*
G01X1381175Y845486D01*
X1380368Y846884D01*
X1380278Y846901D01*
G02X1379222Y848176I242J1275D01*
G37*
G36*
G01X1386622D02*
G02X1389218I1298J0D01*
G02X1389145Y847747I-1297J0D01*
G01X1389114Y847661D01*
X1389921Y846263D01*
X1390011Y846246D01*
G02X1391066Y844971I-243J-1275D01*
G02X1388472I-1297J0D01*
G02X1388544Y845400I1297J3D01*
G01X1388575Y845486D01*
X1387768Y846884D01*
X1387678Y846901D01*
G02X1386622Y848176I242J1275D01*
G37*
G36*
G01X1394022D02*
G02X1396618I1298J0D01*
G02X1396545Y847747I-1297J0D01*
G01X1396514Y847661D01*
X1397321Y846263D01*
X1397411Y846246D01*
G02X1398466Y844971I-243J-1275D01*
G02X1395872I-1297J0D01*
G02X1395944Y845400I1297J3D01*
G01X1395975Y845486D01*
X1395168Y846884D01*
X1395078Y846901D01*
G02X1394022Y848176I242J1275D01*
G37*
G36*
G01X1401422D02*
G02X1404018I1298J0D01*
G02X1403945Y847747I-1297J0D01*
G01X1403914Y847661D01*
X1404721Y846263D01*
X1404811Y846246D01*
G02X1405866Y844971I-243J-1275D01*
G02X1403272I-1297J0D01*
G02X1403344Y845400I1297J3D01*
G01X1403375Y845486D01*
X1402568Y846884D01*
X1402478Y846901D01*
G02X1401422Y848176I242J1275D01*
G37*
G36*
G01X1406420Y849474D02*
G02X1407459Y848954I0J-1298D01*
G01X1409081D01*
G02X1410120Y849474I1039J-778D01*
G02Y846878I0J-1298D01*
G02X1409081Y847398I0J1298D01*
G01X1407459D01*
G02X1406420Y846878I-1039J778D01*
G02Y849474I0J1298D01*
G37*
G36*
G01X1412522Y848176D02*
G02X1415118I1298J0D01*
G02X1414062Y846901I-1298J0D01*
G01X1413972Y846884D01*
X1413164Y845485D01*
X1413194Y845398D01*
G02X1413266Y844973I-1225J-426D01*
G01Y844971D01*
G02X1410672I-1297J0D01*
G02X1411728Y846246I1298J0D01*
G01X1411818Y846263D01*
X1412625Y847662D01*
X1412595Y847748D01*
G02X1412522Y848176I1225J429D01*
G37*
G36*
G01X1381074Y857789D02*
G02X1383668I1297J0D01*
G02X1383596Y857360I-1297J-3D01*
G01X1383565Y857274D01*
X1384372Y855876D01*
X1384462Y855859D01*
G02X1385518Y854584I-242J-1275D01*
G02X1382922I-1298J0D01*
G02X1382995Y855013I1297J0D01*
G01X1383026Y855099D01*
X1382219Y856497D01*
X1382129Y856514D01*
G02X1381074Y857789I243J1275D01*
G37*
G36*
G01X1388474D02*
G02X1391068I1297J0D01*
G02X1390996Y857360I-1297J-3D01*
G01X1390965Y857274D01*
X1391772Y855876D01*
X1391862Y855859D01*
G02X1392918Y854584I-242J-1275D01*
G02X1390322I-1298J0D01*
G02X1390395Y855013I1297J0D01*
G01X1390426Y855099D01*
X1389619Y856497D01*
X1389529Y856514D01*
G02X1388474Y857789I243J1275D01*
G37*
G36*
G01X1395874D02*
G02X1398468I1297J0D01*
G02X1398396Y857360I-1297J-3D01*
G01X1398365Y857274D01*
X1399172Y855876D01*
X1399262Y855859D01*
G02X1400318Y854584I-242J-1275D01*
G02X1397722I-1298J0D01*
G02X1397795Y855013I1297J0D01*
G01X1397826Y855099D01*
X1397019Y856497D01*
X1396929Y856514D01*
G02X1395874Y857789I243J1275D01*
G37*
G36*
G01X1403274D02*
G02X1405868I1297J0D01*
G02X1405796Y857360I-1297J-3D01*
G01X1405765Y857274D01*
X1406572Y855876D01*
X1406662Y855859D01*
G02X1407718Y854584I-242J-1275D01*
G02X1405122I-1298J0D01*
G02X1405195Y855013I1297J0D01*
G01X1405226Y855099D01*
X1404419Y856497D01*
X1404329Y856514D01*
G02X1403274Y857789I243J1275D01*
G37*
G36*
G01X1410674D02*
G02X1413268I1297J0D01*
G02X1413196Y857360I-1297J-3D01*
G01X1413165Y857274D01*
X1413972Y855876D01*
X1414062Y855859D01*
G02X1415118Y854584I-242J-1275D01*
G02X1412524I-1297J0D01*
G02X1412596Y855012I1297J2D01*
G01X1412626Y855098D01*
X1411819Y856497D01*
X1411729Y856514D01*
G02X1410674Y857789I243J1275D01*
G37*
G36*
G01X1421774D02*
G02X1424368I1297J0D01*
G02X1423313Y856514I-1298J0D01*
G01X1423223Y856497D01*
X1422415Y855098D01*
X1422445Y855011D01*
G02X1422518Y854584I-1225J-429D01*
G02X1419922I-1298J0D01*
G02X1420980Y855859I1297J0D01*
G01X1421070Y855876D01*
X1421877Y857274D01*
X1421846Y857361D01*
G02X1421774Y857789I1225J426D01*
G37*
G36*
G01X1379222Y860993D02*
G02X1381818I1298J0D01*
G02X1380762Y859718I-1298J0D01*
G01X1380672Y859701D01*
X1379865Y858304D01*
X1379896Y858217D01*
G02X1379968Y857789I-1225J-426D01*
G02X1377374I-1297J0D01*
G02X1378429Y859064I1298J0D01*
G01X1378519Y859081D01*
X1379326Y860478D01*
X1379295Y860565D01*
G02X1379222Y860993I1225J429D01*
G37*
G36*
G01X1386622D02*
G02X1389218I1298J0D01*
G02X1388162Y859718I-1298J0D01*
G01X1388072Y859701D01*
X1387265Y858304D01*
X1387296Y858217D01*
G02X1387368Y857789I-1225J-426D01*
G02X1384774I-1297J0D01*
G02X1385829Y859064I1298J0D01*
G01X1385919Y859081D01*
X1386726Y860478D01*
X1386695Y860565D01*
G02X1386622Y860993I1225J429D01*
G37*
G36*
G01X1394022D02*
G02X1396618I1298J0D01*
G02X1395562Y859718I-1298J0D01*
G01X1395472Y859701D01*
X1394665Y858304D01*
X1394696Y858217D01*
G02X1394768Y857789I-1225J-426D01*
G02X1392174I-1297J0D01*
G02X1393229Y859064I1298J0D01*
G01X1393319Y859081D01*
X1394126Y860478D01*
X1394095Y860565D01*
G02X1394022Y860993I1225J429D01*
G37*
G36*
G01X1401422D02*
G02X1404018I1298J0D01*
G02X1402962Y859718I-1298J0D01*
G01X1402872Y859701D01*
X1402065Y858304D01*
X1402096Y858217D01*
G02X1402168Y857789I-1225J-426D01*
G02X1399574I-1297J0D01*
G02X1400629Y859064I1298J0D01*
G01X1400719Y859081D01*
X1401526Y860478D01*
X1401495Y860565D01*
G02X1401422Y860993I1225J429D01*
G37*
G36*
G01X1408824D02*
G02X1411418I1297J0D01*
G02X1410363Y859718I-1298J0D01*
G01X1410273Y859701D01*
X1409466Y858303D01*
X1409496Y858217D01*
G02X1409568Y857789I-1225J-426D01*
G02X1406974I-1297J0D01*
G02X1408030Y859064I1298J0D01*
G01X1408120Y859081D01*
X1408927Y860478D01*
X1408896Y860565D01*
G02X1408824Y860993I1225J426D01*
G37*
G36*
G01X1416222D02*
G02X1418818I1298J0D01*
G02X1418745Y860564I-1297J0D01*
G01X1418714Y860478D01*
X1419520Y859081D01*
X1419610Y859064D01*
G02X1420668Y857789I-239J-1275D01*
G02X1418074I-1297J0D01*
G02X1418145Y858215I1297J3D01*
G01X1418176Y858302D01*
X1417368Y859701D01*
X1417278Y859718D01*
G02X1416222Y860993I242J1275D01*
G37*
G36*
G01X1423624D02*
G02X1426218I1297J0D01*
G02X1426146Y860564I-1297J-3D01*
G01X1426115Y860478D01*
X1426921Y859081D01*
X1427011Y859064D01*
G02X1428068Y857789I-240J-1275D01*
G02X1425474I-1297J0D01*
G01Y857791D01*
G02X1425546Y858216I1297J-1D01*
G01X1425576Y858303D01*
X1424769Y859701D01*
X1424679Y859718D01*
G02X1423624Y860993I243J1275D01*
G37*
G36*
G01X1392174Y870606D02*
G02X1394768I1297J0D01*
G02X1393713Y869331I-1298J0D01*
G01X1393623Y869314D01*
X1392815Y867915D01*
X1392845Y867828D01*
G02X1392918Y867401I-1225J-429D01*
G02X1390322I-1298J0D01*
G02X1391380Y868676I1297J0D01*
G01X1391470Y868693D01*
X1392277Y870091D01*
X1392246Y870178D01*
G02X1392174Y870606I1225J426D01*
G37*
G36*
G01X1399574D02*
G02X1402168I1297J0D01*
G02X1401113Y869331I-1298J0D01*
G01X1401023Y869314D01*
X1400215Y867915D01*
X1400245Y867828D01*
G02X1400318Y867401I-1225J-429D01*
G02X1397722I-1298J0D01*
G02X1398780Y868676I1297J0D01*
G01X1398870Y868693D01*
X1399677Y870091D01*
X1399646Y870178D01*
G02X1399574Y870606I1225J426D01*
G37*
G36*
G01X1406974D02*
G02X1409568I1297J0D01*
G02X1408513Y869331I-1298J0D01*
G01X1408423Y869314D01*
X1407615Y867915D01*
X1407645Y867828D01*
G02X1407718Y867401I-1225J-429D01*
G02X1405122I-1298J0D01*
G02X1406180Y868676I1297J0D01*
G01X1406270Y868693D01*
X1407077Y870091D01*
X1407046Y870178D01*
G02X1406974Y870606I1225J426D01*
G37*
G36*
G01X1414374D02*
G02X1416968I1297J0D01*
G02X1415913Y869331I-1298J0D01*
G01X1415823Y869314D01*
X1415015Y867915D01*
X1415045Y867828D01*
G02X1415118Y867401I-1225J-429D01*
G02X1412522I-1298J0D01*
G02X1413580Y868676I1297J0D01*
G01X1413670Y868693D01*
X1414477Y870091D01*
X1414446Y870178D01*
G02X1414374Y870606I1225J426D01*
G37*
G36*
G01X1421774D02*
G02X1424368I1297J0D01*
G02X1423313Y869331I-1298J0D01*
G01X1423223Y869314D01*
X1422415Y867915D01*
X1422445Y867828D01*
G02X1422518Y867401I-1225J-429D01*
G02X1419922I-1298J0D01*
G02X1420980Y868676I1297J0D01*
G01X1421070Y868693D01*
X1421877Y870091D01*
X1421846Y870178D01*
G02X1421774Y870606I1225J426D01*
G37*
G36*
G01X1394022Y873810D02*
G02X1396618I1298J0D01*
G02X1396545Y873381I-1297J0D01*
G01X1396514Y873295D01*
X1397320Y871898D01*
X1397410Y871881D01*
G02X1398468Y870606I-239J-1275D01*
G02X1395874I-1297J0D01*
G02X1395945Y871032I1297J3D01*
G01X1395976Y871119D01*
X1395168Y872518D01*
X1395078Y872535D01*
G02X1394022Y873810I242J1275D01*
G37*
G36*
G01X1401422D02*
G02X1404018I1298J0D01*
G02X1403945Y873381I-1297J0D01*
G01X1403914Y873295D01*
X1404720Y871898D01*
X1404810Y871881D01*
G02X1405868Y870606I-239J-1275D01*
G02X1403274I-1297J0D01*
G02X1403345Y871032I1297J3D01*
G01X1403376Y871119D01*
X1402568Y872518D01*
X1402478Y872535D01*
G02X1401422Y873810I242J1275D01*
G37*
G36*
G01X1408824D02*
G02X1411418I1297J0D01*
G02X1411346Y873381I-1297J-3D01*
G01X1411315Y873295D01*
X1412121Y871898D01*
X1412211Y871881D01*
G02X1413268Y870606I-240J-1275D01*
G02X1410674I-1297J0D01*
G01Y870608D01*
G02X1410746Y871033I1297J-1D01*
G01X1410776Y871120D01*
X1409969Y872518D01*
X1409879Y872535D01*
G02X1408824Y873810I243J1275D01*
G37*
G36*
G01X1416222D02*
G02X1418818I1298J0D01*
G02X1418745Y873381I-1297J0D01*
G01X1418714Y873295D01*
X1419520Y871898D01*
X1419610Y871881D01*
G02X1420668Y870606I-239J-1275D01*
G02X1418074I-1297J0D01*
G02X1418145Y871032I1297J3D01*
G01X1418176Y871119D01*
X1417368Y872518D01*
X1417278Y872535D01*
G02X1416222Y873810I242J1275D01*
G37*
G36*
G01X1423624D02*
G02X1426218I1297J0D01*
G02X1426146Y873381I-1297J-3D01*
G01X1426115Y873295D01*
X1426921Y871898D01*
X1427011Y871881D01*
G02X1428068Y870606I-240J-1275D01*
G02X1425474I-1297J0D01*
G01Y870608D01*
G02X1425546Y871033I1297J-1D01*
G01X1425576Y871120D01*
X1424769Y872518D01*
X1424679Y872535D01*
G02X1423624Y873810I243J1275D01*
G37*
G36*
G01X1388474Y883423D02*
G02X1391068I1297J0D01*
G02X1390996Y882994I-1297J-3D01*
G01X1390965Y882908D01*
X1391771Y881511D01*
X1391861Y881494D01*
G02X1392918Y880219I-240J-1275D01*
G02X1390322I-1298J0D01*
G02X1390395Y880647I1298J-1D01*
G01X1390425Y880734D01*
X1389619Y882131D01*
X1389529Y882148D01*
G02X1388474Y883423I243J1275D01*
G37*
G36*
G01X1395874D02*
G02X1398468I1297J0D01*
G02X1398396Y882994I-1297J-3D01*
G01X1398365Y882908D01*
X1399171Y881511D01*
X1399261Y881494D01*
G02X1400318Y880219I-240J-1275D01*
G02X1397722I-1298J0D01*
G02X1397795Y880647I1298J-1D01*
G01X1397825Y880734D01*
X1397019Y882131D01*
X1396929Y882148D01*
G02X1395874Y883423I243J1275D01*
G37*
G36*
G01X1403274D02*
G02X1405868I1297J0D01*
G02X1405796Y882994I-1297J-3D01*
G01X1405765Y882908D01*
X1406571Y881511D01*
X1406661Y881494D01*
G02X1407718Y880219I-240J-1275D01*
G02X1405122I-1298J0D01*
G02X1405195Y880647I1298J-1D01*
G01X1405225Y880734D01*
X1404419Y882131D01*
X1404329Y882148D01*
G02X1403274Y883423I243J1275D01*
G37*
G36*
G01X1410674D02*
G02X1413268I1297J0D01*
G02X1413196Y882994I-1297J-3D01*
G01X1413165Y882908D01*
X1413971Y881511D01*
X1414061Y881494D01*
G02X1415118Y880219I-240J-1275D01*
G02X1412522I-1298J0D01*
G02X1412595Y880647I1298J-1D01*
G01X1412625Y880734D01*
X1411819Y882131D01*
X1411729Y882148D01*
G02X1410674Y883423I243J1275D01*
G37*
G36*
G01X1418074D02*
G02X1420668I1297J0D01*
G02X1420596Y882994I-1297J-3D01*
G01X1420565Y882908D01*
X1421371Y881511D01*
X1421461Y881494D01*
G02X1422518Y880219I-240J-1275D01*
G02X1419922I-1298J0D01*
G02X1419995Y880647I1298J-1D01*
G01X1420025Y880734D01*
X1419219Y882131D01*
X1419129Y882148D01*
G02X1418074Y883423I243J1275D01*
G37*
G36*
G01X1394022Y886627D02*
G02X1396618I1298J0D01*
G02X1395562Y885352I-1298J0D01*
G01X1395472Y885335D01*
X1394665Y883938D01*
X1394696Y883851D01*
G02X1394768Y883423I-1225J-426D01*
G02X1392174I-1297J0D01*
G02X1393229Y884698I1298J0D01*
G01X1393319Y884715D01*
X1394126Y886112D01*
X1394095Y886199D01*
G02X1394022Y886627I1225J429D01*
G37*
G36*
G01X1401422D02*
G02X1404018I1298J0D01*
G02X1402962Y885352I-1298J0D01*
G01X1402872Y885335D01*
X1402065Y883938D01*
X1402096Y883851D01*
G02X1402168Y883423I-1225J-426D01*
G02X1399574I-1297J0D01*
G02X1400629Y884698I1298J0D01*
G01X1400719Y884715D01*
X1401526Y886112D01*
X1401495Y886199D01*
G02X1401422Y886627I1225J429D01*
G37*
G36*
G01X1408822D02*
G02X1411418I1298J0D01*
G02X1410362Y885352I-1298J0D01*
G01X1410272Y885335D01*
X1409465Y883938D01*
X1409496Y883851D01*
G02X1409568Y883423I-1225J-426D01*
G02X1406974I-1297J0D01*
G02X1408029Y884698I1298J0D01*
G01X1408119Y884715D01*
X1408926Y886112D01*
X1408895Y886199D01*
G02X1408822Y886627I1225J429D01*
G37*
G36*
G01X1416222D02*
G02X1418818I1298J0D01*
G02X1417762Y885352I-1298J0D01*
G01X1417672Y885335D01*
X1416865Y883938D01*
X1416896Y883851D01*
G02X1416968Y883423I-1225J-426D01*
G02X1414374I-1297J0D01*
G02X1415429Y884698I1298J0D01*
G01X1415519Y884715D01*
X1416326Y886112D01*
X1416295Y886199D01*
G02X1416222Y886627I1225J429D01*
G37*
G36*
G01X1423622D02*
G02X1426218I1298J0D01*
G02X1425162Y885352I-1298J0D01*
G01X1425072Y885335D01*
X1424265Y883938D01*
X1424296Y883851D01*
G02X1424368Y883423I-1225J-426D01*
G02X1421774I-1297J0D01*
G02X1422829Y884698I1298J0D01*
G01X1422919Y884715D01*
X1423726Y886112D01*
X1423695Y886199D01*
G02X1423622Y886627I1225J429D01*
G37*
G36*
G01X1435870Y855876D02*
X1436677Y857274D01*
X1436646Y857361D01*
G02X1436574Y857789I1225J426D01*
G02X1439168I1297J0D01*
G02X1438113Y856514I-1298J0D01*
G01X1438023Y856497D01*
X1437215Y855098D01*
X1437245Y855011D01*
G02X1437318Y854584I-1225J-429D01*
G02X1434722I-1298J0D01*
G02X1435780Y855859I1297J0D01*
G01X1435870Y855876D01*
G37*
G36*
G01X1443270D02*
X1444077Y857274D01*
X1444046Y857361D01*
G02X1443974Y857789I1225J426D01*
G02X1446568I1297J0D01*
G02X1445513Y856514I-1298J0D01*
G01X1445423Y856497D01*
X1444615Y855098D01*
X1444645Y855011D01*
G02X1444718Y854584I-1225J-429D01*
G02X1442122I-1298J0D01*
G02X1443180Y855859I1297J0D01*
G01X1443270Y855876D01*
G37*
G36*
G01X1450670D02*
X1451477Y857274D01*
X1451446Y857361D01*
G02X1451374Y857789I1225J426D01*
G02X1453968I1297J0D01*
G02X1452913Y856514I-1298J0D01*
G01X1452823Y856497D01*
X1452015Y855098D01*
X1452045Y855011D01*
G02X1452118Y854584I-1225J-429D01*
G02X1449522I-1298J0D01*
G02X1450580Y855859I1297J0D01*
G01X1450670Y855876D01*
G37*
G36*
G01X1458070D02*
X1458877Y857274D01*
X1458846Y857361D01*
G02X1458774Y857789I1225J426D01*
G02X1461368I1297J0D01*
G02X1460313Y856514I-1298J0D01*
G01X1460223Y856497D01*
X1459415Y855098D01*
X1459445Y855011D01*
G02X1459518Y854584I-1225J-429D01*
G02X1456922I-1298J0D01*
G02X1457980Y855859I1297J0D01*
G01X1458070Y855876D01*
G37*
G36*
G01X1465470D02*
X1466277Y857274D01*
X1466246Y857361D01*
G02X1466174Y857789I1225J426D01*
G02X1468768I1297J0D01*
G02X1467713Y856514I-1298J0D01*
G01X1467623Y856497D01*
X1466815Y855098D01*
X1466845Y855011D01*
G02X1466918Y854584I-1225J-429D01*
G02X1464322I-1298J0D01*
G02X1465380Y855859I1297J0D01*
G01X1465470Y855876D01*
G37*
G36*
G01X1472870D02*
X1473677Y857274D01*
X1473646Y857361D01*
G02X1473574Y857789I1225J426D01*
G02X1476168I1297J0D01*
G02X1475113Y856514I-1298J0D01*
G01X1475023Y856497D01*
X1474215Y855098D01*
X1474245Y855011D01*
G02X1474318Y854584I-1225J-429D01*
G02X1471722I-1298J0D01*
G02X1472780Y855859I1297J0D01*
G01X1472870Y855876D01*
G37*
G36*
G01X1440376Y858302D02*
X1439568Y859701D01*
X1439478Y859718D01*
G02X1438422Y860993I242J1275D01*
G02X1441018I1298J0D01*
G02X1440945Y860564I-1297J0D01*
G01X1440914Y860478D01*
X1441720Y859081D01*
X1441810Y859064D01*
G02X1442868Y857789I-239J-1275D01*
G02X1440274I-1297J0D01*
G02X1440345Y858215I1297J3D01*
G01X1440376Y858302D01*
G37*
G36*
G01X1447776D02*
X1446968Y859701D01*
X1446878Y859718D01*
G02X1445822Y860993I242J1275D01*
G02X1448418I1298J0D01*
G02X1448345Y860564I-1297J0D01*
G01X1448314Y860478D01*
X1449120Y859081D01*
X1449210Y859064D01*
G02X1450268Y857789I-239J-1275D01*
G02X1447674I-1297J0D01*
G02X1447745Y858215I1297J3D01*
G01X1447776Y858302D01*
G37*
G36*
G01X1455176D02*
X1454368Y859701D01*
X1454278Y859718D01*
G02X1453222Y860993I242J1275D01*
G02X1455818I1298J0D01*
G02X1455745Y860564I-1297J0D01*
G01X1455714Y860478D01*
X1456520Y859081D01*
X1456610Y859064D01*
G02X1457668Y857789I-239J-1275D01*
G02X1455074I-1297J0D01*
G02X1455145Y858215I1297J3D01*
G01X1455176Y858302D01*
G37*
G36*
G01X1462576D02*
X1461768Y859701D01*
X1461678Y859718D01*
G02X1460622Y860993I242J1275D01*
G02X1463218I1298J0D01*
G02X1463145Y860564I-1297J0D01*
G01X1463114Y860478D01*
X1463920Y859081D01*
X1464010Y859064D01*
G02X1465068Y857789I-239J-1275D01*
G02X1462474I-1297J0D01*
G02X1462545Y858215I1297J3D01*
G01X1462576Y858302D01*
G37*
G36*
G01X1469976D02*
X1469168Y859701D01*
X1469078Y859718D01*
G02X1468022Y860993I242J1275D01*
G02X1470618I1298J0D01*
G02X1470545Y860564I-1297J0D01*
G01X1470514Y860478D01*
X1471320Y859081D01*
X1471410Y859064D01*
G02X1472468Y857789I-239J-1275D01*
G02X1469874I-1297J0D01*
G02X1469945Y858215I1297J3D01*
G01X1469976Y858302D01*
G37*
G36*
G01X1435870Y868693D02*
X1436677Y870091D01*
X1436646Y870178D01*
G02X1436574Y870606I1225J426D01*
G02X1439168I1297J0D01*
G02X1438113Y869331I-1298J0D01*
G01X1438023Y869314D01*
X1437215Y867915D01*
X1437245Y867828D01*
G02X1437318Y867401I-1225J-429D01*
G02X1434722I-1298J0D01*
G02X1435780Y868676I1297J0D01*
G01X1435870Y868693D01*
G37*
G36*
G01X1443270D02*
X1444077Y870091D01*
X1444046Y870178D01*
G02X1443974Y870606I1225J426D01*
G02X1446568I1297J0D01*
G02X1445513Y869331I-1298J0D01*
G01X1445423Y869314D01*
X1444615Y867915D01*
X1444645Y867828D01*
G02X1444718Y867401I-1225J-429D01*
G02X1442122I-1298J0D01*
G02X1443180Y868676I1297J0D01*
G01X1443270Y868693D01*
G37*
G36*
G01X1450670D02*
X1451477Y870091D01*
X1451446Y870178D01*
G02X1451374Y870606I1225J426D01*
G02X1453968I1297J0D01*
G02X1452913Y869331I-1298J0D01*
G01X1452823Y869314D01*
X1452015Y867915D01*
X1452045Y867828D01*
G02X1452118Y867401I-1225J-429D01*
G02X1449522I-1298J0D01*
G02X1450580Y868676I1297J0D01*
G01X1450670Y868693D01*
G37*
G36*
G01X1458070D02*
X1458877Y870091D01*
X1458846Y870178D01*
G02X1458774Y870606I1225J426D01*
G02X1461368I1297J0D01*
G02X1460313Y869331I-1298J0D01*
G01X1460223Y869314D01*
X1459415Y867915D01*
X1459445Y867828D01*
G02X1459518Y867401I-1225J-429D01*
G02X1456922I-1298J0D01*
G02X1457980Y868676I1297J0D01*
G01X1458070Y868693D01*
G37*
G36*
G01X1465470D02*
X1466277Y870091D01*
X1466246Y870178D01*
G02X1466174Y870606I1225J426D01*
G02X1468768I1297J0D01*
G02X1467713Y869331I-1298J0D01*
G01X1467623Y869314D01*
X1466815Y867915D01*
X1466845Y867828D01*
G02X1466918Y867401I-1225J-429D01*
G02X1464322I-1298J0D01*
G02X1465380Y868676I1297J0D01*
G01X1465470Y868693D01*
G37*
G36*
G01X1472870D02*
X1473677Y870091D01*
X1473646Y870178D01*
G02X1473574Y870606I1225J426D01*
G02X1476168I1297J0D01*
G02X1475113Y869331I-1298J0D01*
G01X1475023Y869314D01*
X1474215Y867915D01*
X1474245Y867828D01*
G02X1474318Y867401I-1225J-429D01*
G02X1471722I-1298J0D01*
G02X1472780Y868676I1297J0D01*
G01X1472870Y868693D01*
G37*
G36*
G01X1440376Y871119D02*
X1439568Y872518D01*
X1439478Y872535D01*
G02X1438422Y873810I242J1275D01*
G02X1441018I1298J0D01*
G02X1440945Y873381I-1297J0D01*
G01X1440914Y873295D01*
X1441720Y871898D01*
X1441810Y871881D01*
G02X1442868Y870606I-239J-1275D01*
G02X1440274I-1297J0D01*
G02X1440345Y871032I1297J3D01*
G01X1440376Y871119D01*
G37*
G36*
G01X1455176D02*
X1454368Y872518D01*
X1454278Y872535D01*
G02X1453222Y873810I242J1275D01*
G02X1455818I1298J0D01*
G02X1455745Y873381I-1297J0D01*
G01X1455714Y873295D01*
X1456520Y871898D01*
X1456610Y871881D01*
G02X1457668Y870606I-239J-1275D01*
G02X1455074I-1297J0D01*
G02X1455145Y871032I1297J3D01*
G01X1455176Y871119D01*
G37*
G36*
G01X1462576D02*
X1461768Y872518D01*
X1461678Y872535D01*
G02X1460622Y873810I242J1275D01*
G02X1463218I1298J0D01*
G02X1463145Y873381I-1297J0D01*
G01X1463114Y873295D01*
X1463920Y871898D01*
X1464010Y871881D01*
G02X1465068Y870606I-239J-1275D01*
G02X1462474I-1297J0D01*
G02X1462545Y871032I1297J3D01*
G01X1462576Y871119D01*
G37*
G36*
G01X1469976D02*
X1469168Y872518D01*
X1469078Y872535D01*
G02X1468022Y873810I242J1275D01*
G02X1470618I1298J0D01*
G02X1470545Y873381I-1297J0D01*
G01X1470514Y873295D01*
X1471320Y871898D01*
X1471410Y871881D01*
G02X1472468Y870606I-239J-1275D01*
G02X1469874I-1297J0D01*
G02X1469945Y871032I1297J3D01*
G01X1469976Y871119D01*
G37*
G36*
G01X1434825Y880734D02*
X1434019Y882131D01*
X1433929Y882148D01*
G02X1432874Y883423I243J1275D01*
G02X1435468I1297J0D01*
G02X1435396Y882994I-1297J-3D01*
G01X1435365Y882908D01*
X1436171Y881511D01*
X1436261Y881494D01*
G02X1437318Y880219I-240J-1275D01*
G02X1434722I-1298J0D01*
G02X1434795Y880647I1298J-1D01*
G01X1434825Y880734D01*
G37*
G36*
G01X1442225D02*
X1441419Y882131D01*
X1441329Y882148D01*
G02X1440274Y883423I243J1275D01*
G02X1442868I1297J0D01*
G02X1442796Y882994I-1297J-3D01*
G01X1442765Y882908D01*
X1443571Y881511D01*
X1443661Y881494D01*
G02X1444718Y880219I-240J-1275D01*
G02X1442122I-1298J0D01*
G02X1442195Y880647I1298J-1D01*
G01X1442225Y880734D01*
G37*
G36*
G01X1449625D02*
X1448819Y882131D01*
X1448729Y882148D01*
G02X1447674Y883423I243J1275D01*
G02X1450268I1297J0D01*
G02X1450196Y882994I-1297J-3D01*
G01X1450165Y882908D01*
X1450971Y881511D01*
X1451061Y881494D01*
G02X1452118Y880219I-240J-1275D01*
G02X1449522I-1298J0D01*
G02X1449595Y880647I1298J-1D01*
G01X1449625Y880734D01*
G37*
G36*
G01X1457025D02*
X1456219Y882131D01*
X1456129Y882148D01*
G02X1455074Y883423I243J1275D01*
G02X1457668I1297J0D01*
G02X1457596Y882994I-1297J-3D01*
G01X1457565Y882908D01*
X1458371Y881511D01*
X1458461Y881494D01*
G02X1459518Y880219I-240J-1275D01*
G02X1456922I-1298J0D01*
G02X1456995Y880647I1298J-1D01*
G01X1457025Y880734D01*
G37*
G36*
G01X1464425D02*
X1463619Y882131D01*
X1463529Y882148D01*
G02X1462474Y883423I243J1275D01*
G02X1465068I1297J0D01*
G02X1464996Y882994I-1297J-3D01*
G01X1464965Y882908D01*
X1465771Y881511D01*
X1465861Y881494D01*
G02X1466918Y880219I-240J-1275D01*
G02X1464322I-1298J0D01*
G02X1464395Y880647I1298J-1D01*
G01X1464425Y880734D01*
G37*
G36*
G01X1471825D02*
X1471019Y882131D01*
X1470929Y882148D01*
G02X1469874Y883423I243J1275D01*
G02X1472468I1297J0D01*
G02X1472396Y882994I-1297J-3D01*
G01X1472365Y882908D01*
X1473171Y881511D01*
X1473261Y881494D01*
G02X1474318Y880219I-240J-1275D01*
G02X1471722I-1298J0D01*
G02X1471795Y880647I1298J-1D01*
G01X1471825Y880734D01*
G37*
G36*
G01X1437719Y884715D02*
X1438526Y886112D01*
X1438495Y886199D01*
G02X1438422Y886627I1225J429D01*
G02X1441018I1298J0D01*
G02X1439962Y885352I-1298J0D01*
G01X1439872Y885335D01*
X1439065Y883938D01*
X1439096Y883851D01*
G02X1439168Y883423I-1225J-426D01*
G02X1436574I-1297J0D01*
G02X1437629Y884698I1298J0D01*
G01X1437719Y884715D01*
G37*
G36*
G01X1445119D02*
X1445926Y886112D01*
X1445895Y886199D01*
G02X1445822Y886627I1225J429D01*
G02X1448418I1298J0D01*
G02X1447362Y885352I-1298J0D01*
G01X1447272Y885335D01*
X1446465Y883938D01*
X1446496Y883851D01*
G02X1446568Y883423I-1225J-426D01*
G02X1443974I-1297J0D01*
G02X1445029Y884698I1298J0D01*
G01X1445119Y884715D01*
G37*
G36*
G01X1452519D02*
X1453326Y886112D01*
X1453295Y886199D01*
G02X1453222Y886627I1225J429D01*
G02X1455818I1298J0D01*
G02X1454762Y885352I-1298J0D01*
G01X1454672Y885335D01*
X1453865Y883938D01*
X1453896Y883851D01*
G02X1453968Y883423I-1225J-426D01*
G02X1451374I-1297J0D01*
G02X1452429Y884698I1298J0D01*
G01X1452519Y884715D01*
G37*
G36*
G01X1459919D02*
X1460726Y886112D01*
X1460695Y886199D01*
G02X1460622Y886627I1225J429D01*
G02X1463218I1298J0D01*
G02X1462162Y885352I-1298J0D01*
G01X1462072Y885335D01*
X1461265Y883938D01*
X1461296Y883851D01*
G02X1461368Y883423I-1225J-426D01*
G02X1458774I-1297J0D01*
G02X1459829Y884698I1298J0D01*
G01X1459919Y884715D01*
G37*
G36*
G01X1467319D02*
X1468126Y886112D01*
X1468095Y886199D01*
G02X1468022Y886627I1225J429D01*
G02X1470618I1298J0D01*
G02X1469562Y885352I-1298J0D01*
G01X1469472Y885335D01*
X1468665Y883938D01*
X1468696Y883851D01*
G02X1468768Y883423I-1225J-426D01*
G02X1466174I-1297J0D01*
G02X1467229Y884698I1298J0D01*
G01X1467319Y884715D01*
G37*
G36*
G01X1505096Y886198D02*
G02X1505024Y886625I1226J426D01*
G01Y886627D01*
G02X1507618I1297J0D01*
G02X1506563Y885352I-1298J0D01*
G01X1506473Y885335D01*
X1505666Y883937D01*
X1505696Y883851D01*
G02X1505768Y883423I-1226J-426D01*
G02X1503174I-1297J0D01*
G02X1504230Y884698I1298J0D01*
G01X1504320Y884715D01*
X1505126Y886112D01*
X1505096Y886198D01*
G37*
G36*
G01X1499575Y871118D02*
X1498768Y872518D01*
X1498678Y872535D01*
G02X1497622Y873810I242J1275D01*
G02X1500218I1298J0D01*
G01Y873808D01*
G02X1500145Y873381I-1298J2D01*
G01X1500115Y873295D01*
X1500921Y871898D01*
X1501011Y871881D01*
G02X1502068Y870606I-240J-1275D01*
G02X1499474I-1297J0D01*
G01Y870607D01*
G02X1499545Y871032I1297J2D01*
G01X1499575Y871118D01*
G37*
G36*
G01X1494025Y880733D02*
X1493219Y882131D01*
X1493129Y882148D01*
G02X1492074Y883423I243J1275D01*
G02X1494668I1297J0D01*
G01Y883421D01*
G02X1494596Y882994I-1298J-1D01*
G01X1494566Y882908D01*
X1495372Y881511D01*
X1495462Y881494D01*
G02X1496518Y880219I-242J-1275D01*
G02X1493922I-1298J0D01*
G02X1493995Y880647I1299J-1D01*
G01X1494025Y880733D01*
G37*
G36*
G01X1501426Y880732D02*
X1500619Y882131D01*
X1500529Y882148D01*
G02X1499474Y883423I243J1275D01*
G02X1502068I1297J0D01*
G01Y883421D01*
G02X1501996Y882994I-1298J-1D01*
G01X1501966Y882908D01*
X1502772Y881511D01*
X1502862Y881494D01*
G02X1503918Y880219I-242J-1275D01*
G02X1501324I-1297J0D01*
G02X1501396Y880646I1297J1D01*
G01X1501426Y880732D01*
G37*
G36*
G01X1506975Y871118D02*
X1506168Y872518D01*
X1506078Y872535D01*
G02X1505022Y873810I242J1275D01*
G02X1507618I1298J0D01*
G01Y873808D01*
G02X1507545Y873381I-1298J2D01*
G01X1507515Y873295D01*
X1508321Y871898D01*
X1508411Y871881D01*
G02X1509468Y870606I-240J-1275D01*
G02X1506874I-1297J0D01*
G01Y870607D01*
G02X1506945Y871032I1297J2D01*
G01X1506975Y871118D01*
G37*
G36*
G01X1487670Y855876D02*
X1488477Y857274D01*
X1488446Y857361D01*
G02X1488374Y857789I1225J426D01*
G02X1490968I1297J0D01*
G02X1489913Y856514I-1298J0D01*
G01X1489823Y856497D01*
X1489015Y855098D01*
X1489045Y855011D01*
G02X1489118Y854584I-1225J-429D01*
G02X1486522I-1298J0D01*
G02X1487580Y855859I1297J0D01*
G01X1487670Y855876D01*
G37*
G36*
G01X1495070D02*
X1495877Y857274D01*
X1495846Y857361D01*
G02X1495774Y857789I1225J426D01*
G02X1498368I1297J0D01*
G02X1497313Y856514I-1298J0D01*
G01X1497223Y856497D01*
X1496415Y855098D01*
X1496445Y855011D01*
G02X1496518Y854584I-1225J-429D01*
G02X1493922I-1298J0D01*
G02X1494980Y855859I1297J0D01*
G01X1495070Y855876D01*
G37*
G36*
G01X1502470D02*
X1503277Y857274D01*
X1503246Y857361D01*
G02X1503174Y857789I1225J426D01*
G02X1505768I1297J0D01*
G02X1504713Y856514I-1298J0D01*
G01X1504623Y856497D01*
X1503815Y855098D01*
X1503845Y855011D01*
G02X1503918Y854584I-1225J-429D01*
G02X1501322I-1298J0D01*
G02X1502380Y855859I1297J0D01*
G01X1502470Y855876D01*
G37*
G36*
G01X1484776Y858302D02*
X1483968Y859701D01*
X1483878Y859718D01*
G02X1482822Y860993I242J1275D01*
G02X1485418I1298J0D01*
G02X1485345Y860564I-1297J0D01*
G01X1485314Y860478D01*
X1486120Y859081D01*
X1486210Y859064D01*
G02X1487268Y857789I-239J-1275D01*
G02X1484674I-1297J0D01*
G02X1484745Y858215I1297J3D01*
G01X1484776Y858302D01*
G37*
G36*
G01X1492176D02*
X1491368Y859701D01*
X1491278Y859718D01*
G02X1490222Y860993I242J1275D01*
G02X1492818I1298J0D01*
G02X1492745Y860564I-1297J0D01*
G01X1492714Y860478D01*
X1493520Y859081D01*
X1493610Y859064D01*
G02X1494668Y857789I-239J-1275D01*
G02X1492074I-1297J0D01*
G02X1492145Y858215I1297J3D01*
G01X1492176Y858302D01*
G37*
G36*
G01X1499576D02*
X1498768Y859701D01*
X1498678Y859718D01*
G02X1497622Y860993I242J1275D01*
G02X1500218I1298J0D01*
G02X1500145Y860564I-1297J0D01*
G01X1500114Y860478D01*
X1500920Y859081D01*
X1501010Y859064D01*
G02X1502068Y857789I-239J-1275D01*
G02X1499474I-1297J0D01*
G02X1499545Y858215I1297J3D01*
G01X1499576Y858302D01*
G37*
G36*
G01X1487670Y868693D02*
X1488477Y870091D01*
X1488446Y870178D01*
G02X1488374Y870606I1225J426D01*
G02X1490968I1297J0D01*
G02X1489913Y869331I-1298J0D01*
G01X1489823Y869314D01*
X1489015Y867915D01*
X1489045Y867828D01*
G02X1489118Y867401I-1225J-429D01*
G02X1486522I-1298J0D01*
G02X1487580Y868676I1297J0D01*
G01X1487670Y868693D01*
G37*
G36*
G01X1495070D02*
X1495877Y870091D01*
X1495846Y870178D01*
G02X1495774Y870606I1225J426D01*
G02X1498368I1297J0D01*
G02X1497313Y869331I-1298J0D01*
G01X1497223Y869314D01*
X1496415Y867915D01*
X1496445Y867828D01*
G02X1496518Y867401I-1225J-429D01*
G02X1493922I-1298J0D01*
G02X1494980Y868676I1297J0D01*
G01X1495070Y868693D01*
G37*
G36*
G01X1502470D02*
X1503277Y870091D01*
X1503246Y870178D01*
G02X1503174Y870606I1225J426D01*
G02X1505768I1297J0D01*
G02X1504713Y869331I-1298J0D01*
G01X1504623Y869314D01*
X1503816Y867916D01*
X1503846Y867829D01*
G02X1503918Y867401I-1225J-426D01*
G02X1501324I-1297J0D01*
G02X1502380Y868676I1298J0D01*
G01X1502470Y868693D01*
G37*
G36*
G01X1484776Y871119D02*
X1483968Y872518D01*
X1483878Y872535D01*
G02X1482822Y873810I242J1275D01*
G02X1485418I1298J0D01*
G02X1485345Y873381I-1297J0D01*
G01X1485314Y873295D01*
X1486120Y871898D01*
X1486210Y871881D01*
G02X1487268Y870606I-239J-1275D01*
G02X1484674I-1297J0D01*
G02X1484745Y871032I1297J3D01*
G01X1484776Y871119D01*
G37*
G36*
G01X1492176D02*
X1491368Y872518D01*
X1491278Y872535D01*
G02X1490222Y873810I242J1275D01*
G02X1492818I1298J0D01*
G02X1492745Y873381I-1297J0D01*
G01X1492714Y873295D01*
X1493520Y871898D01*
X1493610Y871881D01*
G02X1494668Y870606I-239J-1275D01*
G02X1492074I-1297J0D01*
G02X1492145Y871032I1297J3D01*
G01X1492176Y871119D01*
G37*
G36*
G01X1486625Y880734D02*
X1485819Y882131D01*
X1485729Y882148D01*
G02X1484674Y883423I243J1275D01*
G02X1487268I1297J0D01*
G02X1487196Y882994I-1297J-3D01*
G01X1487165Y882908D01*
X1487971Y881511D01*
X1488061Y881494D01*
G02X1489118Y880219I-240J-1275D01*
G02X1486522I-1298J0D01*
G02X1486595Y880647I1298J-1D01*
G01X1486625Y880734D01*
G37*
G36*
G01X1482119Y884715D02*
X1482926Y886112D01*
X1482895Y886199D01*
G02X1482822Y886627I1225J429D01*
G02X1485418I1298J0D01*
G02X1484362Y885352I-1298J0D01*
G01X1484272Y885335D01*
X1483465Y883938D01*
X1483496Y883851D01*
G02X1483568Y883423I-1225J-426D01*
G02X1480974I-1297J0D01*
G02X1482029Y884698I1298J0D01*
G01X1482119Y884715D01*
G37*
G36*
G01X1489519D02*
X1490326Y886112D01*
X1490295Y886199D01*
G02X1490222Y886627I1225J429D01*
G02X1492818I1298J0D01*
G02X1491762Y885352I-1298J0D01*
G01X1491672Y885335D01*
X1490865Y883938D01*
X1490896Y883851D01*
G02X1490968Y883423I-1225J-426D01*
G02X1488374I-1297J0D01*
G02X1489429Y884698I1298J0D01*
G01X1489519Y884715D01*
G37*
G36*
G01X1496919D02*
X1497726Y886112D01*
X1497695Y886199D01*
G02X1497622Y886627I1225J429D01*
G02X1500218I1298J0D01*
G02X1499162Y885352I-1298J0D01*
G01X1499072Y885335D01*
X1498265Y883938D01*
X1498296Y883851D01*
G02X1498368Y883423I-1225J-426D01*
G02X1495774I-1297J0D01*
G02X1496829Y884698I1298J0D01*
G01X1496919Y884715D01*
G37*
G36*
G01X1452952Y1122739D02*
X1453759Y1124136D01*
X1453728Y1124223D01*
G02X1453656Y1124651I1225J426D01*
G02X1456250I1297J0D01*
G02X1455195Y1123376I-1298J0D01*
G01X1455105Y1123359D01*
X1454298Y1121962D01*
X1454329Y1121875D01*
G02X1454402Y1121447I-1225J-429D01*
G02X1451806I-1298J0D01*
G02X1452862Y1122722I1298J0D01*
G01X1452952Y1122739D01*
G37*
G36*
G01X1460352D02*
X1461159Y1124136D01*
X1461128Y1124223D01*
G02X1461056Y1124651I1225J426D01*
G02X1463650I1297J0D01*
G02X1462595Y1123376I-1298J0D01*
G01X1462505Y1123359D01*
X1461698Y1121962D01*
X1461729Y1121875D01*
G02X1461802Y1121447I-1225J-429D01*
G02X1459206I-1298J0D01*
G02X1460262Y1122722I1298J0D01*
G01X1460352Y1122739D01*
G37*
G36*
G01X1467752D02*
X1468559Y1124136D01*
X1468528Y1124223D01*
G02X1468456Y1124651I1225J426D01*
G02X1471050I1297J0D01*
G02X1469995Y1123376I-1298J0D01*
G01X1469905Y1123359D01*
X1469098Y1121962D01*
X1469129Y1121875D01*
G02X1469202Y1121447I-1225J-429D01*
G02X1466606I-1298J0D01*
G02X1467662Y1122722I1298J0D01*
G01X1467752Y1122739D01*
G37*
G36*
G01X1475152D02*
X1475959Y1124136D01*
X1475928Y1124223D01*
G02X1475856Y1124651I1225J426D01*
G02X1478450I1297J0D01*
G02X1477395Y1123376I-1298J0D01*
G01X1477305Y1123359D01*
X1476498Y1121962D01*
X1476529Y1121875D01*
G02X1476602Y1121447I-1225J-429D01*
G02X1474006I-1298J0D01*
G02X1475062Y1122722I1298J0D01*
G01X1475152Y1122739D01*
G37*
G36*
G01X1482552D02*
X1483359Y1124136D01*
X1483328Y1124223D01*
G02X1483256Y1124651I1225J426D01*
G02X1485850I1297J0D01*
G02X1484795Y1123376I-1298J0D01*
G01X1484705Y1123359D01*
X1483898Y1121962D01*
X1483929Y1121875D01*
G02X1484002Y1121447I-1225J-429D01*
G02X1481406I-1298J0D01*
G02X1482462Y1122722I1298J0D01*
G01X1482552Y1122739D01*
G37*
G36*
G01X1489952D02*
X1490759Y1124136D01*
X1490728Y1124223D01*
G02X1490656Y1124651I1225J426D01*
G02X1493250I1297J0D01*
G02X1492195Y1123376I-1298J0D01*
G01X1492105Y1123359D01*
X1491298Y1121962D01*
X1491329Y1121875D01*
G02X1491402Y1121447I-1225J-429D01*
G02X1488806I-1298J0D01*
G02X1489862Y1122722I1298J0D01*
G01X1489952Y1122739D01*
G37*
G36*
G01X1497352D02*
X1498159Y1124136D01*
X1498128Y1124223D01*
G02X1498056Y1124651I1225J426D01*
G02X1500650I1297J0D01*
G02X1499595Y1123376I-1298J0D01*
G01X1499505Y1123359D01*
X1498698Y1121962D01*
X1498729Y1121875D01*
G02X1498802Y1121447I-1225J-429D01*
G02X1496206I-1298J0D01*
G02X1497262Y1122722I1298J0D01*
G01X1497352Y1122739D01*
G37*
G36*
G01X1457459Y1125166D02*
X1456652Y1126564D01*
X1456562Y1126581D01*
G02X1455506Y1127856I242J1275D01*
G02X1458102I1298J0D01*
G02X1458029Y1127427I-1297J0D01*
G01X1457998Y1127341D01*
X1458805Y1125943D01*
X1458895Y1125926D01*
G02X1459950Y1124651I-243J-1275D01*
G02X1457356I-1297J0D01*
G02X1457428Y1125080I1297J3D01*
G01X1457459Y1125166D01*
G37*
G36*
G01X1464859D02*
X1464052Y1126564D01*
X1463962Y1126581D01*
G02X1462906Y1127856I242J1275D01*
G02X1465502I1298J0D01*
G02X1465429Y1127427I-1297J0D01*
G01X1465398Y1127341D01*
X1466205Y1125943D01*
X1466295Y1125926D01*
G02X1467350Y1124651I-243J-1275D01*
G02X1464756I-1297J0D01*
G02X1464828Y1125080I1297J3D01*
G01X1464859Y1125166D01*
G37*
G36*
G01X1472259D02*
X1471452Y1126564D01*
X1471362Y1126581D01*
G02X1470306Y1127856I242J1275D01*
G02X1472902I1298J0D01*
G02X1472829Y1127427I-1297J0D01*
G01X1472798Y1127341D01*
X1473605Y1125943D01*
X1473695Y1125926D01*
G02X1474750Y1124651I-243J-1275D01*
G02X1472156I-1297J0D01*
G02X1472228Y1125080I1297J3D01*
G01X1472259Y1125166D01*
G37*
G36*
G01X1479659D02*
X1478852Y1126564D01*
X1478762Y1126581D01*
G02X1477706Y1127856I242J1275D01*
G02X1480302I1298J0D01*
G02X1480229Y1127427I-1297J0D01*
G01X1480198Y1127341D01*
X1481005Y1125943D01*
X1481095Y1125926D01*
G02X1482150Y1124651I-243J-1275D01*
G02X1479556I-1297J0D01*
G02X1479628Y1125080I1297J3D01*
G01X1479659Y1125166D01*
G37*
G36*
G01X1487059D02*
X1486252Y1126564D01*
X1486162Y1126581D01*
G02X1485106Y1127856I242J1275D01*
G02X1487702I1298J0D01*
G02X1487629Y1127427I-1297J0D01*
G01X1487598Y1127341D01*
X1488405Y1125943D01*
X1488495Y1125926D01*
G02X1489550Y1124651I-243J-1275D01*
G02X1486956I-1297J0D01*
G02X1487028Y1125080I1297J3D01*
G01X1487059Y1125166D01*
G37*
G36*
G01X1494459D02*
X1493652Y1126564D01*
X1493562Y1126581D01*
G02X1492506Y1127856I242J1275D01*
G02X1495102I1298J0D01*
G02X1495029Y1127427I-1297J0D01*
G01X1494998Y1127341D01*
X1495805Y1125943D01*
X1495895Y1125926D01*
G02X1496950Y1124651I-243J-1275D01*
G02X1494356I-1297J0D01*
G02X1494428Y1125080I1297J3D01*
G01X1494459Y1125166D01*
G37*
G36*
G01X1501859D02*
X1501052Y1126564D01*
X1500962Y1126581D01*
G02X1499906Y1127856I242J1275D01*
G02X1502502I1298J0D01*
G02X1502429Y1127427I-1297J0D01*
G01X1502398Y1127341D01*
X1503205Y1125943D01*
X1503295Y1125926D01*
G02X1504350Y1124651I-243J-1275D01*
G02X1501756I-1297J0D01*
G02X1501828Y1125080I1297J3D01*
G01X1501859Y1125166D01*
G37*
G54D100*
X1290005Y293768D03*
G54D88*
X93547Y692260D03*
X1455787Y1421784D03*
X1710550Y691327D03*
G54D92*
X174685Y637367D03*
X174393Y668511D03*
G54D95*
X1565236Y184783D03*
Y264035D03*
G54D96*
X1405118Y112008D03*
G54D75*
X1380522Y261936D03*
X1388754Y255503D03*
X1380638Y247394D03*
X1386630Y240351D03*
X1031950Y385471D03*
X968286Y482241D03*
X944032Y435931D03*
G54D99*
X1247638Y269488D03*
G54D97*
X306771Y991220D03*
X531240Y811122D03*
X525275Y1171319D03*
X356062D03*
X574566Y991220D03*
X1282913D03*
X1326240Y811122D03*
X1332204Y1171319D03*
X1501417D03*
X1507381Y811122D03*
X1550708Y991220D03*
G54D74*
X1386273Y270370D03*
X615573Y178034D03*
X628195Y174214D03*
X941059Y426211D03*
X1407029Y154432D03*
X1282645Y253971D03*
G54D93*
X322500Y1391830D03*
X537477Y1395413D03*
X1298642Y1391830D03*
X1513618Y1395413D03*
G54D94*
X704185Y277236D03*
X177413Y277208D03*
X1153555D03*
%LPC*%
G75*
G36*
G01X307246Y1374027D02*
X325476D01*
X326274Y1373229D01*
X326290Y1373189D01*
G03X326294Y1373179I466J181D01*
G01X326309Y1373142D01*
Y1367927D01*
X317918Y1359537D01*
G03X317772Y1359185I354J-353D01*
G01Y1351160D01*
G03X317918Y1350808I500J1D01*
G01X318590Y1350136D01*
G03X318942Y1349990I353J354D01*
G01X333342D01*
G03X333694Y1350136I-1J500D01*
G01X335419Y1351862D01*
X348596D01*
X352709Y1347749D01*
Y1340040D01*
X350243Y1337575D01*
G03X350097Y1337223I354J-353D01*
G01Y1327978D01*
G03X350243Y1327626I500J1D01*
G01X350541Y1327328D01*
G03X350893Y1327182I353J354D01*
G01X365363D01*
G03X365715Y1327328I-1J500D01*
G01X366181Y1327794D01*
G03X366327Y1328146I-354J353D01*
G01Y1335949D01*
X367024Y1336646D01*
X383374D01*
X385781Y1334239D01*
Y1326661D01*
X382282Y1323163D01*
G03X382136Y1322811I354J-353D01*
G01Y1314682D01*
G03X382282Y1314330I500J1D01*
G01X382783Y1313829D01*
G03X383135Y1313683I353J354D01*
G01X397105D01*
G03X397457Y1313829I-1J500D01*
G01X397964Y1314336D01*
G03X398110Y1314688I-354J353D01*
G01Y1320655D01*
G03X398399Y1321691I-1712J1036D01*
G03X398136Y1322682I-2002J-1D01*
G01X398110Y1322729D01*
Y1323553D01*
X398136Y1323600D01*
G03X398399Y1324591I-1739J992D01*
G03X398136Y1325582I-2002J-1D01*
G01X398110Y1325629D01*
Y1326453D01*
X398136Y1326500D01*
G03X398399Y1327491I-1739J992D01*
G03X398110Y1328527I-2001J0D01*
G01Y1333403D01*
X401481Y1336774D01*
X416025D01*
X417431Y1335368D01*
Y1326335D01*
X414405Y1323310D01*
G03X414259Y1322958I354J-353D01*
G01Y1314709D01*
G03X414405Y1314357I500J1D01*
G01X414940Y1313822D01*
G03X415292Y1313676I353J354D01*
G01X429425D01*
G03X429777Y1313822I-1J500D01*
G01X430504Y1314549D01*
G03X430650Y1314901I-354J353D01*
G01Y1328067D01*
G03X430504Y1328419I-500J-1D01*
G01X429655Y1329267D01*
Y1332822D01*
X433514Y1336681D01*
X447510D01*
X449010Y1335181D01*
Y1325616D01*
X446617Y1323224D01*
G03X446471Y1322872I354J-353D01*
G01Y1314616D01*
G03X446617Y1314264I500J1D01*
G01X447056Y1313825D01*
G03X447408Y1313679I353J354D01*
G01X461522D01*
G03X461874Y1313825I-1J500D01*
G01X462463Y1314414D01*
G03X462609Y1314766I-354J353D01*
G01Y1321264D01*
X462613Y1321284D01*
G03X462655Y1321691I-1960J408D01*
G03X462613Y1322098I-2002J-1D01*
G01X462609Y1322118D01*
Y1324164D01*
X462613Y1324184D01*
G03X462655Y1324591I-1960J408D01*
G03X462613Y1324998I-2002J-1D01*
G01X462609Y1325018D01*
Y1327064D01*
X462613Y1327084D01*
G03X462655Y1327491I-1960J408D01*
G03X462613Y1327898I-2002J-1D01*
G01X462609Y1327918D01*
Y1333968D01*
X465957Y1337316D01*
X479556D01*
X481315Y1335557D01*
Y1326017D01*
X478672Y1323375D01*
G03X478526Y1323023I354J-353D01*
G01Y1314616D01*
G03X478672Y1314264I500J1D01*
G01X479115Y1313821D01*
G03X479467Y1313675I353J354D01*
G01X493674D01*
G03X494026Y1313821I-1J500D01*
G01X494652Y1314447D01*
G03X494798Y1314799I-354J353D01*
G01Y1322050D01*
X494805Y1322077D01*
G03X494880Y1322618I-1927J543D01*
G03X494805Y1323159I-2002J-2D01*
G01X494798Y1323186D01*
Y1324950D01*
X494805Y1324977D01*
G03X494880Y1325518I-1927J543D01*
G03X494805Y1326059I-2002J-2D01*
G01X494798Y1326086D01*
Y1327850D01*
X494805Y1327877D01*
G03X494880Y1328418I-1927J543D01*
G03X494805Y1328959I-2002J-2D01*
G01X494798Y1328986D01*
Y1348099D01*
X497440Y1350741D01*
X510830D01*
X513564Y1348007D01*
Y1341917D01*
X510842Y1339196D01*
G03X510696Y1338844I354J-353D01*
G01Y1327861D01*
G03X510842Y1327509I500J1D01*
G01X511114Y1327237D01*
G03X511466Y1327091I353J354D01*
G01X525796D01*
G03X526148Y1327237I-1J500D01*
G01X527231Y1328320D01*
G03X527377Y1328672I-354J353D01*
G01Y1370120D01*
X529046Y1371789D01*
X544276D01*
X545066Y1370999D01*
Y1362358D01*
X542971Y1360264D01*
G03X542825Y1359912I354J-353D01*
G01Y1350571D01*
X542375Y1350121D01*
X537011D01*
G03X536304Y1349828I0J-999D01*
G01X533590Y1347114D01*
G03X533297Y1346407I706J-707D01*
G01Y1345963D01*
X533288Y1345934D01*
G03X533230Y1345539I1309J-394D01*
G03X533288Y1345144I1367J-1D01*
G01X533297Y1345115D01*
Y1342856D01*
X533288Y1342827D01*
G03X533230Y1342432I1309J-394D01*
G03X533288Y1342037I1367J-1D01*
G01X533297Y1342008D01*
Y1322918D01*
X528506Y1318127D01*
X503305D01*
G03X502598Y1317834I0J-999D01*
G01X500320Y1315556D01*
G03X500027Y1314849I706J-707D01*
G01Y1306116D01*
X498778Y1304867D01*
X492360D01*
X492346Y1304869D01*
G03X492155Y1304882I-190J-1389D01*
G03X491964Y1304869I-1J-1402D01*
G01X491950Y1304867D01*
X489760D01*
X489746Y1304869D01*
G03X489555Y1304882I-190J-1389D01*
G03X489364Y1304869I-1J-1402D01*
G01X489350Y1304867D01*
X462013D01*
G03X459841I-1086J-888D01*
G01X459413D01*
G03X457241I-1086J-888D01*
G01X428104D01*
X428090Y1304869D01*
G03X427899Y1304882I-190J-1389D01*
G03X427708Y1304869I-1J-1402D01*
G01X427694Y1304867D01*
X425504D01*
X425490Y1304869D01*
G03X425299Y1304882I-190J-1389D01*
G03X425108Y1304869I-1J-1402D01*
G01X425094Y1304867D01*
X395976D01*
X395962Y1304869D01*
G03X395771Y1304882I-190J-1389D01*
G03X395580Y1304869I-1J-1402D01*
G01X395566Y1304867D01*
X393376D01*
X393362Y1304869D01*
G03X393171Y1304882I-190J-1389D01*
G03X392980Y1304869I-1J-1402D01*
G01X392966Y1304867D01*
X367530D01*
X362137Y1310260D01*
G02X362114Y1310801I283J283D01*
G03X362445Y1311706I-1072J905D01*
G03X362014Y1312717I-1401J0D01*
G02Y1313295I277J289D01*
G03X362445Y1314306I-970J1011D01*
G03X361259Y1315691I-1402J0D01*
G02X361090Y1315877I31J198D01*
G03X360799Y1316527I-998J-57D01*
G01X359434Y1317892D01*
G03X358727Y1318185I-707J-706D01*
G01X338017D01*
X330159Y1326043D01*
X330210Y1326167D01*
G03X330317Y1326704I-1294J537D01*
G03X329823Y1327773I-1402J1D01*
G01X329752Y1327833D01*
Y1328175D01*
X329823Y1328235D01*
G03X330317Y1329304I-908J1068D01*
G03X329823Y1330373I-1402J1D01*
G01X329752Y1330433D01*
Y1330775D01*
X329823Y1330835D01*
G03X330317Y1331904I-908J1068D01*
G03X329823Y1332973I-1402J1D01*
G01X329752Y1333033D01*
Y1333375D01*
X329823Y1333435D01*
G03X330317Y1334504I-908J1068D01*
G03X329823Y1335573I-1402J1D01*
G01X329752Y1335633D01*
Y1335975D01*
X329823Y1336035D01*
G03X330317Y1337104I-908J1068D01*
G03X329751Y1338230I-1403J0D01*
G03X329459Y1338991I-998J54D01*
G01X327965Y1340485D01*
G03X327258Y1340778I-707J-706D01*
G01X304406D01*
X301260Y1343924D01*
Y1368041D01*
X307246Y1374027D01*
G37*
G36*
G01X456144Y1384372D02*
X472356D01*
X478785Y1377943D01*
G03X479492Y1377650I707J706D01*
G01X549640D01*
X562781Y1364509D01*
Y1350728D01*
X562174Y1350121D01*
X544231D01*
X543826Y1350525D01*
Y1359703D01*
X546068Y1361943D01*
Y1371414D01*
X544691Y1372790D01*
X528631D01*
X526376Y1370535D01*
Y1336027D01*
X526375Y1336025D01*
Y1335982D01*
Y1335939D01*
X526376Y1335937D01*
Y1328881D01*
X525587Y1328092D01*
X511698D01*
Y1338635D01*
X514566Y1341502D01*
Y1348422D01*
X513109Y1349878D01*
X513096Y1349933D01*
G03X511614Y1351415I-1947J-465D01*
G01X511559Y1351428D01*
X511245Y1351742D01*
X497025D01*
X493796Y1348514D01*
Y1315008D01*
X493465Y1314676D01*
X479676D01*
X479528Y1314825D01*
Y1322814D01*
X482316Y1325602D01*
Y1335972D01*
X479971Y1338318D01*
X465542D01*
X461608Y1334383D01*
Y1314975D01*
X461313Y1314680D01*
X447617D01*
X447472Y1314825D01*
Y1322663D01*
X450012Y1325201D01*
Y1335596D01*
X448677Y1336930D01*
X448665Y1336951D01*
G03X447967Y1337649I-1721J-1023D01*
G01X447946Y1337661D01*
X447925Y1337682D01*
X447909D01*
X447866Y1337705D01*
G03X446944Y1337930I-922J-1777D01*
G03X445980Y1337682I1J-2002D01*
G01X435940D01*
G03X434983Y1337926I-958J-1758D01*
G03X434068Y1337705I-1J-2002D01*
G01X434025Y1337682D01*
X433099D01*
X428654Y1333237D01*
Y1328852D01*
X429648Y1327858D01*
Y1315110D01*
X429216Y1314678D01*
X415501D01*
X415260Y1314918D01*
Y1322749D01*
X418432Y1325920D01*
Y1335783D01*
X417991Y1336225D01*
X417976Y1336265D01*
G03X416796Y1337445I-1877J-697D01*
G01X416756Y1337460D01*
X416440Y1337776D01*
X403981D01*
X403943Y1337793D01*
G03X403130Y1337965I-812J-1830D01*
G03X402317Y1337793I-1J-2002D01*
G01X402279Y1337776D01*
X401066D01*
X397108Y1333818D01*
Y1314897D01*
X396896Y1314684D01*
X383344D01*
X383138Y1314891D01*
Y1322602D01*
X386782Y1326246D01*
Y1334654D01*
X383789Y1337648D01*
X371807D01*
G03X370874Y1337878I-932J-1772D01*
G03X369941Y1337648I-1J-2002D01*
G01X366609D01*
X365326Y1336364D01*
Y1328355D01*
X365154Y1328184D01*
X351102D01*
X351098Y1328187D01*
Y1337014D01*
X353710Y1339625D01*
Y1348164D01*
X352429Y1349445D01*
X352416Y1349500D01*
G03X350940Y1350976I-1946J-470D01*
G01X350885Y1350989D01*
X349011Y1352864D01*
X335004D01*
X333133Y1350992D01*
X319151D01*
X318774Y1351369D01*
Y1358976D01*
X327310Y1367512D01*
Y1373217D01*
X328121Y1374027D01*
X337925D01*
G03X338632Y1374320I0J999D01*
G01X347862Y1383550D01*
X376941D01*
X378661Y1381830D01*
X378643Y1381728D01*
G03X378623Y1381490I1382J-236D01*
G03X380025Y1380088I1402J0D01*
G03X380263Y1380108I2J1402D01*
G01X380365Y1380126D01*
X384025Y1376466D01*
G03X384732Y1376173I707J706D01*
G01X447531D01*
G03X448238Y1376466I0J999D01*
G01X456144Y1384372D01*
G37*
G36*
G01X1283387Y1374026D02*
X1301617D01*
X1302415Y1373228D01*
X1302431Y1373188D01*
G03X1302435Y1373178I466J181D01*
G01X1302450Y1373141D01*
Y1367926D01*
X1294059Y1359536D01*
G03X1293913Y1359184I354J-353D01*
G01Y1351159D01*
G03X1294059Y1350807I500J1D01*
G01X1294731Y1350135D01*
G03X1295083Y1349989I353J354D01*
G01X1309483D01*
G03X1309835Y1350135I-1J500D01*
G01X1311560Y1351861D01*
X1324737D01*
X1328850Y1347748D01*
Y1340039D01*
X1326384Y1337574D01*
G03X1326238Y1337222I354J-353D01*
G01Y1327977D01*
G03X1326384Y1327625I500J1D01*
G01X1326682Y1327327D01*
G03X1327034Y1327181I353J354D01*
G01X1341004D01*
G03X1341356Y1327327I-1J500D01*
G01X1341822Y1327793D01*
G03X1341968Y1328145I-354J353D01*
G01Y1333888D01*
G03Y1335818I-1753J965D01*
G01Y1335948D01*
X1342665Y1336645D01*
X1359515D01*
X1361922Y1334238D01*
Y1326660D01*
X1358423Y1323162D01*
G03X1358277Y1322810I354J-353D01*
G01Y1314681D01*
G03X1358423Y1314329I500J1D01*
G01X1358924Y1313828D01*
G03X1359276Y1313682I353J354D01*
G01X1373246D01*
G03X1373598Y1313828I-1J500D01*
G01X1374105Y1314335D01*
G03X1374251Y1314687I-354J353D01*
G01Y1320655D01*
G03X1374540Y1321691I-1712J1036D01*
G03X1374277Y1322682I-2002J-1D01*
G01X1374251Y1322729D01*
Y1323553D01*
X1374277Y1323600D01*
G03X1374540Y1324591I-1739J992D01*
G03X1374277Y1325582I-2002J-1D01*
G01X1374251Y1325629D01*
Y1326453D01*
X1374277Y1326500D01*
G03X1374540Y1327491I-1739J992D01*
G03X1374251Y1328527I-2001J0D01*
G01Y1333402D01*
X1377622Y1336773D01*
X1392166D01*
X1393572Y1335367D01*
Y1326334D01*
X1390546Y1323309D01*
G03X1390400Y1322957I354J-353D01*
G01Y1314708D01*
G03X1390546Y1314356I500J1D01*
G01X1391081Y1313821D01*
G03X1391433Y1313675I353J354D01*
G01X1405566D01*
G03X1405918Y1313821I-1J500D01*
G01X1406645Y1314548D01*
G03X1406791Y1314900I-354J353D01*
G01Y1328066D01*
G03X1406645Y1328418I-500J-1D01*
G01X1405796Y1329266D01*
Y1332821D01*
X1409655Y1336680D01*
X1423651D01*
X1425151Y1335180D01*
Y1325615D01*
X1422758Y1323223D01*
G03X1422612Y1322871I354J-353D01*
G01Y1314615D01*
G03X1422758Y1314263I500J1D01*
G01X1423197Y1313824D01*
G03X1423549Y1313678I353J354D01*
G01X1437663D01*
G03X1438015Y1313824I-1J500D01*
G01X1438604Y1314413D01*
G03X1438750Y1314765I-354J353D01*
G01Y1321264D01*
X1438754Y1321284D01*
G03X1438796Y1321691I-1960J408D01*
G03X1438754Y1322098I-2002J-1D01*
G01X1438750Y1322118D01*
Y1324164D01*
X1438754Y1324184D01*
G03X1438796Y1324591I-1960J408D01*
G03X1438754Y1324998I-2002J-1D01*
G01X1438750Y1325018D01*
Y1327064D01*
X1438754Y1327084D01*
G03X1438796Y1327491I-1960J408D01*
G03X1438754Y1327898I-2002J-1D01*
G01X1438750Y1327918D01*
Y1333967D01*
X1442098Y1337315D01*
X1455697D01*
X1457456Y1335556D01*
Y1326016D01*
X1454813Y1323374D01*
G03X1454667Y1323022I354J-353D01*
G01Y1314615D01*
G03X1454813Y1314263I500J1D01*
G01X1455256Y1313820D01*
G03X1455608Y1313674I353J354D01*
G01X1469815D01*
G03X1470167Y1313820I-1J500D01*
G01X1470793Y1314446D01*
G03X1470939Y1314798I-354J353D01*
G01Y1322050D01*
X1470946Y1322077D01*
G03X1471021Y1322618I-1927J543D01*
G03X1470946Y1323159I-2002J-2D01*
G01X1470939Y1323186D01*
Y1324950D01*
X1470946Y1324977D01*
G03X1471021Y1325518I-1927J543D01*
G03X1470946Y1326059I-2002J-2D01*
G01X1470939Y1326086D01*
Y1327850D01*
X1470946Y1327877D01*
G03X1471021Y1328418I-1927J543D01*
G03X1470946Y1328959I-2002J-2D01*
G01X1470939Y1328986D01*
Y1348098D01*
X1473581Y1350740D01*
X1486971D01*
X1489705Y1348006D01*
Y1341916D01*
X1486983Y1339195D01*
G03X1486837Y1338843I354J-353D01*
G01Y1327860D01*
G03X1486983Y1327508I500J1D01*
G01X1487255Y1327236D01*
G03X1487607Y1327090I353J354D01*
G01X1501937D01*
G03X1502289Y1327236I-1J500D01*
G01X1503372Y1328319D01*
G03X1503518Y1328671I-354J353D01*
G01Y1370119D01*
X1505187Y1371788D01*
X1520417D01*
X1521207Y1370998D01*
Y1362357D01*
X1519112Y1360263D01*
G03X1518966Y1359911I354J-353D01*
G01Y1350570D01*
X1518516Y1350120D01*
X1513152D01*
G03X1512445Y1349827I0J-999D01*
G01X1509731Y1347113D01*
G03X1509438Y1346406I706J-707D01*
G01Y1345963D01*
X1509429Y1345934D01*
G03X1509371Y1345539I1309J-394D01*
G03X1509429Y1345144I1367J-1D01*
G01X1509438Y1345115D01*
Y1342856D01*
X1509429Y1342827D01*
G03X1509371Y1342432I1309J-394D01*
G03X1509429Y1342037I1367J-1D01*
G01X1509438Y1342008D01*
Y1322917D01*
X1504647Y1318126D01*
X1479446D01*
G03X1478739Y1317833I0J-999D01*
G01X1476461Y1315555D01*
G03X1476168Y1314848I706J-707D01*
G01Y1306115D01*
X1474919Y1304866D01*
X1468508D01*
X1468494Y1304868D01*
G03X1468296Y1304882I-198J-1388D01*
G03X1468098Y1304868I0J-1402D01*
G01X1468084Y1304866D01*
X1465908D01*
X1465894Y1304868D01*
G03X1465696Y1304882I-198J-1388D01*
G03X1465498Y1304868I0J-1402D01*
G01X1465484Y1304866D01*
X1438411D01*
G03X1437182Y1305593I-1229J-675D01*
G03X1436171Y1305162I0J-1401D01*
G02X1435593I-289J277D01*
G03X1434582Y1305593I-1011J-970D01*
G03X1433353Y1304866I0J-1402D01*
G01X1404252D01*
X1404238Y1304868D01*
G03X1404040Y1304882I-198J-1388D01*
G03X1403842Y1304868I0J-1402D01*
G01X1403828Y1304866D01*
X1401652D01*
X1401638Y1304868D01*
G03X1401440Y1304882I-198J-1388D01*
G03X1401242Y1304868I0J-1402D01*
G01X1401228Y1304866D01*
X1372124D01*
X1372110Y1304868D01*
G03X1371912Y1304882I-198J-1388D01*
G03X1371714Y1304868I0J-1402D01*
G01X1371700Y1304866D01*
X1369524D01*
X1369510Y1304868D01*
G03X1369312Y1304882I-198J-1388D01*
G03X1369114Y1304868I0J-1402D01*
G01X1369100Y1304866D01*
X1343671D01*
X1338277Y1310260D01*
G02X1338255Y1310801I283J282D01*
G03X1338586Y1311706I-1072J905D01*
G03X1338155Y1312717I-1401J0D01*
G02Y1313295I277J289D01*
G03X1338586Y1314306I-970J1011D01*
G03X1337400Y1315691I-1402J0D01*
G02X1337231Y1315877I31J198D01*
G03X1336940Y1316526I-998J-58D01*
G01X1335575Y1317891D01*
G03X1334868Y1318184I-707J-706D01*
G01X1314158D01*
X1306299Y1326043D01*
X1306351Y1326166D01*
G03X1306458Y1326704I-1295J537D01*
G03X1305964Y1327773I-1402J1D01*
G01X1305893Y1327833D01*
Y1328175D01*
X1305964Y1328235D01*
G03X1306458Y1329304I-908J1068D01*
G03X1305964Y1330373I-1402J1D01*
G01X1305893Y1330433D01*
Y1330775D01*
X1305964Y1330835D01*
G03X1306458Y1331904I-908J1068D01*
G03X1305964Y1332973I-1402J1D01*
G01X1305893Y1333033D01*
Y1333375D01*
X1305964Y1333435D01*
G03X1306458Y1334504I-908J1068D01*
G03X1305964Y1335573I-1402J1D01*
G01X1305893Y1335633D01*
Y1335975D01*
X1305964Y1336035D01*
G03X1306458Y1337104I-908J1068D01*
G03X1305892Y1338230I-1403J0D01*
G03X1305600Y1338990I-998J53D01*
G01X1304106Y1340484D01*
G03X1303399Y1340777I-707J-706D01*
G01X1281303D01*
G03X1280135Y1341404I-1168J-774D01*
G03X1280024Y1341400I-5J-1402D01*
G01X1279932Y1341392D01*
X1277401Y1343923D01*
Y1361472D01*
X1277518Y1361526D01*
G03Y1364256I-627J1365D01*
G01X1277401Y1364310D01*
Y1368040D01*
X1283387Y1374026D01*
G37*
G36*
G01X1431874Y1384632D02*
X1448216D01*
X1454875Y1377973D01*
G03X1455582Y1377680I707J706D01*
G01X1525750D01*
X1537406Y1366024D01*
X1537358Y1365902D01*
G03X1537255Y1365355I1399J-547D01*
G03X1538726Y1363853I1502J0D01*
G02X1538922Y1363653I-4J-200D01*
G01Y1350727D01*
X1538315Y1350120D01*
X1520372D01*
X1519968Y1350524D01*
Y1359702D01*
X1522208Y1361942D01*
Y1371413D01*
X1520832Y1372790D01*
X1504772D01*
X1502516Y1370534D01*
Y1336025D01*
Y1335982D01*
Y1328880D01*
X1501728Y1328092D01*
X1487838D01*
Y1338634D01*
X1490706Y1341501D01*
Y1348421D01*
X1489308Y1349819D01*
X1489294Y1349865D01*
G03X1487993Y1351166I-1908J-607D01*
G01X1487947Y1351180D01*
X1487386Y1351742D01*
X1473166D01*
X1469938Y1348513D01*
Y1315007D01*
X1469606Y1314676D01*
X1455817D01*
X1455668Y1314824D01*
Y1322813D01*
X1458458Y1325601D01*
Y1335971D01*
X1456112Y1338316D01*
X1441683D01*
X1437748Y1334382D01*
Y1314974D01*
X1437454Y1314680D01*
X1423758D01*
X1423614Y1314824D01*
Y1322662D01*
X1426152Y1325200D01*
Y1335595D01*
X1425501Y1336247D01*
X1425486Y1336281D01*
G03X1424469Y1337298I-1830J-813D01*
G01X1424435Y1337313D01*
X1424066Y1337682D01*
X1412083D01*
G03X1411124Y1337926I-958J-1758D01*
G03X1410207Y1337704I-1J-2002D01*
G01X1410164Y1337682D01*
X1409240D01*
X1404794Y1333236D01*
Y1328851D01*
X1405790Y1327857D01*
Y1315109D01*
X1405357Y1314676D01*
X1391642D01*
X1391402Y1314917D01*
Y1322748D01*
X1394574Y1325919D01*
Y1335782D01*
X1393922Y1336433D01*
X1393907Y1336467D01*
G03X1392885Y1337489I-1831J-809D01*
G01X1392851Y1337504D01*
X1392581Y1337774D01*
X1380124D01*
X1380086Y1337792D01*
G03X1379271Y1337965I-814J-1829D01*
G03X1378456Y1337792I-1J-2002D01*
G01X1378418Y1337774D01*
X1377207D01*
X1373250Y1333817D01*
Y1314896D01*
X1373037Y1314684D01*
X1359485D01*
X1359278Y1314890D01*
Y1322601D01*
X1362924Y1326245D01*
Y1334653D01*
X1359930Y1337646D01*
X1347950D01*
G03X1347015Y1337878I-935J-1770D01*
G03X1346080Y1337646I0J-2002D01*
G01X1342250D01*
X1340966Y1336363D01*
Y1328354D01*
X1340795Y1328182D01*
X1327243D01*
X1327240Y1328186D01*
Y1337013D01*
X1329852Y1339624D01*
Y1348163D01*
X1329186Y1348829D01*
X1329193Y1348920D01*
G03X1329198Y1349068I-1997J142D01*
G03X1327196Y1351070I-2002J0D01*
G03X1327048Y1351065I-6J-2002D01*
G01X1326957Y1351058D01*
X1325152Y1352862D01*
X1311145D01*
X1309274Y1350990D01*
X1295292D01*
X1294914Y1351368D01*
Y1352413D01*
X1294915Y1352418D01*
G03X1294918Y1352531I-1999J110D01*
G03X1294915Y1352644I-2002J3D01*
G01X1294914Y1352649D01*
Y1358013D01*
X1294915Y1358018D01*
G03X1294918Y1358131I-1999J110D01*
G03X1294915Y1358244I-2002J3D01*
G01X1294914Y1358249D01*
Y1358975D01*
X1303452Y1367511D01*
Y1373216D01*
X1304262Y1374026D01*
X1314066D01*
G03X1314773Y1374319I0J999D01*
G01X1324003Y1383549D01*
X1353082D01*
X1360166Y1376465D01*
G03X1360873Y1376172I707J706D01*
G01X1423000D01*
G03X1423707Y1376465I0J999D01*
G01X1431874Y1384632D01*
G37*
%LPD*%
G75*
G54D20*
X40120Y1287664D03*
X69820D03*
X99520D03*
X129220Y1000853D03*
Y1287664D03*
X158920Y1000853D03*
Y1287664D03*
X188620Y1000853D03*
Y1287664D03*
X218320Y1000853D03*
Y1287664D03*
X248020Y744554D03*
Y1000853D03*
Y1287664D03*
X633320Y744554D03*
Y1000853D03*
Y1287664D03*
X663020Y744554D03*
Y1000853D03*
Y1287664D03*
X692720Y744554D03*
Y1000853D03*
Y1287664D03*
X722420Y744554D03*
Y1287664D03*
X752120Y744554D03*
Y1287664D03*
X781820Y744554D03*
Y1287664D03*
X811520Y744554D03*
Y1287664D03*
X841220Y744554D03*
Y1287664D03*
X1016262Y744554D03*
Y1287664D03*
X1045962Y744554D03*
Y1287664D03*
X1075662Y744554D03*
Y1287664D03*
X1105362Y744554D03*
Y1287664D03*
X1135062Y744554D03*
Y1000853D03*
Y1287664D03*
X1164762Y744554D03*
Y1000853D03*
Y1287664D03*
X1194462Y744554D03*
Y1000853D03*
Y1287664D03*
X1224162Y744554D03*
Y1000853D03*
Y1287664D03*
X1609462Y744554D03*
Y1000853D03*
Y1287664D03*
X1639162Y1000853D03*
Y1287664D03*
X1668862Y1000853D03*
Y1287664D03*
X1698562D03*
X1728262D03*
X1757962Y744554D03*
Y1000853D03*
Y1287664D03*
X1787662Y744554D03*
Y1000853D03*
Y1287664D03*
X1817362Y744554D03*
Y1000853D03*
Y1287664D03*
G54D11*
X3010Y63308D03*
Y123308D03*
Y163308D03*
Y183308D03*
Y203308D03*
Y223308D03*
Y243308D03*
Y263308D03*
Y283308D03*
X14092Y287115D03*
X3010Y303308D03*
X10884Y321693D03*
Y341693D03*
Y361693D03*
Y381693D03*
Y401693D03*
Y421693D03*
Y441693D03*
Y461693D03*
Y481693D03*
Y501693D03*
Y521693D03*
Y661693D03*
Y681693D03*
Y701693D03*
Y721693D03*
Y741693D03*
Y781693D03*
Y801693D03*
Y821693D03*
Y841693D03*
Y861693D03*
Y881693D03*
Y901693D03*
Y921693D03*
Y941693D03*
Y961693D03*
Y981693D03*
Y1001693D03*
Y1021693D03*
Y1041693D03*
Y1061693D03*
Y1081693D03*
Y1101693D03*
Y1121693D03*
Y1141693D03*
Y1161693D03*
Y1181693D03*
Y1201693D03*
Y1221693D03*
Y1241693D03*
Y1401693D03*
Y1421693D03*
Y1441693D03*
Y1461693D03*
Y1481693D03*
Y1501693D03*
Y1521693D03*
Y1541693D03*
Y1561693D03*
Y1581693D03*
X17371Y49388D03*
X26054Y195148D03*
X16925Y203366D03*
X17061Y196368D03*
X25752Y203274D03*
X24720Y216362D03*
X24754Y220220D03*
X24720Y232362D03*
Y224362D03*
X24814Y236472D03*
X24720Y240362D03*
X22223Y388057D03*
X29509Y398132D03*
X29962Y401000D03*
X16420Y420662D03*
X26615Y670036D03*
X26500Y672862D03*
Y675862D03*
X24700Y765600D03*
X27300Y764200D03*
X27520Y1245162D03*
X20188Y1599396D03*
X28601Y1617541D03*
Y1637541D03*
Y1657541D03*
Y1677541D03*
X37371Y49388D03*
X33500Y200862D03*
X33670Y192862D03*
Y208362D03*
X30795Y213358D03*
X35600Y227380D03*
X33670Y232362D03*
X42500Y224409D03*
X30795Y227366D03*
X33670Y240362D03*
X41492Y290637D03*
X40000Y298707D03*
X36000Y295952D03*
X40000Y293392D03*
X36255Y304972D03*
X33105D03*
X42809Y360862D03*
X35740Y363337D03*
X39410Y384582D03*
X39226Y395346D03*
X33020Y382822D03*
X39320Y392269D03*
X40940Y387302D03*
X43020Y382942D03*
X41933Y395652D03*
X36524Y398013D03*
X45182Y426310D03*
X45960Y428806D03*
X30680Y438142D03*
X45034Y449106D03*
X38220Y589862D03*
Y592862D03*
Y595862D03*
X33020Y595232D03*
X32720Y598402D03*
X34790Y666595D03*
X31390D03*
X38470Y688122D03*
Y683122D03*
Y680622D03*
Y685622D03*
Y693122D03*
Y690622D03*
Y695622D03*
X34899Y711400D03*
X45700Y724100D03*
X45800Y726874D03*
X43841Y1248688D03*
X44833Y1659909D03*
Y1656759D03*
X48269Y1672771D03*
X54593Y19183D03*
X58379Y69340D03*
X60379Y66844D03*
Y71836D03*
X60692Y87118D03*
X54920Y185039D03*
Y177165D03*
X62020Y295952D03*
X62731Y305426D03*
X46834Y360862D03*
X55190D03*
X59322Y360702D03*
X51114Y360862D03*
X61340Y384362D03*
X61250Y396142D03*
X49250Y396332D03*
X49400Y384392D03*
X47618Y413113D03*
X62833Y410047D03*
X53406Y402862D03*
X47619Y421155D03*
X62808Y418425D03*
X53825Y421746D03*
X50138Y426310D03*
X60393D03*
X49360Y428806D03*
X61171D03*
X47619Y418655D03*
X47618Y415613D03*
X54762Y444993D03*
X53800Y435451D03*
X49990Y449106D03*
X48400Y586000D03*
X57595Y603476D03*
X59500Y738700D03*
X55177Y1322328D03*
X56777Y1314165D03*
X55277Y1326068D03*
X56799Y1520094D03*
Y1524094D03*
Y1528094D03*
Y1532094D03*
Y1536094D03*
Y1544094D03*
Y1548094D03*
Y1552094D03*
Y1540094D03*
Y1556094D03*
Y1560094D03*
X54333Y1604359D03*
X59833D03*
X54333Y1613359D03*
X50333D03*
X46994Y1663165D03*
X54478Y1663669D03*
X54535Y1658447D03*
X50900Y1677775D03*
X57833Y1671809D03*
X53333Y1671862D03*
X65000Y1681900D03*
X58325Y1679275D03*
X69058Y3010D03*
X79047Y23978D03*
X74091D03*
X72091Y25974D03*
X73020Y37106D03*
Y28406D03*
X78269Y26474D03*
X74869D03*
X65937Y28403D03*
X73020Y48720D03*
Y40020D03*
X65937Y48720D03*
X67335Y69340D03*
X65335Y66844D03*
Y71836D03*
X65648Y87118D03*
X71379Y72844D03*
Y77836D03*
X76335Y72844D03*
Y77836D03*
X78335Y75340D03*
X69379D03*
X77165Y278798D03*
Y295798D03*
Y286262D03*
X65881Y305426D03*
X77165Y303262D03*
X63429Y360702D03*
X67681D03*
X77220Y379022D03*
Y381522D03*
X68020Y395222D03*
X71772Y421746D03*
X65349Y426310D03*
X75516Y420319D03*
Y424319D03*
X64571Y428806D03*
X75516Y436519D03*
X75490Y432519D03*
X68365Y443677D03*
X64150Y434972D03*
X63540Y438802D03*
X72610Y441262D03*
Y444762D03*
X77000Y485362D03*
X74550Y487812D03*
X80300Y641862D03*
X80241Y659011D03*
X80123Y664031D03*
X80135Y667933D03*
X74559Y667814D03*
X78080Y701832D03*
X63930Y739300D03*
X73759Y754726D03*
X68315Y765664D03*
X73759Y759246D03*
X65600Y1318588D03*
X65240Y1326068D03*
X75564Y1509952D03*
X78120Y1512936D03*
X76369Y1507456D03*
X78120Y1521336D03*
X76680Y1530482D03*
X72774Y1549669D03*
Y1546519D03*
X75922Y1564874D03*
Y1556474D03*
Y1558974D03*
Y1562374D03*
X73429Y1570008D03*
X78415D03*
X77618Y1572504D03*
X74218D03*
X66906Y1598324D03*
X77040Y1601102D03*
X66906Y1603280D03*
X65120Y1609909D03*
X65520Y1615972D03*
X74100Y1613300D03*
X77833Y1678902D03*
X73833Y1674252D03*
X69833Y1678582D03*
X73832Y1689362D03*
X77833Y1689162D03*
X89058Y3010D03*
X81196Y17042D03*
Y22034D03*
X86152Y17042D03*
Y22034D03*
X95369Y17042D03*
Y22034D03*
X79196Y19538D03*
X88152D03*
X93369D03*
X85374D03*
X81974D03*
X88264Y23978D03*
X93220D03*
X86264Y25974D03*
X95220D03*
X81047D03*
X94279Y37106D03*
Y28406D03*
X87193Y37106D03*
Y28406D03*
X80106Y37106D03*
Y28406D03*
X92442Y26474D03*
X89042D03*
X94279Y48720D03*
Y40020D03*
X87193Y48720D03*
Y40020D03*
X80106Y48720D03*
Y40020D03*
X80379Y69340D03*
X89335D03*
X82379Y66844D03*
Y71836D03*
X87335Y66844D03*
Y71836D03*
X91379Y75340D03*
X93379Y72844D03*
Y77836D03*
X86490Y200787D03*
Y208661D03*
X85960Y224409D03*
X85788Y240157D03*
X90700Y282762D03*
X87620Y285321D03*
X87845Y278798D03*
Y295798D03*
X90700Y300262D03*
X87820Y302821D03*
X87654Y376026D03*
X87520Y386502D03*
Y395865D03*
Y391391D03*
Y382219D03*
X85826Y424319D03*
Y420319D03*
Y428319D03*
X84410Y438519D03*
X83320Y445212D03*
X82661Y449604D03*
X94439Y450081D03*
X81505Y447377D03*
X79400Y482862D03*
X94811Y510173D03*
X91027Y643276D03*
X89859Y628246D03*
X86459D03*
X82961Y657111D03*
X95725Y654540D03*
X95860Y659622D03*
X83165Y652564D03*
X91078Y649584D03*
X83208Y646436D03*
X83250Y665428D03*
X84470Y668702D03*
X86433Y688160D03*
X81285Y689804D03*
X84035Y697604D03*
X93547Y692260D03*
X83004Y705141D03*
X97295Y699786D03*
X85095Y722164D03*
X95849Y716358D03*
X91610Y721414D03*
X82357Y737803D03*
X84623Y741249D03*
X81966Y759246D03*
X85877Y759275D03*
X88520Y1484482D03*
X92071Y1492888D03*
X88520Y1491482D03*
Y1487982D03*
Y1494982D03*
X80649Y1509944D03*
X84274Y1517619D03*
X93544Y1510099D03*
X88459Y1510107D03*
X90998Y1513037D03*
X89264Y1507611D03*
X92664D03*
X79769Y1507456D03*
X90998Y1521437D03*
X81038Y1536899D03*
X91538Y1539399D03*
X87500Y1567069D03*
X91500D03*
X84048Y1578008D03*
X90713Y1581852D03*
Y1585852D03*
Y1589852D03*
Y1593867D03*
Y1597867D03*
X81008Y1589872D03*
X90788Y1611821D03*
Y1605867D03*
Y1615821D03*
Y1601867D03*
X81900Y1613300D03*
X85800D03*
X90788Y1623821D03*
X84700Y1627000D03*
X90698Y1630362D03*
X90788Y1619821D03*
X90698Y1638362D03*
Y1634362D03*
Y1642362D03*
X90407Y1656672D03*
X88333Y1661334D03*
X81833Y1674526D03*
X86245Y1690362D03*
X81833Y1689162D03*
X94220Y1686622D03*
X86245Y1694362D03*
X96420Y1693803D03*
X86030Y1683092D03*
X92895Y1737108D03*
X109058Y3010D03*
X100325Y17042D03*
Y22034D03*
X109542Y17042D03*
Y22034D03*
X102325Y19538D03*
X107542D03*
X99547D03*
X110320D03*
X96147D03*
X102437Y23978D03*
X107393D03*
X100437Y25974D03*
X109393D03*
X108453Y37106D03*
Y28406D03*
X101366Y37106D03*
Y28406D03*
X106615Y26474D03*
X103215D03*
X108453Y48720D03*
Y40020D03*
X101366Y48720D03*
Y40020D03*
X102379Y69340D03*
X111335D03*
X104379Y66844D03*
Y71836D03*
X109335Y66844D03*
Y71836D03*
X98335Y72844D03*
Y77836D03*
X100335Y75340D03*
X113490Y216596D03*
X113400Y232128D03*
X110937Y285495D03*
Y302854D03*
X107200Y393562D03*
X107301Y388071D03*
X104220Y400862D03*
X101720D03*
X101317Y431727D03*
X113597Y488434D03*
X102060Y493578D03*
X104875Y490980D03*
X102152Y509374D03*
X102334Y500628D03*
X102359Y497374D03*
X112480Y507792D03*
X110689Y498271D03*
X110464Y505374D03*
X102152Y513374D03*
X111087Y520052D03*
X101983Y518100D03*
X99880Y526300D03*
X110060Y515279D03*
X99773Y515606D03*
X105587Y520727D03*
X106110Y633732D03*
X107489Y630917D03*
X110374Y630879D03*
X102269Y634466D03*
X107045Y661917D03*
X99021Y663732D03*
X103397Y667272D03*
X102120Y688650D03*
X102060Y692100D03*
X102420Y697262D03*
X96626Y736187D03*
X110527Y758869D03*
X112270Y1518907D03*
X99274Y1526019D03*
Y1529169D03*
X96570Y1546187D03*
X99716Y1567878D03*
X99750Y1559478D03*
Y1565378D03*
Y1561978D03*
X96251Y1577532D03*
X107451Y1574704D03*
X100451D03*
X103902Y1584337D03*
X102251Y1576504D03*
X105651D03*
X104318Y1592304D03*
Y1589352D03*
X100620Y1596367D03*
X104318Y1603690D03*
X110200Y1605200D03*
X101500Y1604400D03*
X100020Y1615821D03*
X98738Y1605867D03*
X104318Y1622380D03*
X104400Y1632385D03*
X104430Y1628012D03*
X104318Y1641075D03*
Y1637862D03*
X99600Y1668332D03*
X99645Y1663217D03*
X99980Y1685362D03*
Y1696052D03*
Y1687921D03*
Y1698921D03*
X114498Y17042D03*
Y22034D03*
X123716Y17042D03*
Y22034D03*
X116498Y19538D03*
X121716D03*
X113720D03*
X127894D03*
X124494D03*
X121567Y23978D03*
X116611D03*
X114611Y25974D03*
X123567D03*
X122626Y37106D03*
Y28406D03*
X115539Y37106D03*
Y28406D03*
X120789Y26474D03*
X117389D03*
X122626Y48720D03*
Y40020D03*
X115539Y48720D03*
Y40020D03*
X124379Y69340D03*
X126379Y66844D03*
Y71836D03*
X115379Y72844D03*
Y77836D03*
X120335Y72844D03*
Y77836D03*
X122335Y75340D03*
X113379D03*
X115850Y186362D03*
X122000Y207362D03*
X116920Y207462D03*
X114087Y285495D03*
X118920Y278875D03*
X114087Y302854D03*
X119220Y306236D03*
X119920Y379362D03*
X125007Y392071D03*
Y388071D03*
Y384071D03*
Y396071D03*
X119457Y392071D03*
Y388071D03*
X114507Y404571D03*
X117597Y488434D03*
X127206Y480216D03*
X125070Y486736D03*
X125013Y491829D03*
X124124Y495883D03*
X116171Y485041D03*
X126225Y504368D03*
X120225D03*
Y510368D03*
X112483Y510637D03*
X116411Y497707D03*
X126225Y516368D03*
X120225D03*
X118652Y528860D03*
X129762Y531942D03*
X115793Y528188D03*
X112393D03*
X123257Y547506D03*
X119087D03*
X115060D03*
X111920Y632922D03*
X114540Y633032D03*
X117750Y633232D03*
X120440Y633347D03*
X121400Y638062D03*
X125890Y644163D03*
X122329Y654660D03*
X122280Y651934D03*
X124431Y649570D03*
X122575Y671930D03*
X118019Y661371D03*
X124737Y735726D03*
X118737D03*
X121737D03*
Y738726D03*
X118737D03*
X124737D03*
X123220Y1324662D03*
X120220D03*
X120267Y1327697D03*
X127366Y1535855D03*
X112749Y1524594D03*
Y1532594D03*
Y1528594D03*
X127366Y1541874D03*
Y1547935D03*
X112749Y1540594D03*
Y1544594D03*
Y1548594D03*
Y1536594D03*
Y1552594D03*
Y1564594D03*
Y1560594D03*
Y1556594D03*
X117707Y1553759D03*
X116798Y1586288D03*
Y1598572D03*
X125033Y1589352D03*
X116798D03*
X123230Y1597350D03*
X116798Y1617262D03*
X119500Y1622380D03*
X116798Y1635303D03*
X117220Y1680287D03*
X127195Y1670362D03*
X124795Y1681846D03*
X128195Y1674362D03*
X117795Y1698862D03*
X127195Y1688362D03*
Y1692362D03*
X114645Y1698862D03*
X117220Y1683437D03*
X127195Y1696362D03*
Y1708362D03*
Y1700362D03*
Y1704362D03*
X117255Y1730422D03*
X125082Y1727092D03*
X123394Y1723472D03*
X117426Y1726622D03*
X125720Y1719262D03*
X112895Y1737108D03*
X129058Y3010D03*
X128672Y17042D03*
Y22034D03*
X130672Y19538D03*
X129713Y37106D03*
Y28406D03*
Y48720D03*
Y40020D03*
X133335Y69340D03*
X131335Y66844D03*
Y71836D03*
X137379Y72844D03*
Y77836D03*
X142335Y72844D03*
Y77836D03*
X135379Y75340D03*
X136301Y179095D03*
X141520Y181462D03*
X139720Y179162D03*
X143470Y184012D03*
X143340Y204622D03*
X133590Y212382D03*
X129394Y278875D03*
X129375Y274800D03*
X129394Y306236D03*
X140974Y396885D03*
X135220Y397071D03*
X140974Y401885D03*
Y399385D03*
X132490Y420062D03*
X138042Y480238D03*
X132833D03*
X142166Y490835D03*
X136982Y497090D03*
X131737Y496295D03*
X135006Y487753D03*
X131295Y487822D03*
X132225Y504368D03*
Y510368D03*
X141325Y503806D03*
X141462Y507600D03*
X141329Y510487D03*
X141220Y498810D03*
X138878Y512550D03*
X138408Y507366D03*
X132401Y516368D03*
X139153Y516453D03*
X133160Y532002D03*
X132600Y537072D03*
Y540472D03*
X133467Y634531D03*
X131740Y640103D03*
X131600Y646861D03*
X131330Y665740D03*
X142960Y690807D03*
X140460D03*
X142754Y698811D03*
X140254D03*
X142778Y706835D03*
X140278D03*
X140326Y721660D03*
X142826D03*
X141470Y1359100D03*
X140142Y1392545D03*
Y1396275D03*
X144263Y1412275D03*
X129670Y1563160D03*
X140104Y1560136D03*
X129627Y1556360D03*
X129586Y1553759D03*
X129813Y1604367D03*
X130533Y1622321D03*
X129533Y1637862D03*
X137420Y1708362D03*
X144520Y1717562D03*
X138492Y1717592D03*
X139080Y1731398D03*
X141642Y1717592D03*
X134557Y1722778D03*
X137852Y1726572D03*
X132895Y1737108D03*
X149058Y3010D03*
X159582Y17042D03*
Y22034D03*
X157582Y19538D03*
X160360D03*
X152477Y23978D03*
X157433D03*
X150477Y25974D03*
X159433D03*
X158492Y37106D03*
Y28406D03*
X151405Y37106D03*
Y28406D03*
X156655Y26474D03*
X153255D03*
X147924Y28258D03*
X158492Y48720D03*
Y40020D03*
X151405Y48720D03*
Y40020D03*
X148784Y48720D03*
X146379Y69340D03*
X155335D03*
X148379Y66844D03*
Y71836D03*
X153335Y66844D03*
Y71836D03*
X158583Y75340D03*
X144335D03*
X147901Y188852D03*
X145720Y186462D03*
Y202862D03*
Y206362D03*
X156670Y344542D03*
X159170D03*
X154220Y375682D03*
X158110Y376172D03*
X160090Y391170D03*
Y397470D03*
X149371Y423383D03*
Y419383D03*
Y427383D03*
Y439383D03*
Y431383D03*
Y435383D03*
Y443383D03*
X152826Y439397D03*
Y434362D03*
X159125Y448664D03*
X156306Y449045D03*
X153360Y449112D03*
X152171Y490615D03*
X149557Y494353D03*
X150113Y488487D03*
X161267Y503143D03*
X149472Y502810D03*
X149486Y498810D03*
X149472Y506810D03*
X160000Y510052D03*
X152470Y495383D03*
X151378Y526924D03*
X149518Y522810D03*
X149512Y514810D03*
X150800Y512021D03*
X153737Y514893D03*
X149504Y519881D03*
X154647Y521783D03*
X150877Y757969D03*
X154477Y1360797D03*
X159898Y1360790D03*
X148663Y1378607D03*
X151163D03*
Y1383807D03*
Y1381207D03*
X158318Y1384286D03*
X155718D03*
X158318Y1387393D03*
X155718D03*
X148663Y1386407D03*
X151163D03*
X148663Y1383807D03*
Y1381207D03*
X160201Y1399732D03*
X157731D03*
Y1394132D03*
X160201D03*
X147307Y1404745D03*
X149568Y1395145D03*
Y1397695D03*
X152684Y1403451D03*
X152806Y1414175D03*
X159858Y1409361D03*
X155858Y1406669D03*
Y1409390D03*
X144748Y1514878D03*
X149728D03*
X146390Y1504240D03*
X145538Y1517374D03*
X148938D03*
X153600Y1505600D03*
X154581Y1520981D03*
X158570D03*
X153271Y1540961D03*
X153138Y1549032D03*
X147067Y1545985D03*
X150502Y1572021D03*
X145522D03*
X159107Y1571364D03*
X157441Y1581932D03*
X146312Y1569525D03*
X149712D03*
X152026Y1614138D03*
X158335Y1614452D03*
X155180Y1619872D03*
X156070Y1695702D03*
X144854Y1702389D03*
X154803Y1708532D03*
X145745Y1712362D03*
X161310Y1708022D03*
X148145Y1701862D03*
X155145Y1713517D03*
X155100Y1723262D03*
X152895Y1737108D03*
X169058Y3010D03*
X164538Y17042D03*
Y22034D03*
X173755Y17042D03*
Y22034D03*
X166538Y19538D03*
X171755D03*
X163760D03*
X174533D03*
X166650Y23978D03*
X171606D03*
X164650Y25974D03*
X173606D03*
X172665Y37106D03*
Y28406D03*
X165579Y37106D03*
Y28406D03*
X170828Y26474D03*
X167428D03*
X172665Y48720D03*
Y40020D03*
X165579Y48720D03*
Y40020D03*
X169583Y69340D03*
X171583Y66844D03*
Y71836D03*
X176539Y66844D03*
Y71836D03*
X165539Y72844D03*
X160583D03*
Y77836D03*
X165539D03*
X167539Y75340D03*
X174327Y230928D03*
X164830Y344542D03*
X161670D03*
X173275Y393497D03*
X171180Y401885D03*
X163900Y409362D03*
X164000Y415362D03*
X163926Y425383D03*
X164000Y420362D03*
X172507Y417205D03*
X163926Y430883D03*
Y443319D03*
Y439397D03*
Y435383D03*
X175640Y453779D03*
X178546Y453806D03*
X172632Y454095D03*
X163132Y493299D03*
X165176Y500782D03*
X162750Y512502D03*
X166986Y575918D03*
X176651Y596883D03*
Y594163D03*
X173878Y597027D03*
Y594307D03*
X176651Y599603D03*
X173878Y599747D03*
X161126Y721660D03*
X161078Y706835D03*
X163626Y721660D03*
X163578Y706835D03*
X162398Y1360790D03*
X164898D03*
X172807Y1360797D03*
X160918Y1384286D03*
X163518D03*
Y1387393D03*
X160918D03*
X169318Y1384286D03*
X166118D03*
X172262Y1384302D03*
Y1387409D03*
X174932Y1378797D03*
Y1381397D03*
X163718Y1390500D03*
X161118D03*
X162631Y1399732D03*
Y1394132D03*
X172231Y1390532D03*
X176358Y1403669D03*
X176258Y1400669D03*
X173892Y1402749D03*
Y1405649D03*
X170922Y1399255D03*
X166262D03*
X173252Y1400005D03*
X168592D03*
X162693Y1411529D03*
X164000Y1408862D03*
X162257Y1406594D03*
X171262Y1443390D03*
X173727Y1452134D03*
Y1448734D03*
X170570Y1509250D03*
X164710Y1518014D03*
X168110D03*
X168900Y1520510D03*
X163920D03*
X161321Y1540858D03*
X161374Y1549073D03*
X166476Y1572464D03*
X171456D03*
X173331Y1579399D03*
X167266Y1569968D03*
X170666D03*
X172099Y1588141D03*
X166529Y1707678D03*
X164920Y1712017D03*
X163060Y1717017D03*
X166661Y1721211D03*
X178226Y1726517D03*
X172962Y1721234D03*
X169777Y1726517D03*
X178142Y1720652D03*
X172895Y1737108D03*
X166761Y1732967D03*
X189058Y3010D03*
X178711Y17042D03*
Y22034D03*
X180711Y19538D03*
X177933D03*
X179752Y37106D03*
Y28406D03*
X186120Y24162D03*
X188620D03*
X179752Y48720D03*
Y40020D03*
X191583Y69340D03*
X178539D03*
X182583Y72844D03*
Y77836D03*
X187539Y72844D03*
Y77836D03*
X189539Y75340D03*
X180583D03*
X186457Y393071D03*
Y385071D03*
Y389071D03*
X190880Y383012D03*
Y387162D03*
Y391082D03*
X178375Y396571D03*
X186457Y405071D03*
X192220Y408662D03*
Y412162D03*
X184490Y402203D03*
X181845Y401071D03*
X177871Y421383D03*
Y425383D03*
X191305Y430216D03*
X187532Y421387D03*
X187371Y430883D03*
X177871D03*
Y443383D03*
X187371D03*
X180740Y437562D03*
X184550Y435712D03*
X187371Y440742D03*
X194440Y433895D03*
Y439565D03*
X188221Y454048D03*
X184147Y447078D03*
X187371Y447172D03*
X177871D03*
X181994Y453932D03*
X180640Y447172D03*
X185211Y453942D03*
X185191Y502439D03*
X187490Y568752D03*
X181651Y596883D03*
X179151D03*
X186796Y594195D03*
Y596915D03*
X184151Y596883D03*
X179151Y594163D03*
X181651D03*
X184151D03*
X181651Y599603D03*
X179151D03*
X186796Y599635D03*
X184151Y599603D03*
X186720Y737862D03*
X180720D03*
X183720D03*
Y734862D03*
X180720D03*
X186720D03*
X185835Y757057D03*
X188978Y756855D03*
X191602Y756839D03*
X184215Y1361072D03*
X181403Y1361115D03*
X192620Y1360797D03*
X188233Y1387027D03*
Y1379227D03*
Y1381827D03*
Y1384427D03*
X183283Y1387987D03*
X185633Y1387027D03*
X180672Y1387987D03*
X185633Y1379227D03*
X180672Y1380187D03*
X183283D03*
X177532Y1378797D03*
X185633Y1384427D03*
Y1381827D03*
X180672Y1382787D03*
Y1385387D03*
X183283Y1382787D03*
Y1385387D03*
X177421Y1383997D03*
X177532Y1381397D03*
X182653Y1404535D03*
X187711Y1395170D03*
Y1397670D03*
X190827Y1403451D03*
X180977Y1396173D03*
X178458Y1399269D03*
Y1402169D03*
Y1405069D03*
X192767Y1413725D03*
X185643Y1413945D03*
X188211Y1406691D03*
X186165Y1422589D03*
X183135Y1419784D03*
X180510Y1420258D03*
X177510D03*
X186135Y1419784D03*
X183165Y1422589D03*
X177510Y1423278D03*
X180510D03*
X183075Y1430424D03*
Y1425424D03*
Y1427924D03*
X186075Y1430424D03*
Y1425424D03*
Y1427924D03*
X183075Y1432924D03*
X186075D03*
X185895Y1535462D03*
Y1539723D03*
Y1544029D03*
Y1548487D03*
Y1552875D03*
X192600Y1557360D03*
X185895Y1557875D03*
X189600Y1566300D03*
X187400Y1568132D03*
X176793Y1585173D03*
X192529Y1728947D03*
X183822Y1720517D03*
X187542Y1729092D03*
X193293Y1722197D03*
X188794Y1725092D03*
X192895Y1737108D03*
X209058Y3010D03*
X203716Y17042D03*
Y22034D03*
X208672Y17042D03*
Y22034D03*
X201716Y19538D03*
X207894D03*
X204494D03*
X201567Y23978D03*
X196611D03*
X194611Y25974D03*
X203567D03*
X208784D03*
X202626Y28406D03*
Y37106D03*
X195539Y28406D03*
Y37106D03*
X200789Y26474D03*
X197389D03*
X202626Y40020D03*
Y48720D03*
X195539Y40020D03*
Y48720D03*
X200539Y69340D03*
X193583Y66844D03*
Y71836D03*
X198539Y66844D03*
Y71836D03*
X204717Y72844D03*
Y77836D03*
X202717Y75340D03*
X195050Y412055D03*
X199047Y428626D03*
X199139Y422882D03*
X199149Y425755D03*
Y420255D03*
Y414755D03*
X204699Y423242D03*
Y428742D03*
X195050Y417465D03*
X199149Y436755D03*
Y442255D03*
Y431255D03*
X196215Y447565D03*
X199149Y453255D03*
Y447755D03*
X197650Y455712D03*
X199149Y468255D03*
X208200Y493510D03*
X202338Y568746D03*
X201392Y574271D03*
X198336D03*
X204610Y571097D03*
X199164Y582481D03*
X200654Y578271D03*
X201622Y581009D03*
X208056Y591665D03*
X208806Y589335D03*
X208056Y587005D03*
X208806Y584675D03*
X202262Y592305D03*
X205162D03*
X194059Y604901D03*
X202338Y602746D03*
X201392Y608271D03*
X198336D03*
X203892Y594471D03*
X202492Y596571D03*
X208292D03*
X206892Y594371D03*
X205392Y596571D03*
X204610Y605097D03*
X199164Y616481D03*
X200654Y612271D03*
X201622Y615009D03*
X208806Y618675D03*
X208056Y621005D03*
X208806Y623335D03*
X202338Y636746D03*
X208056Y625665D03*
X203892Y628471D03*
X202492Y630571D03*
X202262Y626305D03*
X208292Y630571D03*
X206892Y628371D03*
X205162Y626305D03*
X205392Y630571D03*
X204610Y639097D03*
X201392Y642271D03*
X199164Y650481D03*
X200654Y646271D03*
X201622Y649009D03*
X198336Y642271D03*
X208056Y655005D03*
X208806Y657335D03*
Y652675D03*
X207620Y671262D03*
X198420Y672662D03*
X198495Y669487D03*
X208056Y659665D03*
X205392Y664571D03*
X205162Y660305D03*
X206892Y662371D03*
X202262Y660305D03*
X202492Y664571D03*
X203892Y662471D03*
X208292Y664571D03*
X196049Y678195D03*
X194196Y687061D03*
X200018Y677492D03*
X193332Y678195D03*
X207129Y690027D03*
X203199Y690006D03*
X197086Y686326D03*
X203179Y693626D03*
X207140Y693636D03*
X195735Y696469D03*
X198235Y698969D03*
Y696469D03*
X200735Y698969D03*
Y696469D03*
X207140Y738462D03*
X205220Y736562D03*
X201220Y736662D03*
X203660Y731802D03*
X195602Y756839D03*
X203602Y756855D03*
X203441Y1360790D03*
X198041D03*
X200941D03*
X201661Y1384286D03*
X193861D03*
X196461D03*
X199061D03*
X201661Y1387393D03*
X193861D03*
X196461D03*
X199061D03*
X204261Y1384286D03*
X207461D03*
X201861Y1390500D03*
X199261D03*
X195874Y1399732D03*
X198344D03*
X200774D03*
X195874Y1394132D03*
X198344D03*
X200774D03*
X206735Y1400005D03*
X209065Y1399255D03*
X204405D03*
X201071Y1412173D03*
X198001Y1409361D03*
X193941Y1407029D03*
X200797Y1409605D03*
X200492Y1406686D03*
X193941Y1409750D03*
X195966Y1542863D03*
X207229Y1631181D03*
X203120Y1624782D03*
X208115Y1624217D03*
X193410Y1711606D03*
X205582Y1700867D03*
X195590Y1714517D03*
X196010Y1709017D03*
X208295Y1703362D03*
X196443Y1722197D03*
X199050Y1726431D03*
X204600Y1733022D03*
X217889Y17042D03*
Y22034D03*
X222845Y17042D03*
Y22034D03*
X210672Y19538D03*
X215889D03*
X224845D03*
X222067D03*
X218667D03*
X215740Y23978D03*
X210784D03*
X217740Y25974D03*
X223886Y28406D03*
Y37106D03*
X216799Y28406D03*
Y37106D03*
X209713Y28406D03*
Y37106D03*
X214962Y26474D03*
X211562D03*
X223886Y40020D03*
Y48720D03*
X216799Y40020D03*
Y48720D03*
X209713Y40020D03*
Y48720D03*
X215717Y66844D03*
Y71836D03*
X220673Y66844D03*
Y71836D03*
X213717Y69340D03*
X222673D03*
X209673Y72844D03*
Y77836D03*
X211673Y75340D03*
X224717D03*
X225407Y321831D03*
X223330Y426467D03*
X220843Y430004D03*
X209530Y426192D03*
X217770Y428262D03*
X224210Y431501D03*
X224305Y422977D03*
X219995Y426267D03*
X220874Y442079D03*
X224210Y436619D03*
X218140Y440735D03*
X218010Y432735D03*
X223664Y443125D03*
X220000Y448735D03*
X209579Y457222D03*
Y462235D03*
X212891Y566632D03*
X210391Y567981D03*
X212891Y601981D03*
X210391D03*
Y635981D03*
X212891D03*
X210320Y671262D03*
X224900Y713293D03*
X209720Y731862D03*
X220033Y756844D03*
X211602Y756855D03*
X216842Y756865D03*
X215824Y1361199D03*
X211350Y1360797D03*
X218960Y1388312D03*
X210405Y1384302D03*
Y1387409D03*
X213075Y1381558D03*
X217133Y1384055D03*
X214425Y1384058D03*
X215675Y1381558D03*
X218175D03*
X213075Y1378958D03*
X215675D03*
X218175D03*
X219752Y1405499D03*
Y1401999D03*
Y1398599D03*
X210374Y1390532D03*
X211395Y1400005D03*
X214201Y1404169D03*
X212035Y1402899D03*
X214101Y1401169D03*
X216554Y1399264D03*
Y1402164D03*
Y1405064D03*
X212035Y1405799D03*
X224137Y1414345D03*
X224077Y1416975D03*
X224350Y1432032D03*
X219587Y1435402D03*
X217469Y1454725D03*
X219587Y1443402D03*
Y1439402D03*
X220869Y1454725D03*
X209820Y1631142D03*
X210593Y1714017D03*
X212120Y1703062D03*
X214120Y1713462D03*
X212684Y1720307D03*
X212895Y1737108D03*
X229058Y3010D03*
X233339Y17662D03*
X235701Y21582D03*
X241310Y20322D03*
X238063Y37162D03*
X230972Y28406D03*
Y37106D03*
X229135Y26474D03*
X225735D03*
X238063Y26232D03*
X235701Y39570D03*
X230972Y48720D03*
Y40020D03*
X229131Y50646D03*
X225731D03*
X239820Y54362D03*
X239720Y71862D03*
X226717Y72844D03*
Y77836D03*
X231673Y72844D03*
Y77836D03*
X233673Y75340D03*
X239010Y78542D03*
X238297Y129703D03*
X242215Y151788D03*
X233800Y162692D03*
X237539Y174266D03*
X234902Y174047D03*
X226800Y359464D03*
X228550Y420412D03*
X230359Y461683D03*
X240993Y570490D03*
Y604490D03*
Y596820D03*
Y594220D03*
Y638490D03*
Y630820D03*
Y628220D03*
X227430Y719772D03*
X238940Y716652D03*
X230864Y1254295D03*
X249058Y3010D03*
X243490Y23002D03*
X246510Y20362D03*
X253000Y28362D03*
X256500D03*
X249500D03*
X242220Y39362D03*
X246220D03*
X250220D03*
X254050Y39422D03*
X246360Y26852D03*
X248820Y48962D03*
X252320D03*
X255820D03*
X257520Y51562D03*
X254020D03*
X250520D03*
X247720Y71862D03*
X244300Y59762D03*
X249885Y69623D03*
X245220Y67862D03*
X247720Y75862D03*
X251797Y100843D03*
X244822Y115543D03*
Y111543D03*
X253910Y115722D03*
X253878Y111771D03*
X252195Y144320D03*
X249735Y152694D03*
X259933Y141122D03*
X242255Y162512D03*
X257256Y156727D03*
X245490Y159702D03*
X252000Y395400D03*
X255810Y405582D03*
X252500Y415862D03*
X257434Y415896D03*
X258066Y426735D03*
X259845Y461117D03*
X256695D03*
X257750Y450842D03*
X249300Y510362D03*
X253800Y515362D03*
X249860Y518222D03*
X254713Y518465D03*
X245700Y513262D03*
X250100Y521783D03*
X246400Y563162D03*
X242460Y716652D03*
X253057Y755345D03*
X245487Y755435D03*
X259510Y757822D03*
X251187Y1255025D03*
X252895Y1737108D03*
X269058Y3010D03*
X260000Y28362D03*
X263280Y35312D03*
X272600Y27182D03*
X263240Y38122D03*
X266990Y41832D03*
X275120Y28562D03*
X271600Y40162D03*
X275900Y48872D03*
X259320Y48962D03*
X261020Y51562D03*
X263520D03*
X261820Y48962D03*
X264740Y49182D03*
X266497Y69536D03*
Y72036D03*
X264720Y56362D03*
Y60362D03*
Y64362D03*
X266597Y77526D03*
Y80026D03*
X263320Y87662D03*
X261420Y100662D03*
X264920D03*
X268420D03*
X262920Y97962D03*
X266420D03*
X269920D03*
X273620Y96662D03*
X272361Y120243D03*
X270364Y118415D03*
X263550Y120922D03*
X269191Y121092D03*
X275797Y120245D03*
X261387Y133783D03*
X258257D03*
X265910Y125492D03*
X266975Y140107D03*
X260600Y151062D03*
X272800Y140162D03*
X264578Y151203D03*
Y155203D03*
Y159203D03*
X260100Y159562D03*
X260700Y218662D03*
X268940Y217982D03*
X263580Y218627D03*
X270745Y207562D03*
X265500Y227862D03*
X263000D03*
X260500Y227362D03*
Y224862D03*
X265343Y244460D03*
X270240Y245332D03*
X271821Y251962D03*
X267759D03*
X258746Y407842D03*
X260807Y424403D03*
X259224Y419532D03*
X263430Y422235D03*
X272029Y443735D03*
X259869Y431039D03*
X262963Y443735D03*
X272500Y447735D03*
X263040Y448752D03*
X272500Y452862D03*
X269600Y715792D03*
X274247Y727165D03*
X268331Y738029D03*
X273046Y735662D03*
X270100Y727262D03*
X264000Y726262D03*
X266700Y730962D03*
X270322Y740207D03*
X274270Y746602D03*
X271570Y746422D03*
X265997Y747535D03*
X272208Y768516D03*
X271057Y765525D03*
Y762425D03*
X272895Y1737108D03*
X289058Y3010D03*
X287000Y20862D03*
X285900Y23962D03*
X286071Y28406D03*
X278984D03*
X284233Y26474D03*
X280833D03*
X290799Y28362D03*
X287952Y39984D03*
X286071Y48720D03*
X286500Y52462D03*
X278984Y48720D03*
X284230Y50646D03*
X280830D03*
X289400Y54222D03*
X287800Y60062D03*
X279277Y99183D03*
X289557Y121803D03*
X275797Y129592D03*
X283953Y152503D03*
X280687Y140746D03*
X287000Y139862D03*
X283053Y139728D03*
X276825Y140462D03*
X288520Y157062D03*
X290685Y165447D03*
X282640Y214102D03*
X279740Y205962D03*
X276890Y249022D03*
X289920Y248652D03*
X286920D03*
X282420D03*
X286481Y251962D03*
X281077D03*
X276491D03*
X289274Y290662D03*
X284515D03*
X276500Y444862D03*
X274850Y442562D03*
X279500Y455362D03*
X277578Y509039D03*
X284482Y569548D03*
X286582Y630757D03*
X287819Y691097D03*
X284287Y716015D03*
X277046Y725709D03*
Y735442D03*
X284358Y732562D03*
X287820Y727962D03*
X278520Y738072D03*
X283350Y728483D03*
X289137Y735275D03*
X279507Y727025D03*
X285046Y737964D03*
X281046Y737938D03*
X275210Y738102D03*
X290077Y739735D03*
X287607Y754962D03*
X277046Y746702D03*
X281046D03*
X285046D03*
X289047Y760245D03*
X291520Y12762D03*
X291660Y21642D03*
X299500Y22862D03*
X295520Y12762D03*
X302610Y26362D03*
X292060Y24472D03*
X295520Y26362D03*
X300248Y28362D03*
X304927Y24654D03*
X304972Y28362D03*
X302720Y38182D03*
X298720Y40017D03*
X306720Y39982D03*
X292590Y53982D03*
X293161Y50522D03*
X306570Y50222D03*
X290720Y40017D03*
X294720D03*
X295524Y52092D03*
X301310Y52482D03*
X298550Y51602D03*
X303715Y50857D03*
X292942Y67513D03*
X305747Y64013D03*
Y61113D03*
X305247Y71567D03*
X293447Y78573D03*
X293452Y82483D03*
Y85983D03*
X303047Y79373D03*
X299947Y79273D03*
X301600Y82457D03*
X302310Y75673D03*
X295357Y88903D03*
X299657Y92503D03*
X307820Y95724D03*
X301751Y127466D03*
Y124466D03*
Y121466D03*
X305025Y144202D03*
X299628Y149203D03*
X302891Y141811D03*
X296478Y149203D03*
X296800Y139762D03*
X299628Y158703D03*
X294553Y153819D03*
X306000Y165662D03*
X295685Y165447D03*
X296478Y158703D03*
X306730Y173842D03*
X304651Y251962D03*
X291759D03*
X306736Y290662D03*
X302765D03*
X298184D03*
X293763D03*
X300520Y552262D03*
X306087Y569718D03*
X307987Y577658D03*
X293805Y569397D03*
Y565997D03*
X298000Y587890D03*
X308417Y585158D03*
X308447Y592255D03*
X306144Y602225D03*
X305612Y622530D03*
Y625030D03*
X294658Y637809D03*
X305612Y627530D03*
X296405Y630732D03*
Y634132D03*
X295962Y679374D03*
X294679Y688446D03*
Y685046D03*
X291600Y705162D03*
X298273Y715400D03*
X297087Y721249D03*
X304602Y727968D03*
X293027Y755985D03*
X290680Y745312D03*
X299427Y768265D03*
X303831Y1318566D03*
X303723Y1353316D03*
Y1355853D03*
X304051Y1365453D03*
X306667Y1361597D03*
X302805Y1379941D03*
Y1376541D03*
X296170Y1622852D03*
X292895Y1737108D03*
X309058Y3010D03*
X318651Y22921D03*
X310400Y50362D03*
X314657Y71803D03*
Y68903D03*
X323040Y73122D03*
X320057Y85803D03*
X323117Y81168D03*
Y76938D03*
X322875Y84318D03*
X316364Y89212D03*
X310459Y75892D03*
X320430Y78002D03*
X320057Y88803D03*
X311758Y124469D03*
Y121469D03*
Y127469D03*
X324733Y148598D03*
X308175Y144202D03*
X320825Y159062D03*
X308500Y165662D03*
X311200Y165562D03*
X309230Y173842D03*
X309756Y177449D03*
Y181449D03*
X310970Y195362D03*
X308790Y197622D03*
X320270Y200462D03*
X319370Y214492D03*
X316370D03*
X319370Y217492D03*
X316370D03*
X323314Y210645D03*
X306910Y228162D03*
X309910D03*
X306910Y225162D03*
X309910D03*
X322658Y229254D03*
X319718Y223750D03*
X313995Y237724D03*
X317981D03*
X320940Y238372D03*
X317129Y251962D03*
X316463Y290662D03*
X316444Y559125D03*
X317860Y572322D03*
X319520Y577658D03*
X314200Y585282D03*
X316080Y578262D03*
X312007Y588675D03*
X319520Y582658D03*
X316127Y592785D03*
X318560Y587632D03*
X320691Y602448D03*
X311820Y598762D03*
X321276Y599298D03*
X317386Y623207D03*
X308605Y629525D03*
Y627025D03*
X319557Y736225D03*
X317967Y746985D03*
Y771875D03*
X316397Y776125D03*
X321119Y1313108D03*
X317119D03*
X313119D03*
X313841Y1365553D03*
X309841Y1364815D03*
X318051Y1367043D03*
X316579Y1364585D03*
X309841Y1367871D03*
X329535Y49388D03*
X336240Y150738D03*
X332500D03*
X326216Y138787D03*
X326900Y162287D03*
X335285Y210609D03*
X332285D03*
X323420Y207549D03*
X326168Y207580D03*
X334485Y216809D03*
X337000Y216862D03*
X335575Y214170D03*
X328588Y209677D03*
X325755Y230719D03*
X338985Y229509D03*
X325855Y227619D03*
X334500Y219362D03*
X337000D03*
X328939Y229139D03*
X335385Y235309D03*
X335412Y222176D03*
X325055Y237219D03*
X328965Y237214D03*
X332465D03*
X329648Y252202D03*
X329002Y290662D03*
X330417Y380482D03*
X330674Y368261D03*
Y365702D03*
X328167Y379073D03*
X336370Y406302D03*
X336270Y402992D03*
X329050Y607402D03*
X331760Y705882D03*
X331339Y709313D03*
X328120Y710862D03*
X335677Y715215D03*
X327107Y732665D03*
X335467Y725335D03*
X338097Y736235D03*
X335126Y728323D03*
X327096Y736005D03*
X336446Y746486D03*
X338667Y772452D03*
X341527Y778362D03*
X325119Y1313108D03*
X328915Y1337104D03*
Y1331904D03*
Y1329304D03*
Y1334504D03*
Y1326704D03*
X335679Y1330518D03*
X334973Y1333353D03*
X338795Y1338799D03*
X336179Y1342753D03*
X332895Y1737108D03*
X349535Y49388D03*
X343040Y122522D03*
X340440Y120552D03*
X343450Y131167D03*
X344776Y148462D03*
X342700Y139662D03*
X355189Y144267D03*
X351100Y150412D03*
X348100Y185162D03*
X345869Y192716D03*
X345600Y188162D03*
X356295Y219362D03*
X353145Y228362D03*
Y219362D03*
X342000Y252612D03*
X354672Y252693D03*
X354145Y290591D03*
X345164Y314234D03*
X343411Y363143D03*
X345411Y364702D03*
X343411Y375364D03*
X345411Y376923D03*
X343354Y387988D03*
Y391643D03*
X343720Y400628D03*
X347340Y407462D03*
X348880Y703442D03*
X354100Y720743D03*
X349187Y715485D03*
X352879Y728657D03*
X348037Y728735D03*
X348730Y735098D03*
Y731698D03*
X344446Y739434D03*
X348000Y755362D03*
X339769Y1299868D03*
X342769D03*
X345969Y1342755D03*
X341969Y1342017D03*
X350179Y1344245D03*
X348707Y1341787D03*
X341969Y1345073D03*
X352895Y1737108D03*
X366775Y127662D03*
X363625D03*
X361800Y122522D03*
X366060Y133912D03*
X366675Y158702D03*
X363525D03*
X356250Y216342D03*
X358209Y208169D03*
X361190Y210762D03*
X357303Y213159D03*
X371551Y224862D03*
X367306Y252811D03*
X366498Y290264D03*
X357764Y314234D03*
X357660Y318850D03*
X364014Y366391D03*
X363750Y369362D03*
X371370Y373622D03*
X364014Y378649D03*
Y382304D03*
X364179Y394596D03*
Y392037D03*
X371066Y400628D03*
X370200Y409582D03*
X373720Y431362D03*
X369690Y431812D03*
X365970Y444662D03*
X365720Y440562D03*
X365771Y449480D03*
X359669Y686744D03*
X359639Y690114D03*
X360470Y705965D03*
X363101Y697348D03*
Y693948D03*
X360990Y726862D03*
X359930Y732985D03*
X358902Y736225D03*
X355946Y728800D03*
X359790Y729835D03*
X358902Y739755D03*
Y743035D03*
Y754945D03*
Y746405D03*
X360927Y757665D03*
X358902Y773352D03*
X361043Y1306506D03*
X361769Y1300008D03*
X363643Y1306506D03*
X364769Y1300008D03*
X367939Y1303319D03*
X361043Y1314306D03*
Y1309106D03*
Y1311706D03*
X367694Y1317092D03*
X367807Y1319592D03*
X368391Y1328161D03*
X370923Y1325373D03*
X367948Y1531529D03*
X371850Y1534062D03*
X368600Y1543200D03*
X367140Y1645390D03*
X366700Y1649000D03*
X370500Y1654362D03*
X370635Y1675820D03*
X369300Y1680400D03*
Y1682900D03*
X383140Y119822D03*
X380930Y122022D03*
X375330Y121182D03*
X374981Y131433D03*
X383160Y124322D03*
X383060Y128491D03*
X372530Y122972D03*
X373200Y126052D03*
X379295Y131002D03*
X376245Y212862D03*
Y217362D03*
Y221362D03*
Y225362D03*
X386120Y220322D03*
X379860Y252162D03*
X379112Y290386D03*
X385720Y323761D03*
Y320902D03*
X376500Y362736D03*
Y366391D03*
Y378649D03*
X376770Y387272D03*
X377136Y390307D03*
X390220Y392062D03*
X383060Y403542D03*
X385520Y429262D03*
X373190Y438342D03*
X384510Y438662D03*
X379220Y436362D03*
X376220D03*
X382220D03*
X385730Y460922D03*
X389920Y461362D03*
X382860Y471122D03*
X379220Y470962D03*
X387500Y495362D03*
X389020Y522862D03*
X371970Y683892D03*
X381010Y734732D03*
X383239Y1286578D03*
X378069Y1286568D03*
X375069D03*
X386239Y1286578D03*
X378097Y1329329D03*
X374097Y1328591D03*
X382307Y1330819D03*
X380835Y1328361D03*
X374097Y1331647D03*
X380025Y1381490D03*
X383127Y1395610D03*
X381060Y1433622D03*
X382489Y1428478D03*
X385667Y1433425D03*
X386827Y1429525D03*
X377830Y1534342D03*
X374900Y1534102D03*
X381120D03*
X377720Y1539862D03*
X374720D03*
X374800Y1546400D03*
X385100Y1539700D03*
X381800Y1539600D03*
X381000Y1546500D03*
X384000D03*
X378000Y1546400D03*
X387152Y1582659D03*
X387930Y1585155D03*
X384600Y1595100D03*
X382220Y1591870D03*
X374690Y1631700D03*
X374391Y1648476D03*
X385123Y1639732D03*
X378547D03*
X375550Y1662052D03*
X380170Y1660002D03*
X372640Y1662112D03*
X380077Y1654049D03*
X381068Y1674824D03*
X386824Y1682866D03*
X387760Y1671092D03*
X372009Y1682584D03*
X375430Y1676462D03*
X373320Y1688202D03*
X376610Y1688252D03*
X372895Y1737108D03*
X393830Y62062D03*
X399800Y59662D03*
X403800D03*
X396380Y62742D03*
X402100Y62632D03*
X399240Y62722D03*
X404910Y62562D03*
X388735Y117322D03*
X395980Y148272D03*
X390830Y155833D03*
X388965Y215067D03*
Y209949D03*
X388720Y218362D03*
X394720Y206362D03*
X402700Y234167D03*
X392616Y252162D03*
X396294Y281585D03*
X392083Y290954D03*
X404215Y291140D03*
X398720Y318643D03*
Y321202D03*
X398661Y323761D03*
X403675Y363081D03*
X390876Y365640D03*
X391195Y368199D03*
X391101Y380939D03*
X403581Y375880D03*
X390843Y378439D03*
X403875Y365640D03*
X404120Y378439D03*
X390730Y394852D03*
X403570Y388874D03*
X404291Y391433D03*
X403700Y402422D03*
X390892Y406863D03*
X391149Y404304D03*
X403720Y405552D03*
X403260Y439352D03*
X391150Y445302D03*
X388720Y430862D03*
X403220Y436362D03*
X395520Y448362D03*
X396570Y472602D03*
X400080Y472652D03*
X402500Y495362D03*
X391360Y495712D03*
X402780Y499372D03*
X394860Y518812D03*
X394500Y522862D03*
X400589Y575236D03*
X403200Y572622D03*
X396139Y1286708D03*
X399139D03*
X395771Y1303480D03*
X393171D03*
X395771Y1300880D03*
X393171D03*
X395771Y1295680D03*
X393171D03*
X395771Y1298280D03*
X393171D03*
X400067Y1303319D03*
Y1300719D03*
Y1295519D03*
Y1298119D03*
X399935Y1317092D03*
Y1319592D03*
X400073Y1327653D03*
X403051Y1325373D03*
X400888Y1395508D03*
X400926Y1402207D03*
X391249Y1401048D03*
X392947Y1397827D03*
X390934Y1404085D03*
X401079Y1399208D03*
X400924Y1408227D03*
X400926Y1404707D03*
X400919Y1411231D03*
X392517Y1419015D03*
X400991Y1417264D03*
X390934Y1407605D03*
X390914Y1412991D03*
X391370Y1424782D03*
X403125Y1425008D03*
X390687Y1431713D03*
X390777Y1435152D03*
X394067Y1435323D03*
X401244Y1440773D03*
X396822Y1439340D03*
X396946Y1537632D03*
X396921Y1549810D03*
X396768Y1541810D03*
X404920Y1539362D03*
X396946Y1560810D03*
Y1556810D03*
X392108Y1582659D03*
X391330Y1585155D03*
X404030Y1595390D03*
Y1591990D03*
X401812Y1616456D03*
X394360Y1616380D03*
X388220Y1631404D03*
X394910Y1632364D03*
X392550Y1618650D03*
X397406Y1633142D03*
X402590Y1618952D03*
X394910Y1637320D03*
X401740Y1648082D03*
X404240D03*
X404320Y1645452D03*
X401820D03*
X391563Y1640244D03*
X397406Y1636542D03*
X397400Y1641000D03*
X402246Y1671745D03*
X390180Y1668212D03*
X396824Y1673662D03*
X409535Y49388D03*
X412930Y62572D03*
X407970Y59612D03*
X407790Y62652D03*
X415800Y62665D03*
Y67465D03*
X419901Y117491D03*
X413459Y129061D03*
X411434Y163662D03*
X408284D03*
X407490Y216912D03*
X420865Y215067D03*
X410996Y218834D03*
X412820Y231922D03*
X420752Y239562D03*
X405478Y236726D03*
X410090Y241932D03*
X420710Y242482D03*
X405139Y239908D03*
X417765Y252162D03*
X404985D03*
X417218Y291274D03*
X419920Y338162D03*
X416220Y364062D03*
X419012Y368762D03*
X418704Y379201D03*
X416762Y367353D03*
X418602Y394722D03*
X419023Y381760D03*
X418540Y392163D03*
X418982Y407847D03*
X416514Y407028D03*
X417010Y439352D03*
X412720Y439362D03*
X417880Y461942D03*
X418520Y473562D03*
X415130Y480202D03*
X410532Y1153341D03*
X407948Y1153370D03*
Y1161570D03*
X410532Y1161541D03*
X407948Y1169597D03*
X410532D03*
X410225Y1329329D03*
X406225Y1328591D03*
X414435Y1330819D03*
X412963Y1328361D03*
X406225Y1331647D03*
X418320Y1383862D03*
X422320D03*
X414333Y1385292D03*
X410933Y1384648D03*
X412465Y1393878D03*
X419974Y1405289D03*
X414909Y1395658D03*
X408915Y1402606D03*
X411150Y1408163D03*
X419974Y1412789D03*
X420474Y1420289D03*
X410912Y1418177D03*
X408968Y1410427D03*
X411162Y1414126D03*
X407125Y1424978D03*
X416926Y1426471D03*
X412416Y1431645D03*
X419861Y1429718D03*
X419302Y1434700D03*
X422708Y1437560D03*
X410074Y1424993D03*
X416999Y1441908D03*
X413599D03*
X404475Y1552452D03*
X407625Y1552572D03*
X419820Y1555862D03*
X409140Y1566892D03*
X405000Y1566670D03*
X419002Y1600306D03*
X406526Y1591212D03*
Y1596168D03*
X412600Y1601000D03*
X406768Y1616456D03*
X408700Y1603500D03*
Y1614300D03*
X408600Y1607400D03*
X419780Y1602802D03*
X411910Y1629170D03*
Y1624214D03*
X414406Y1624992D03*
Y1628392D03*
X405990Y1618952D03*
X416020Y1620862D03*
X412456Y1649838D03*
X417960Y1650072D03*
X410700Y1658460D03*
Y1655310D03*
X410232Y1670244D03*
X409857Y1682767D03*
X421320Y1671699D03*
X410249Y1673082D03*
X429535Y49388D03*
X430655Y58677D03*
X427120Y59862D03*
X428500Y65016D03*
Y70016D03*
X429050Y117491D03*
X435340Y125346D03*
X430980Y132672D03*
X435340Y122196D03*
X428889Y121515D03*
X428883Y131015D03*
X429780Y149373D03*
Y153477D03*
Y157466D03*
Y161466D03*
X433695Y214862D03*
Y209862D03*
X429395Y232562D03*
X426295Y227862D03*
X422210Y221452D03*
X429395Y236562D03*
X421200Y232562D03*
X423145Y227862D03*
X429395Y240562D03*
X426490Y244262D03*
X429702Y290763D03*
X425720Y319492D03*
X425249Y338061D03*
X432380Y346522D03*
X422420Y338162D03*
X432006Y363644D03*
X431503Y376642D03*
X431781Y379201D03*
X434006Y365203D03*
X431596Y389604D03*
X433596Y391163D03*
X431920Y405288D03*
X431462Y402729D03*
X424980Y439462D03*
X428720Y439362D03*
X437720Y435362D03*
X431570Y435512D03*
X437520Y476337D03*
X431220Y496362D03*
X427790Y500862D03*
X427880Y506442D03*
X434343Y504233D03*
Y509733D03*
Y498733D03*
X431220Y507143D03*
Y512623D03*
Y501643D03*
X428510Y515842D03*
X434343Y515233D03*
Y526233D03*
Y520733D03*
X431220Y518133D03*
Y523362D03*
X434620Y535762D03*
X434343Y542733D03*
X434320Y540153D03*
X434343Y547769D03*
Y552769D03*
X436822Y1161570D03*
Y1153370D03*
X431722D03*
Y1161570D03*
X434272Y1153370D03*
Y1161570D03*
X436822Y1170070D03*
X431722D03*
X434272D03*
X430999Y1286758D03*
X423229D03*
X426229D03*
X433999D03*
X432195Y1303319D03*
X425299Y1303480D03*
X427899D03*
X425299Y1295680D03*
X427899D03*
X432195Y1295519D03*
Y1298119D03*
X427899Y1298280D03*
X425299D03*
X432195Y1300719D03*
X427899Y1300880D03*
X425299D03*
X432063Y1317092D03*
Y1319592D03*
X432628Y1327845D03*
X435179Y1325373D03*
X426320Y1383862D03*
X430320D03*
X439030Y1383692D03*
X436780Y1387387D03*
X436467Y1391687D03*
X427474Y1405289D03*
X434974D03*
X438458Y1402169D03*
X434974Y1412789D03*
X427474Y1420289D03*
X434974D03*
X438645Y1426890D03*
X437299Y1436774D03*
X433539Y1430613D03*
X425030Y1434292D03*
X433897Y1434670D03*
X427546Y1443411D03*
X433954Y1439029D03*
X424146Y1443411D03*
X436920Y1541562D03*
X422566Y1550046D03*
X435396Y1551810D03*
X424820Y1552605D03*
X431620Y1541362D03*
X432996Y1558322D03*
X434430Y1567562D03*
X424570Y1579466D03*
X433350Y1579509D03*
X423958Y1600306D03*
X428099Y1586282D03*
X435240Y1609200D03*
X433383Y1602629D03*
X428941Y1606441D03*
X424800Y1616600D03*
X432200Y1607060D03*
X423180Y1602802D03*
X432500Y1613822D03*
X436840Y1632682D03*
X436880Y1622442D03*
X430015Y1626608D03*
X433670Y1639562D03*
X426728Y1636495D03*
X432895Y1737108D03*
X449535Y49388D03*
X451418Y78782D03*
X446640Y104552D03*
X450380Y104647D03*
X443678Y145710D03*
X446746Y152662D03*
X453028Y154864D03*
X452500Y213362D03*
Y222362D03*
X452071Y254862D03*
X442265Y290939D03*
X445964Y314234D03*
X439120Y314562D03*
X442220Y323362D03*
X448220Y323582D03*
Y319862D03*
X446000Y339362D03*
X450400Y338812D03*
X455000Y340362D03*
X445944Y359053D03*
X450500Y358862D03*
X446730Y382432D03*
X443770Y371042D03*
X451062Y397262D03*
X447490Y409052D03*
X443300Y410962D03*
X447750Y414112D03*
X453020Y414262D03*
X443744Y429553D03*
X451421D03*
X449420Y424162D03*
X443744Y452462D03*
X451520Y475837D03*
X442520Y476337D03*
X437520Y484837D03*
X447520D03*
X442520D03*
X451520D03*
X453680Y515072D03*
X442853Y542519D03*
X451320Y533562D03*
X442853Y547519D03*
X442353Y1329329D03*
X438353Y1328591D03*
X446563Y1330819D03*
X445091Y1328361D03*
X438353Y1331647D03*
X443842Y1389106D03*
X448020Y1391862D03*
X443424Y1397869D03*
X439391Y1398266D03*
X441369Y1394260D03*
X451048Y1404914D03*
X447110Y1403812D03*
X448114Y1396812D03*
X445339Y1415731D03*
X446230Y1407722D03*
X445230Y1411719D03*
X445723Y1419730D03*
X443850Y1423404D03*
X451080Y1433740D03*
X440164Y1433982D03*
X445294Y1430415D03*
X443715Y1436052D03*
X446258Y1441606D03*
X449778D03*
X448079Y1562177D03*
X443910Y1555602D03*
X452520Y1564862D03*
X440019Y1576809D03*
X442128Y1574879D03*
X450020Y1570412D03*
X448328Y1582476D03*
X446020Y1570412D03*
X452020Y1580412D03*
X448740Y1574862D03*
X441308Y1602654D03*
X444458D03*
X437383Y1602629D03*
X454661Y1609235D03*
X442974Y1615615D03*
X448181Y1614401D03*
X443800Y1610712D03*
X447100Y1622562D03*
X447020Y1632632D03*
X451910Y1643282D03*
X437562Y1649770D03*
X442518D03*
X449940Y1647412D03*
X447090Y1647472D03*
X444940Y1641842D03*
X438340Y1652266D03*
X441740D03*
X452895Y1737108D03*
X469535Y49388D03*
X454568Y78782D03*
X462620Y120948D03*
X462320Y115948D03*
X466992Y145888D03*
X453346Y149864D03*
X461900Y215244D03*
X466300Y217803D03*
X461900Y222921D03*
X466300Y225480D03*
X458264Y254862D03*
X468323Y254562D03*
X465236Y293823D03*
Y296973D03*
X461736Y301098D03*
Y306098D03*
X467736Y312938D03*
X460300Y303662D03*
X463198Y311587D03*
X468490Y340572D03*
X465000Y340362D03*
X453621Y359053D03*
X469830Y366158D03*
X456660Y359172D03*
X460800Y358962D03*
X459220Y393762D03*
X463500Y383562D03*
X462720Y404762D03*
X458600Y414262D03*
X465421Y424928D03*
Y428078D03*
X466520Y475812D03*
X456520Y476337D03*
X461520D03*
X456520Y484837D03*
X461520D03*
X460323Y510183D03*
X455326Y520389D03*
X453727Y518036D03*
X457456Y522516D03*
X470880Y572692D03*
X467130Y600122D03*
X457196Y1161570D03*
X459696D03*
X462196D03*
X459696Y1153370D03*
X457196D03*
X462196D03*
X459696Y1170070D03*
X462196D03*
X457196D03*
X460049Y1286978D03*
X463049D03*
X469019Y1286718D03*
X458327Y1303980D03*
X460927D03*
X458327Y1301380D03*
X460927D03*
X464427Y1300180D03*
Y1302780D03*
X458327Y1296180D03*
X460927D03*
X464427D03*
X458327Y1298780D03*
X460927D03*
X464191Y1317092D03*
Y1319592D03*
Y1327793D03*
X467307Y1325373D03*
X465749Y1401238D03*
X459550Y1401348D03*
X465947Y1398355D03*
X459321Y1393009D03*
Y1396409D03*
X455576Y1409125D03*
Y1417125D03*
X455602Y1412334D03*
X455576Y1420625D03*
X468880Y1418400D03*
X455576Y1427632D03*
Y1424125D03*
X454450Y1433580D03*
X463140Y1451562D03*
X463207Y1547543D03*
X453595Y1551470D03*
X459520Y1546962D03*
X466905Y1567847D03*
X456961Y1559697D03*
X467400Y1556700D03*
X456020Y1580412D03*
X464020D03*
X462079Y1572177D03*
X460020Y1580412D03*
X457220Y1584020D03*
X466520Y1574862D03*
X454661Y1596755D03*
X464160Y1587122D03*
X457220Y1603562D03*
X460200Y1589900D03*
X459779Y1609235D03*
X456510Y1614472D03*
X469488Y1607362D03*
X458414Y1624994D03*
Y1629950D03*
X460910Y1629172D03*
Y1625772D03*
X455681Y1622492D03*
X458978Y1634481D03*
X463344Y1637622D03*
X469580Y1640272D03*
X468040Y1654807D03*
Y1651657D03*
X466460Y1672332D03*
X466180Y1678392D03*
X478240Y55935D03*
Y66575D03*
Y61129D03*
X481880Y147069D03*
X484396Y161364D03*
X481246D03*
X476220Y158772D03*
X475500Y212685D03*
X470900Y234787D03*
X486800Y259162D03*
X478500Y258862D03*
X472800Y299462D03*
X474736Y302098D03*
X478995Y293787D03*
X484800Y307362D03*
X476740Y309272D03*
X479740Y300202D03*
X479736Y303598D03*
Y308598D03*
X486720Y360862D03*
X475508Y359266D03*
X476585Y370727D03*
X482920Y398060D03*
X472720Y391362D03*
X485020Y414162D03*
X480393Y429412D03*
X471920Y416687D03*
X479379Y452445D03*
X474169Y476196D03*
X479169D03*
Y484696D03*
X474169D03*
X484169D03*
X474044Y503725D03*
X473870Y506622D03*
X474220Y572782D03*
X471940Y597532D03*
X478510Y602942D03*
X472960Y602152D03*
X482780Y607012D03*
X483030Y1153370D03*
Y1161570D03*
Y1170070D03*
X474509Y1286848D03*
X481509D03*
X477509D03*
X484509D03*
X474481Y1329329D03*
X470481Y1328591D03*
X478691Y1330819D03*
X477219Y1328361D03*
X470481Y1331647D03*
X483560Y1401712D03*
X475285Y1395402D03*
X474983Y1400385D03*
X485141Y1405430D03*
X485236Y1417844D03*
X481997Y1409955D03*
X470987Y1409965D03*
X484921Y1413246D03*
X470890Y1435838D03*
X482741Y1438698D03*
X478308Y1439986D03*
X482742Y1441312D03*
X478449Y1448158D03*
X482633Y1449091D03*
Y1446091D03*
X470111Y1548269D03*
X483348Y1548062D03*
X475110Y1548112D03*
X477968Y1548122D03*
X480848Y1548120D03*
X486210Y1547960D03*
X482400Y1558320D03*
X472220Y1626732D03*
X472210Y1618626D03*
X485150Y1624942D03*
X472210Y1622735D03*
X477905Y1663242D03*
Y1659242D03*
X475150Y1654302D03*
X477835Y1673462D03*
X477905Y1667242D03*
X477835Y1677462D03*
Y1685462D03*
X472895Y1737108D03*
X489535Y49347D03*
X488748Y72264D03*
X497002Y88167D03*
X499580Y78442D03*
X489730Y76132D03*
X498330Y96112D03*
X501540Y105152D03*
X498730Y128592D03*
X498630Y140492D03*
X498700Y212685D03*
Y220362D03*
X503100Y215244D03*
X500925Y231262D03*
X503100Y222921D03*
X489980Y250512D03*
X496028Y258590D03*
X499096Y252462D03*
X498636Y293123D03*
X489091Y293787D03*
X498636Y296273D03*
X495136Y300398D03*
Y305398D03*
X501136Y312238D03*
X486861Y309398D03*
X492074Y300306D03*
X486861Y305398D03*
X495036Y310398D03*
X486710Y313582D03*
X492150Y336810D03*
X498720Y360862D03*
X490720D03*
Y368862D03*
X497568Y397632D03*
X489520Y411862D03*
X494020Y414262D03*
X492970Y409252D03*
X502070Y424787D03*
X488070Y429412D03*
X502070Y427937D03*
X488169Y475696D03*
X493169Y476196D03*
X498169D03*
Y484696D03*
X493169D03*
X488169D03*
X494193Y550447D03*
X486500Y556212D03*
X491043Y550447D03*
X490759Y1291978D03*
X489555Y1303480D03*
X492155D03*
Y1300880D03*
X489555D03*
X495309Y1300058D03*
X498309D03*
X496319Y1330493D03*
Y1333043D03*
X499435Y1338799D03*
X496319Y1341264D03*
X499818Y1385027D03*
X499859Y1393027D03*
X490307Y1421499D03*
X491156Y1438713D03*
X499541Y1438698D03*
X491142Y1441312D03*
X499542D03*
X491089Y1446091D03*
Y1449091D03*
X499489D03*
Y1446091D03*
X487340Y1641352D03*
X489230Y1643592D03*
X492895Y1737108D03*
X517914Y42257D03*
X517902Y49194D03*
X510815D03*
X517902Y69508D03*
X510815D03*
X503100Y78402D03*
X510030Y78412D03*
X504980Y101752D03*
X516236Y92948D03*
X513586Y92799D03*
X510600Y92782D03*
X517290Y104252D03*
X513700Y117862D03*
X510900Y111962D03*
X503270Y128592D03*
X507320D03*
X503290Y140492D03*
X507360D03*
X515690Y147852D03*
X519010Y147912D03*
X518186Y139821D03*
X514850Y168443D03*
X519236Y202404D03*
X518670Y219192D03*
X512500Y209862D03*
X504075Y231262D03*
X512500Y223362D03*
X508500Y232862D03*
X508000Y237862D03*
Y241862D03*
X508502Y298813D03*
X503040Y287928D03*
X505900Y311562D03*
X508500Y303362D03*
X508136Y309398D03*
X502239Y315404D03*
X510740Y332592D03*
X507160Y332452D03*
X510720Y360862D03*
X506720Y368862D03*
X509720Y390362D03*
X513173Y408740D03*
X505720Y398362D03*
X502260Y397742D03*
X511320Y437962D03*
X513444Y457522D03*
Y473281D03*
X503169Y475671D03*
X514425Y489112D03*
Y495112D03*
X509493Y539819D03*
X516970Y592942D03*
X513025Y615742D03*
X504135Y615612D03*
X517989Y1300108D03*
X514989D03*
X506609Y1342755D03*
X502609Y1342017D03*
X510819Y1344245D03*
X509347Y1341787D03*
X502609Y1345073D03*
X505055Y1387601D03*
Y1382301D03*
X505018Y1385027D03*
X502418D03*
X505055Y1396001D03*
Y1398601D03*
Y1390201D03*
X508881Y1404880D03*
X506181D03*
X505059Y1393027D03*
X502459D03*
X503559Y1405025D03*
X508775Y1409889D03*
X508828Y1407385D03*
X508802Y1412420D03*
X506075Y1409889D03*
X506128Y1407385D03*
X503572Y1407539D03*
Y1415039D03*
Y1412539D03*
X506102Y1412420D03*
X503572Y1410039D03*
X509246Y1420002D03*
X508001Y1438669D03*
X505777Y1425579D03*
X507942Y1441312D03*
X507964Y1448979D03*
Y1445979D03*
X512895Y1737108D03*
X518606Y23797D03*
X529720Y30792D03*
X525000Y42257D03*
X524988Y49194D03*
X529720Y43054D03*
X534720Y42922D03*
X532075Y69508D03*
Y57894D03*
X524988Y69508D03*
X533915Y59822D03*
X523978Y59074D03*
X529078Y59282D03*
X527520Y69633D03*
X528590Y72922D03*
X529239Y99997D03*
Y92911D03*
X528400Y104225D03*
X518450Y101602D03*
X527310Y98147D03*
Y94747D03*
X528400Y114275D03*
X527823Y131802D03*
X527160Y129243D03*
X527823Y149802D03*
X527278Y164726D03*
X523220Y170362D03*
X534765Y161067D03*
X526920Y161362D03*
X529480Y183921D03*
X529507Y202448D03*
X522337Y202404D03*
X536127Y247652D03*
X531298Y284280D03*
X532533Y299500D03*
X529533D03*
X536420Y309422D03*
X523682Y307541D03*
Y304541D03*
X523660Y323222D03*
X526980Y322582D03*
X521820Y336762D03*
X531720Y360862D03*
X527720D03*
X535220Y383552D03*
X523670Y368892D03*
X525720Y390362D03*
X528145Y408705D03*
X521720Y398362D03*
X526941Y447802D03*
X532650Y446396D03*
Y442376D03*
X518735Y452442D03*
X521885D03*
X532650Y450330D03*
Y454270D03*
X533410Y475932D03*
X525820Y473662D03*
X524425Y489112D03*
Y495112D03*
X519520Y484027D03*
X522805Y482155D03*
X531258Y505473D03*
X526852Y511331D03*
X527042Y505830D03*
X521561Y505969D03*
Y500469D03*
Y511469D03*
X524220Y505862D03*
Y500362D03*
Y511362D03*
X526853Y516817D03*
X521561Y516969D03*
Y522469D03*
X536000Y520362D03*
X524220Y516862D03*
X524720Y525293D03*
Y519743D03*
X521561Y527969D03*
Y539819D03*
X524920D03*
X524820Y545319D03*
X521561Y550819D03*
X523699Y571545D03*
X526280Y569122D03*
X528500Y566722D03*
X523890Y592387D03*
X520710Y592552D03*
X531472Y579750D03*
X534597Y1345539D03*
Y1342432D03*
X528447Y1353316D03*
Y1355816D03*
X528929Y1364212D03*
X531563Y1361597D03*
X532895Y1737108D03*
X548609Y32500D03*
X539720Y30792D03*
X534720D03*
X542050Y47452D03*
X539720Y42862D03*
X550971Y42902D03*
X544720Y42892D03*
X548609Y48082D03*
X546248Y69508D03*
X539161D03*
Y57894D03*
X537315Y59822D03*
X541002Y71436D03*
X544402D03*
X546234Y77443D03*
X548070Y79372D03*
X542620Y103352D03*
X542460Y99172D03*
X549610Y120682D03*
X537360Y120522D03*
X539475Y118772D03*
X550545Y147302D03*
X547395D03*
X543083Y146338D03*
X540460Y200392D03*
X542798Y202646D03*
X544390Y236512D03*
X550390Y231742D03*
X548390Y236512D03*
X546390Y231742D03*
X542050Y231722D03*
X539639Y271972D03*
X539830Y274912D03*
X537720Y278212D03*
X535630Y306602D03*
X547420Y306862D03*
X544920D03*
X549220Y339687D03*
X546758Y360502D03*
X550024Y369123D03*
Y401023D03*
X547810Y414472D03*
X549670Y419892D03*
X543035Y441005D03*
X542870Y438320D03*
X548464Y456534D03*
X548780Y475932D03*
X538120Y463137D03*
X548550Y480382D03*
X546210Y519642D03*
X535290Y572932D03*
X541820Y575130D03*
X541722Y568054D03*
X543450Y590262D03*
X537730Y577440D03*
X547020Y590332D03*
X550320Y583362D03*
X536626Y590500D03*
X537560Y598102D03*
X544813Y1322668D03*
X542213D03*
X538293D03*
X535693D03*
X548197Y1342432D03*
X539997Y1348646D03*
X542397Y1345539D03*
X542597Y1348646D03*
X537197Y1342432D03*
X539797D03*
X542397D03*
X544997D03*
X537197Y1345539D03*
X539797D03*
X538737Y1365553D03*
X534737Y1364815D03*
X542947Y1367043D03*
X541475Y1364585D03*
X534737Y1367871D03*
X562780Y32842D03*
X563482Y40826D03*
X554720Y32862D03*
X565184Y47982D03*
X564430Y45132D03*
X558058Y46352D03*
X554983Y45312D03*
X553650Y48842D03*
X560421Y69508D03*
X553335D03*
X553320Y77443D03*
X551470Y79372D03*
X567865Y92656D03*
X559000Y102862D03*
X561000Y98862D03*
X564988Y118670D03*
X555545Y134340D03*
X552395D03*
X566500Y125097D03*
X551231Y122671D03*
X565500Y145252D03*
X564890Y142173D03*
X555220Y167937D03*
Y164787D03*
X555545Y156462D03*
X555195Y184862D03*
Y171862D03*
X553657Y193862D03*
X554872Y196635D03*
X559400Y201162D03*
X557248Y198909D03*
X564600Y202662D03*
X552489Y212022D03*
X553402Y231292D03*
X564944Y252173D03*
X552089Y253202D03*
Y257202D03*
X562461Y272161D03*
X561324Y301149D03*
X553536Y307527D03*
X566730Y300992D03*
X555520Y309827D03*
X563790Y331846D03*
X561290D03*
X558790D03*
X557701Y369123D03*
X569080Y414002D03*
X559300Y422732D03*
X562200Y419412D03*
X559730Y434772D03*
X557829Y454479D03*
X558220Y459362D03*
X563281Y543113D03*
X563700Y538477D03*
X560640Y540613D03*
X566140Y554972D03*
Y551472D03*
X559927Y548457D03*
X556820Y570462D03*
X557430Y583572D03*
X558933Y1323658D03*
X563634Y1334315D03*
X561034D03*
X558933Y1326258D03*
X556563Y1337918D03*
X553963D03*
X558933Y1328938D03*
X556563Y1335318D03*
Y1332718D03*
X558933Y1331538D03*
X553963Y1335318D03*
Y1332718D03*
X555313Y1340418D03*
X551141Y1345555D03*
X551041Y1348651D03*
X551141Y1342448D03*
X555372Y1343037D03*
X561070Y1346174D03*
X565849Y1346968D03*
X566510Y1352217D03*
X555057Y1449395D03*
X552895Y1737108D03*
X572500Y32862D03*
X568500D03*
X578620Y45112D03*
X581500Y41862D03*
X573190Y42912D03*
X567507Y45869D03*
X575330Y47672D03*
X570208Y47982D03*
X579930Y72052D03*
X577300Y66682D03*
X577880Y75442D03*
X570150Y102862D03*
X579080Y119402D03*
X567673Y130542D03*
X573360Y140532D03*
X581175Y164717D03*
X569965Y161232D03*
X573115D03*
X569470Y171702D03*
X581120Y155062D03*
X568245Y167112D03*
X579481Y202378D03*
Y198378D03*
X579170Y190092D03*
X579481Y194378D03*
Y210378D03*
X568149Y217916D03*
X580712Y215877D03*
X579481Y206378D03*
X578450Y218562D03*
X581645Y233362D03*
X569668Y229812D03*
X578711Y230109D03*
X579245Y221362D03*
X567730Y225362D03*
X578390D03*
X567730Y221362D03*
X581755Y236978D03*
X578509Y265132D03*
X575359D03*
X582510Y296657D03*
X577676Y300268D03*
X569880Y300992D03*
X580400Y302402D03*
X577480Y303822D03*
X582510Y304052D03*
Y311571D03*
X570440Y331930D03*
X567630Y331958D03*
X574800Y322462D03*
X571830Y348772D03*
X582436Y361032D03*
X572360Y351962D03*
X570200Y372229D03*
X571720Y381862D03*
X575050Y383602D03*
X577720Y381862D03*
X580370Y383670D03*
X581090Y426970D03*
X571930Y421232D03*
X571110Y442656D03*
X569490Y437600D03*
X571110Y446706D03*
X570760Y451710D03*
X567320Y454962D03*
Y459962D03*
Y457462D03*
X577220Y449462D03*
X578920Y466462D03*
X583045Y488212D03*
X583220Y493212D03*
X571990Y501046D03*
X568840D03*
X584173Y498422D03*
X568520Y504162D03*
Y506662D03*
X577470Y505592D03*
X578925Y516846D03*
X571700Y552200D03*
X571627Y548124D03*
X569050Y578292D03*
X572057Y577242D03*
X573849Y1346968D03*
X569849D03*
X571555Y1352487D03*
X570645Y1361358D03*
X576220Y1423862D03*
X571620Y1424492D03*
X572895Y1737108D03*
X584950Y54842D03*
X596840Y45152D03*
X593925Y49193D03*
X586260Y52222D03*
X599800Y43152D03*
X597955Y48047D03*
X593369Y45682D03*
X586600Y60602D03*
X590680Y83591D03*
X592307Y94262D03*
X597287D03*
X594720Y97220D03*
X591395Y132142D03*
X588245D03*
X598410Y124102D03*
X598390Y126802D03*
X595220Y140922D03*
X588000D03*
X592710Y156342D03*
X593248Y159480D03*
X598295Y171862D03*
X589690Y161732D03*
X596581Y184849D03*
X590337Y177604D03*
X592220Y173862D03*
X596795Y179287D03*
X590281Y180698D03*
X599720Y184887D03*
X593220D03*
X598760Y203712D03*
X593966Y229965D03*
X584795Y233362D03*
X591310Y219582D03*
X592220Y249362D03*
X595415Y246515D03*
X592039Y252202D03*
X588577Y285862D03*
X590350Y294402D03*
X591727Y285862D03*
X593763Y293999D03*
X588850Y291622D03*
X586820Y314662D03*
X599620Y314762D03*
X595520Y314862D03*
X583820Y314662D03*
X597820Y317062D03*
X592920Y326362D03*
X590820Y330962D03*
X590720Y327862D03*
Y324582D03*
X590470Y319192D03*
X593120Y342782D03*
X583685Y363271D03*
X586185D03*
X586070Y352302D03*
X591720Y430787D03*
X591839Y426112D03*
X595380Y416660D03*
X599220Y444362D03*
X591720Y433937D03*
X595520Y439762D03*
X597220Y458688D03*
X599080Y448062D03*
X584100Y477952D03*
X592520Y467662D03*
X590210Y484132D03*
X593545Y488212D03*
X599645Y479862D03*
X598661Y486922D03*
X587100Y493842D03*
X592400Y479162D03*
X591070Y504900D03*
X594090Y505107D03*
Y501957D03*
X587100Y496342D03*
X589260Y519421D03*
X594240Y511953D03*
X591425Y522337D03*
X591500Y516862D03*
X593675Y534702D03*
X596880Y534812D03*
X589989Y745475D03*
X592340Y744624D03*
X598693Y742072D03*
X607890Y34389D03*
X611810Y34400D03*
X615420Y42342D03*
X605060Y42402D03*
X615185Y49193D03*
X612822Y43232D03*
X606880Y44682D03*
X614400Y46012D03*
X603063Y48023D03*
X615185Y69508D03*
X603374D03*
X606020Y84562D03*
X615220Y76862D03*
X615170Y73812D03*
X601220Y73862D03*
Y76862D03*
X601050Y100008D03*
X603720Y98362D03*
X608620Y94162D03*
X617585Y97257D03*
X613020Y94162D03*
X617409D03*
X603880Y93902D03*
X600220Y96862D03*
X610104Y119342D03*
X614384D03*
X602306Y143077D03*
X612670Y142872D03*
X606040Y153432D03*
X606190Y144002D03*
X602580Y151052D03*
X603019Y146399D03*
X602430Y153862D03*
X612520Y154812D03*
X606260Y161652D03*
X615572Y173942D03*
X615573Y181984D03*
Y179484D03*
X615572Y176442D03*
X614531Y200378D03*
X611030Y188372D03*
X611381Y200378D03*
X603340Y208142D03*
X614531Y209878D03*
X609456Y204994D03*
X606719Y254966D03*
X611310Y266272D03*
X614200Y265792D03*
X605350Y293092D03*
X605870Y298172D03*
X605560Y303372D03*
X607590Y314732D03*
X609844Y330407D03*
X609040Y317282D03*
X615635Y317637D03*
X614130Y328762D03*
X605305Y331162D03*
X615180Y336812D03*
X608830Y374302D03*
X605898Y372984D03*
X605830Y402782D03*
X609690Y402812D03*
X604779Y423862D03*
X605220Y416362D03*
X610720Y436362D03*
X600800Y430900D03*
X614220Y436362D03*
X610720Y442862D03*
X614220D03*
X600351Y461862D03*
X614220Y452862D03*
Y447862D03*
X602910Y461862D03*
X610720Y457862D03*
X614220D03*
X610720Y452862D03*
X604360Y452120D03*
X614220Y467862D03*
Y472862D03*
Y477862D03*
X610820Y472862D03*
X605469Y467562D03*
X610720Y462862D03*
X614220D03*
X603779Y486922D03*
X601220D03*
X600645Y504362D03*
X606200Y510862D03*
Y514862D03*
X609520Y515162D03*
X611870Y512560D03*
X606220Y517762D03*
X614086Y537624D03*
X607328Y537481D03*
X610797Y537528D03*
X614000Y550800D03*
X607720Y550862D03*
X610720D03*
X613220Y654662D03*
X603317Y738415D03*
X603276Y741375D03*
X614660Y739553D03*
X600460Y744912D03*
X613047Y741492D03*
X602027Y761445D03*
X602768Y758385D03*
X612895Y1737108D03*
X616675Y31777D03*
X624633Y49193D03*
X629820Y42562D03*
Y45062D03*
X619562Y49193D03*
X624140Y46672D03*
X622271Y44782D03*
X629000Y67362D03*
X628590Y58622D03*
X622271Y57952D03*
X631546Y85024D03*
X623300Y95762D03*
X620540Y100112D03*
X632300Y104472D03*
X618460Y119342D03*
X626699Y119182D03*
X630951D03*
X624610Y142842D03*
X624520Y154622D03*
X631300Y167872D03*
X631290Y153702D03*
X615970Y161522D03*
X628195Y178414D03*
X628194Y170372D03*
X628195Y175914D03*
X628194Y172872D03*
X630818Y191248D03*
X625862D03*
X620030Y188782D03*
X627645Y236862D03*
X622730Y230362D03*
X630795Y236862D03*
X629564Y256277D03*
X621740Y265952D03*
X618470Y265732D03*
X629564Y253127D03*
X623150Y273172D03*
X621060Y271066D03*
X633150Y301457D03*
X627950Y298897D03*
X625800Y311912D03*
X627600Y309134D03*
X632143Y306575D03*
X630220Y314362D03*
X628294Y317007D03*
X623365Y316742D03*
X631146Y317768D03*
X619474Y331162D03*
X623580Y336429D03*
X619100Y374638D03*
X621720Y373362D03*
X622490Y402162D03*
X628500Y402362D03*
X624220Y411362D03*
X629220D03*
X623220Y426362D03*
X625500Y421362D03*
X629220D03*
Y426362D03*
X629248Y436972D03*
X628900Y431050D03*
X625620Y447862D03*
X625900Y431050D03*
X625620Y442862D03*
X629220D03*
X622220D03*
X617220Y436362D03*
X622220Y452862D03*
Y447862D03*
X629220Y457862D03*
X626400Y462812D03*
X625620Y457862D03*
X622220D03*
X629220Y452862D03*
X625620D03*
X629220Y447862D03*
X626390Y467882D03*
X626210Y478002D03*
X626310Y472902D03*
X629220Y472862D03*
Y477862D03*
Y467862D03*
Y462862D03*
X622220D03*
X622520Y467862D03*
X629220Y487310D03*
Y482862D03*
X622860Y487310D03*
X626720Y482880D03*
X623670Y507862D03*
X629480Y508862D03*
X633000Y508700D03*
X629920Y516652D03*
X623000Y546900D03*
X629220Y643462D03*
X626720D03*
X617252Y739354D03*
X626207Y747585D03*
X623497Y748235D03*
X626017Y745083D03*
X620870Y762072D03*
X617940Y763552D03*
X630417Y757135D03*
X618114Y1258470D03*
X628970Y1670880D03*
X637220Y31462D03*
X646440Y43632D03*
X632463Y43302D03*
X643880Y42142D03*
X647447Y46322D03*
X641200Y46762D03*
X645150Y69508D03*
X645350Y60612D03*
X638500Y57362D03*
X635000D03*
X637000Y68142D03*
X634500Y73422D03*
X645330Y77132D03*
Y72972D03*
X640220Y85542D03*
X634690D03*
X647220Y96929D03*
X639901Y103462D03*
X632640Y107532D03*
X637500Y110362D03*
X640000Y108542D03*
X639970Y113892D03*
X640130Y166362D03*
X642480Y184862D03*
X643170Y171362D03*
X649870Y181942D03*
X645263Y235689D03*
X640295Y234237D03*
X645109Y249202D03*
Y260202D03*
X645876Y296231D03*
X633138Y296766D03*
X643800Y294327D03*
Y298297D03*
X645528Y308623D03*
X645807Y304291D03*
X643800Y306547D03*
Y302247D03*
X645990Y314482D03*
X643800Y310962D03*
X633350Y314362D03*
X647200Y354300D03*
X647100Y357372D03*
X636075Y389862D03*
X649075Y389937D03*
X632620Y389862D03*
X645925Y389937D03*
X638700Y400962D03*
X647700Y399162D03*
X643500Y400962D03*
X643940Y411482D03*
X637220Y411362D03*
X644220Y426362D03*
X640720Y418862D03*
X644220Y421362D03*
X637220Y416362D03*
Y426362D03*
X637195Y421362D03*
X647420Y434162D03*
X640720Y431362D03*
X644000Y438862D03*
X644220Y431362D03*
X638250Y439250D03*
X637220Y431362D03*
X643736Y457214D03*
X644220Y452862D03*
X640820Y457902D03*
X637220Y452862D03*
X640720D03*
X640920Y447862D03*
X644220D03*
X637195Y457862D03*
X637220Y467862D03*
Y472862D03*
Y477862D03*
X644245Y472862D03*
X644220Y467862D03*
Y477862D03*
Y462862D03*
X641235Y477377D03*
X640798Y472934D03*
X637220Y462862D03*
X640820Y467862D03*
X644245Y482862D03*
X640620Y483422D03*
X649218Y504277D03*
X642580Y508172D03*
X645220Y504362D03*
X636960Y516002D03*
X637020Y522362D03*
X642630Y517870D03*
X640130D03*
X633147Y758595D03*
X641057Y1648659D03*
X647725Y1643719D03*
X643725Y1643467D03*
X645407Y1660425D03*
X648225Y1658482D03*
X642725Y1658562D03*
X635410Y1664220D03*
X637540Y1669480D03*
X636702Y1677610D03*
X641386Y1687283D03*
X645725Y1691182D03*
X640725Y1691452D03*
X650725Y1690682D03*
X639745Y1714362D03*
X646225Y1708169D03*
X642225Y1708457D03*
X648220Y1716912D03*
X636160Y1710662D03*
X648290Y1720052D03*
X639745Y1726362D03*
Y1722362D03*
Y1718362D03*
X648220Y1722921D03*
X632895Y1737108D03*
X651943Y33535D03*
X661534Y41748D03*
X661550Y45133D03*
X654464D03*
X661681Y49193D03*
X654595D03*
X663543Y43328D03*
X656950Y59012D03*
X651680Y73812D03*
X656500Y69662D03*
X661587D03*
X661600Y75562D03*
X657165Y79131D03*
X656426Y75431D03*
X652153Y98105D03*
X652680Y89712D03*
X651579Y102703D03*
X659000Y89262D03*
X652320Y123362D03*
X651980Y133822D03*
X662498Y124960D03*
X650790Y144982D03*
Y149871D03*
Y140699D03*
X662880Y149912D03*
Y146912D03*
X651730Y177212D03*
X662560Y214152D03*
X662780Y210362D03*
Y205362D03*
Y207862D03*
X659880Y210762D03*
Y205762D03*
Y208262D03*
X650705Y270947D03*
X662891Y357442D03*
X662680Y354362D03*
X651520Y378662D03*
X660690Y408162D03*
X660720Y404362D03*
X658720Y399862D03*
X652000Y402362D03*
X653100Y407862D03*
X655820Y452662D03*
X655800Y461432D03*
X652195Y457862D03*
X655820Y467662D03*
X663000Y489500D03*
X663014Y493860D03*
X655220Y486862D03*
X661865Y505334D03*
X653800Y498740D03*
X663720Y523806D03*
X656877Y514716D03*
X661743Y521166D03*
X665990Y517131D03*
X661220Y526862D03*
X650794Y515039D03*
X657734Y528255D03*
X652577Y1000775D03*
X662282Y1386432D03*
X653690Y1392362D03*
X653761Y1396300D03*
X663187Y1395170D03*
Y1397720D03*
X666303Y1403476D03*
X663687Y1407279D03*
X654540Y1427605D03*
Y1424205D03*
X661100Y1451012D03*
X662660Y1548120D03*
X663410Y1553982D03*
X664590Y1631620D03*
X655307Y1647436D03*
X663097Y1642667D03*
X651725Y1643397D03*
X656725Y1657619D03*
Y1660769D03*
X663118Y1655557D03*
X663043Y1651557D03*
X663145Y1672862D03*
Y1668862D03*
X656973Y1698727D03*
X652712Y1686275D03*
X653420Y1698662D03*
X663645Y1722862D03*
X652895Y1737108D03*
X680200Y39062D03*
X677560Y40572D03*
X672250Y40812D03*
X675854Y49193D03*
X672005Y44119D03*
X669004Y41698D03*
X668800Y45262D03*
X668768Y49193D03*
X666943Y43328D03*
X682290Y46822D03*
X670612Y47264D03*
X674012D03*
X666406Y69508D03*
X675225Y58108D03*
X674035Y74522D03*
X678050Y58157D03*
X673750Y77692D03*
X673987Y87662D03*
X677820Y89462D03*
X680578Y75992D03*
X674540Y80652D03*
X670800Y85932D03*
X667940Y80142D03*
X671320Y91192D03*
X677790Y104880D03*
X673720Y110362D03*
X674145Y113487D03*
X677978Y119668D03*
Y115668D03*
X675560Y117120D03*
X668300Y132400D03*
X665650Y147692D03*
X673690Y200672D03*
X673300Y211332D03*
X667020Y225762D03*
X673713Y237725D03*
X674731Y359924D03*
X680600Y364282D03*
Y375462D03*
X683100Y369550D03*
X673220Y388362D03*
X677295Y404362D03*
X677195Y408262D03*
X675295Y399862D03*
X670720D03*
X668695Y408362D03*
Y404262D03*
X665870Y433942D03*
X675220Y508862D03*
X680220Y495887D03*
X670220Y503837D03*
X675220D03*
X680220D03*
Y508862D03*
X675220Y521862D03*
Y516852D03*
X670720Y521862D03*
Y516862D03*
X680220Y530362D03*
X673340Y530922D03*
X671607Y742835D03*
X673617Y744735D03*
X669700Y746626D03*
X677887Y742121D03*
X669778Y759929D03*
X664987Y1348896D03*
X667487D03*
X664987Y1346396D03*
X667487D03*
X670037D03*
Y1348896D03*
X673517Y1360815D03*
X676017D03*
X668096Y1360822D03*
X678517Y1360815D03*
X677137Y1384311D03*
X674537D03*
X671937D03*
X669337D03*
X677137Y1387418D03*
X674537D03*
X671937D03*
X669337D03*
X664782Y1383832D03*
Y1381232D03*
Y1378632D03*
Y1386432D03*
X679737Y1384311D03*
X677337Y1390525D03*
X674737D03*
X676250Y1399757D03*
X673820D03*
X671350D03*
X676250Y1394157D03*
X673820D03*
X671350D03*
X679881Y1399280D03*
X666425Y1414200D03*
X676312Y1411554D03*
X673477Y1409386D03*
X669477Y1406694D03*
X677619Y1408887D03*
X675876Y1406619D03*
X669477Y1409415D03*
X667926Y1547018D03*
X682160Y1548040D03*
X665410Y1548180D03*
X679192Y1564252D03*
X679207Y1560482D03*
X678877Y1566798D03*
X678621Y1571072D03*
X678610Y1582154D03*
X666560Y1581000D03*
X678515Y1573910D03*
X678619Y1579070D03*
X666600Y1584900D03*
X678900Y1595400D03*
X678771Y1585945D03*
X666700Y1595500D03*
X678900Y1589800D03*
X666700Y1591900D03*
X678900Y1592600D03*
X666700Y1588500D03*
X679640Y1617520D03*
Y1614000D03*
X679270Y1604040D03*
X675710Y1620320D03*
X673420Y1650057D03*
X671290Y1646320D03*
X668695Y1662235D03*
X671610Y1673792D03*
X671620Y1668303D03*
X677940Y1670110D03*
X678490Y1695660D03*
X674195Y1712362D03*
X675120Y1716242D03*
X674195Y1728362D03*
X672270Y1721612D03*
X672895Y1737108D03*
X687120Y39632D03*
X692289Y40633D03*
X689940Y38952D03*
X696838Y45112D03*
X686854Y43701D03*
X692380Y43532D03*
X696800Y42108D03*
X696838Y47940D03*
X683440Y42832D03*
X687344Y46940D03*
X692389Y46439D03*
X694751Y70212D03*
X690027Y70142D03*
X685780Y70022D03*
X682941Y69982D03*
X699475D03*
X685968Y58157D03*
X694400D03*
X681980D03*
X690510Y59132D03*
X696700Y72462D03*
X692389Y72692D03*
X687664Y73202D03*
X687050Y79212D03*
X685230Y76952D03*
X683820Y79192D03*
X682890Y72642D03*
X696370Y78512D03*
X696727Y81552D03*
Y84052D03*
X695720Y102162D03*
X694220Y104862D03*
X684953Y104968D03*
X688019Y109845D03*
X687030Y113090D03*
X687034Y115896D03*
X694390Y133682D03*
X697615Y123697D03*
X684520Y152482D03*
X688520D03*
X692520D03*
X687238Y171071D03*
X686760Y222912D03*
X685600Y364282D03*
X690600D03*
X695600D03*
X685600Y375462D03*
X690600D03*
X695600D03*
X683500Y381200D03*
X688220Y388362D03*
X685210Y388852D03*
X694920Y388797D03*
X687500Y399402D03*
X692330Y388751D03*
X685220Y391652D03*
X692402Y391250D03*
X697220Y404362D03*
X697120Y408262D03*
X695220Y399862D03*
X685270Y408362D03*
Y404262D03*
X692400Y404682D03*
X694720Y491962D03*
X690720D03*
X683320Y490662D03*
X685220Y495887D03*
X690580Y482992D03*
X694510Y482942D03*
X686120Y481862D03*
X695220Y495887D03*
X690220D03*
X695220Y508862D03*
X685220D03*
X690220Y506362D03*
X685220Y503837D03*
X690220Y508882D03*
X690330Y503530D03*
X695257Y503847D03*
X695220Y516852D03*
X690220D03*
X685220D03*
X690220Y519662D03*
X695220D03*
X689720Y530862D03*
X695220Y530662D03*
X684357Y742345D03*
X683457Y745175D03*
X692784Y1298845D03*
X696810Y1300162D03*
X692280Y1302532D03*
X689605Y1348896D03*
X687105D03*
X689605Y1346396D03*
X687105D03*
X684555D03*
Y1348896D03*
X686426Y1360822D03*
X695022Y1361990D03*
X696462Y1386122D03*
X682937Y1384311D03*
X685881Y1384327D03*
Y1387434D03*
X691351Y1380922D03*
X688751D03*
X691240Y1383522D03*
X693851D03*
Y1378322D03*
Y1380922D03*
X691351Y1378322D03*
X688751D03*
X693851Y1386122D03*
X696462Y1378322D03*
Y1383522D03*
Y1380922D03*
X696272Y1404560D03*
X685850Y1390557D03*
X684541Y1399280D03*
X682211Y1400030D03*
X686871D03*
X691777Y1405594D03*
Y1399794D03*
X689577Y1401194D03*
X687511Y1402924D03*
X691777Y1402694D03*
X689677Y1404194D03*
X687511Y1405824D03*
X694596Y1396198D03*
X694129Y1420283D03*
X696754Y1419809D03*
X691129Y1420283D03*
X685015Y1438475D03*
X696940Y1437955D03*
X694129Y1423303D03*
X691129D03*
X696694Y1427949D03*
Y1425449D03*
Y1430449D03*
X696784Y1422614D03*
X683930Y1552562D03*
Y1555062D03*
Y1557562D03*
X692100Y1567190D03*
X689875Y1577913D03*
X692026Y1580490D03*
X697197Y1640667D03*
X697122Y1636667D03*
X689200Y1648843D03*
X686220Y1640667D03*
X697595Y1666862D03*
X687045Y1673362D03*
X701838Y45112D03*
X706370Y46782D03*
X701838Y42202D03*
Y47940D03*
X703900Y72112D03*
X701400D03*
X700610Y57782D03*
X713000Y69662D03*
X697720Y58162D03*
X710200Y69662D03*
X706867Y58197D03*
X703100Y58157D03*
X700741Y83050D03*
X712500Y79862D03*
X710486Y77695D03*
X700500Y74862D03*
X698710Y86035D03*
X705390Y85792D03*
X703000Y84862D03*
X712433Y103308D03*
X706720Y100462D03*
X699220Y102162D03*
X702720D03*
X701220Y104862D03*
X697720D03*
X712290Y106722D03*
X706673Y122762D03*
X703520Y122540D03*
X704880Y133643D03*
X712340Y128093D03*
X700600Y125309D03*
X707008Y125804D03*
X705800Y167788D03*
X701926Y166535D03*
X705800Y171188D03*
X701926Y178346D03*
Y184252D03*
Y172441D03*
X704770Y182999D03*
Y179599D03*
X701926Y190157D03*
Y196063D03*
Y201968D03*
X704770Y194810D03*
Y191410D03*
X701926Y207874D03*
Y213779D03*
X704770Y218432D03*
Y206621D03*
Y215032D03*
Y203221D03*
X701926Y219685D03*
X700600Y364282D03*
X705600D03*
X710600D03*
X709000Y354000D03*
X715600Y363900D03*
X705700Y361400D03*
X700600Y375462D03*
X705600D03*
X709400Y378200D03*
X713220Y378362D03*
X711200Y396500D03*
X707220Y399362D03*
X709160Y386730D03*
X713220Y388362D03*
X707400Y396200D03*
X713220Y399862D03*
X705195Y408362D03*
Y404262D03*
X705780Y411022D03*
X712770Y406822D03*
X705720Y488862D03*
X703220Y490362D03*
X705720Y484862D03*
X711220Y503842D03*
X705220D03*
Y508862D03*
X711220Y508882D03*
X710720Y521362D03*
X705220D03*
X701757Y521324D03*
X711220Y516852D03*
X705220D03*
Y530362D03*
X698600Y530700D03*
X710940Y591172D03*
X698602Y580536D03*
X705240Y594020D03*
X702740D03*
X712060Y638542D03*
X708680Y638812D03*
X708310Y646032D03*
X704320Y645262D03*
X701917Y742865D03*
X704000Y740862D03*
X700500Y745862D03*
X703545Y745907D03*
X703755Y1290545D03*
X711720Y1286162D03*
X707720Y1290162D03*
X705720Y1286662D03*
X708795Y1303701D03*
X704795Y1294559D03*
X707320Y1301162D03*
X703087Y1346396D03*
X705587D03*
X703087Y1348896D03*
X705587D03*
X708137D03*
Y1346396D03*
X698094Y1361947D03*
X706239Y1360822D03*
X712060Y1360815D03*
X699062Y1380922D03*
Y1383522D03*
Y1378322D03*
X707480Y1384311D03*
X710080D03*
X707480Y1387418D03*
X710080D03*
X701662Y1380922D03*
Y1383522D03*
Y1378322D03*
X699062Y1386122D03*
X701662D03*
X712680Y1384311D03*
Y1387418D03*
X709493Y1399757D03*
Y1394157D03*
X712880Y1390525D03*
X711963Y1399757D03*
Y1394157D03*
X701330Y1395195D03*
Y1397695D03*
X704446Y1403476D03*
X699262Y1413970D03*
X704568Y1414119D03*
X701830Y1407326D03*
X711620Y1409386D03*
X707620Y1406694D03*
Y1409660D03*
X699754Y1419809D03*
X706680Y1437535D03*
X701730Y1437855D03*
X711440Y1436905D03*
X699694Y1427949D03*
Y1425449D03*
Y1430449D03*
X699784Y1422614D03*
X712222Y1570703D03*
X702112Y1583683D03*
Y1571683D03*
Y1575683D03*
Y1579683D03*
X711102Y1575683D03*
X714162Y1574333D03*
X713052Y1579683D03*
X712582Y1584843D03*
X702112Y1587683D03*
Y1591683D03*
X713102Y1601307D03*
X715775Y1599024D03*
X714380Y1589960D03*
X702112Y1595683D03*
X712512Y1596338D03*
X711350Y1590720D03*
X711780Y1614590D03*
X704370Y1604580D03*
X706103Y1617107D03*
X708857Y1613462D03*
X709111Y1618842D03*
X710570Y1629890D03*
X708830Y1623115D03*
X705516Y1620296D03*
X710540Y1636070D03*
X708999Y1646762D03*
X703719Y1646768D03*
X697595Y1662862D03*
X700460Y1660918D03*
X709678Y1658485D03*
X697730Y1677460D03*
X704759Y1677001D03*
X724620Y40062D03*
X722580Y49182D03*
X728980Y39872D03*
X728720Y43562D03*
X719820Y45862D03*
X717320Y44062D03*
X729293Y58062D03*
X724644Y58362D03*
X719949Y58862D03*
X715990Y69662D03*
X725740Y69580D03*
X721990Y69762D03*
X718900Y69662D03*
X727700Y60562D03*
X728591Y71960D03*
X722415Y77862D03*
X718425Y77882D03*
X728090Y75132D03*
X719100Y85262D03*
X728028Y101968D03*
X728023Y98058D03*
X728028Y105468D03*
X729933Y108388D03*
X724133Y141288D03*
X715940Y157362D03*
X718213Y159241D03*
X720633Y160788D03*
X719194Y172909D03*
X714202D03*
X719194Y177865D03*
X714202D03*
X719194Y184909D03*
X714202D03*
X716698Y185687D03*
Y173687D03*
Y177087D03*
X719194Y189865D03*
X714202D03*
X719194Y196409D03*
X714202D03*
X719194Y201365D03*
X714202D03*
X716698Y197187D03*
Y200587D03*
Y189087D03*
X719194Y208243D03*
X714202D03*
X719194Y213199D03*
X714202D03*
X716698Y209021D03*
Y212421D03*
X717020Y220862D03*
X719720Y220142D03*
X727720Y356362D03*
X722500Y365500D03*
X724897Y353887D03*
X721989Y351234D03*
X727000Y365500D03*
X731400D03*
X725220Y380787D03*
X715600Y375462D03*
X722500Y374100D03*
X727000D03*
X731400Y375000D03*
X718220Y388362D03*
X718720Y381892D03*
X728220Y388362D03*
X715220Y404362D03*
X715120Y408262D03*
X723195Y408362D03*
Y404262D03*
X725220Y399862D03*
X713820Y488762D03*
Y484662D03*
X723220Y508882D03*
X717220D03*
X729220D03*
Y503842D03*
X723220D03*
X717220D03*
X714000Y496132D03*
X723120Y525362D03*
X728220Y521362D03*
X717220D03*
X722720D03*
X717296Y525407D03*
X723220Y516852D03*
X729220D03*
X717220D03*
X729212Y531700D03*
X729200Y588952D03*
X729328Y583076D03*
X729295Y586113D03*
X725207Y579371D03*
X722707D03*
X715860Y585540D03*
X714320Y597462D03*
X723450Y597072D03*
X720240Y598292D03*
X715420Y639162D03*
X719190Y646642D03*
X717720Y643262D03*
X715220D03*
X723340Y642922D03*
X714087Y745865D03*
X720697Y765862D03*
X723460Y1245632D03*
X713836Y1283689D03*
X714720Y1286162D03*
X725604Y1346396D03*
X728104D03*
X725604Y1348896D03*
X728104D03*
X723054D03*
Y1346396D03*
X724969Y1360822D03*
X714560Y1360815D03*
X717060D03*
X729443Y1361224D03*
X726694Y1381583D03*
Y1378983D03*
X715280Y1384311D03*
X717880D03*
X715280Y1387418D03*
X721080Y1384311D03*
X724024Y1384327D03*
Y1387434D03*
X728044Y1384083D03*
X729294Y1381583D03*
Y1378983D03*
X715480Y1390525D03*
X723993Y1390557D03*
X714393Y1399757D03*
Y1394157D03*
X725654Y1405824D03*
Y1402924D03*
X727720Y1401194D03*
X727820Y1404194D03*
X718024Y1399280D03*
X722684D03*
X720354Y1400030D03*
X725014D03*
X714455Y1411554D03*
X715762Y1408887D03*
X714019Y1406619D03*
X717300Y1547370D03*
X715792Y1567461D03*
X720370Y1566910D03*
X723520Y1561604D03*
X724712Y1566820D03*
X716612Y1584635D03*
X717152Y1570093D03*
X728977Y1574453D03*
X717402Y1574433D03*
X724465Y1580092D03*
X722465Y1582092D03*
X726465D03*
X723942Y1574123D03*
X718230Y1600372D03*
X724465Y1590950D03*
X722465Y1588950D03*
X726465D03*
X729052Y1602518D03*
X726092Y1598483D03*
X720987Y1599568D03*
X725378Y1614503D03*
X719770Y1614590D03*
X715780D03*
X723542Y1612702D03*
X721488Y1610945D03*
X725910Y1611900D03*
X716688Y1610055D03*
X719168Y1612016D03*
X722040Y1623970D03*
X713791Y1629816D03*
X718195Y1647300D03*
X714203Y1642926D03*
X729150Y1641690D03*
X726810Y1652430D03*
X714071Y1663842D03*
X722630Y1655740D03*
X724500Y1680400D03*
X718758Y1673800D03*
X745900Y40362D03*
X733314Y40862D03*
X740100Y41162D03*
X744987Y49062D03*
X742840Y39832D03*
X736790D03*
X746100Y46262D03*
X736620Y45262D03*
X745130Y69508D03*
X738043D03*
X730957D03*
X731330Y60712D03*
X745474Y57932D03*
X733642Y58062D03*
X741377Y57932D03*
X737595D03*
X732793Y71436D03*
X736193D03*
X742620Y71762D03*
X735880Y60662D03*
X730820Y84062D03*
X740819Y82362D03*
X737623Y98858D03*
X734523Y98758D03*
X736720Y101662D03*
X745035Y94632D03*
X735770Y94988D03*
X739823Y91052D03*
X735733Y111988D03*
X741308Y108742D03*
X738600Y136600D03*
X736060Y145532D03*
X740220Y145362D03*
X732720Y231362D03*
X734220Y238362D03*
X745685Y265322D03*
Y269322D03*
X744247Y312598D03*
X741800Y363200D03*
X742090Y356082D03*
X735600Y351400D03*
X735800Y365500D03*
X732700Y351500D03*
X740200Y375100D03*
X736220Y380787D03*
X742720Y380262D03*
X735800Y375000D03*
X733220Y388362D03*
X738220D03*
X742160Y396452D03*
X738220Y383862D03*
X743720Y404362D03*
X743820Y408262D03*
X745720Y399862D03*
X735220Y410842D03*
X735745Y408362D03*
Y404262D03*
X733720Y399862D03*
X743980Y443482D03*
X740740Y473822D03*
X741420Y494162D03*
X747600Y506592D03*
X735220Y508862D03*
X745220Y503842D03*
X730070Y506212D03*
X744630Y506529D03*
X735220Y503842D03*
X735430Y516862D03*
X745220Y522362D03*
Y516852D03*
X730220Y523362D03*
X740840Y521982D03*
X735173Y521362D03*
X745220Y530362D03*
X736480Y531722D03*
X738980D03*
X733922Y531712D03*
X733117Y580071D03*
Y582571D03*
X733134Y585672D03*
X736710Y603842D03*
Y607242D03*
X739206Y608020D03*
Y603064D03*
X735620Y613862D03*
X730690Y655532D03*
X744538Y746524D03*
X737609Y744282D03*
X730889Y746834D03*
X740820Y741762D03*
X737784Y1360017D03*
X730752Y1384080D03*
X731794Y1381583D03*
Y1378983D03*
X732238Y1388343D03*
X738810Y1396665D03*
X741540Y1396585D03*
X739170Y1405655D03*
X741670Y1405675D03*
X729920Y1405594D03*
X732226Y1396212D03*
X729920Y1399794D03*
Y1402694D03*
X738170Y1414185D03*
X740760Y1414165D03*
X735300Y1648760D03*
X737080Y1655820D03*
X735080Y1662980D03*
X740840Y1655590D03*
X732705Y1669450D03*
X732895Y1737108D03*
X758606Y23797D03*
X747487Y49062D03*
X754620Y51602D03*
X758620D03*
X752720Y59002D03*
X749477Y57932D03*
X755700Y59942D03*
Y62442D03*
X758200Y59942D03*
Y62442D03*
X760700Y59942D03*
Y62442D03*
X747487Y71429D03*
X754219Y75707D03*
X757693Y100653D03*
Y96423D03*
X750700Y106642D03*
X754800Y97082D03*
X750033Y92888D03*
Y89988D03*
X757340Y92562D03*
X754633Y108288D03*
Y105288D03*
X760390Y111810D03*
X762198Y129684D03*
Y126684D03*
X762172Y123898D03*
X751220Y137864D03*
X758110Y172636D03*
X747200Y251500D03*
X761720Y283262D03*
X748085Y278942D03*
X758360Y276122D03*
X757150Y280592D03*
X758720Y283262D03*
X759920Y280562D03*
X754290Y286632D03*
X755200Y296062D03*
X758412Y298790D03*
X755305Y298847D03*
X748820Y284562D03*
X758390Y295450D03*
X748498Y309640D03*
X759637Y311585D03*
X757936Y303908D03*
X760670Y317432D03*
X747554Y384962D03*
X757430Y408212D03*
X760469Y442647D03*
X759940Y438232D03*
X750290Y462162D03*
X758420Y447662D03*
X757365Y459862D03*
X752500Y495762D03*
X757238Y483862D03*
X756642Y501744D03*
X751220Y522362D03*
Y516852D03*
X759790Y525522D03*
X755940Y516862D03*
X756650Y526072D03*
X761710Y517651D03*
X751220Y530362D03*
X757020Y530462D03*
X759820D03*
X754220D03*
X757720Y1375462D03*
Y1384062D03*
X757779Y1390645D03*
X758020Y1397862D03*
X758420Y1406862D03*
X757542Y1420684D03*
X758120Y1414762D03*
X755420Y1426262D03*
Y1422862D03*
X760112Y1579183D03*
X749612Y1579023D03*
X749652Y1586407D03*
X760152Y1583183D03*
X749612Y1583023D03*
X760112Y1592183D03*
Y1587183D03*
X749662Y1590733D03*
X749612Y1594683D03*
X758360Y1589661D03*
X761716Y1661194D03*
X751620Y1674312D03*
X759859Y1686090D03*
X759359Y1729520D03*
X752875Y1726670D03*
X752895Y1737108D03*
X765606Y44894D03*
X774059Y68912D03*
X769474Y75360D03*
X765858Y87340D03*
X762368Y84088D03*
X769284Y103895D03*
X767061Y99959D03*
X767045Y95960D03*
X767028Y91490D03*
X776730Y117479D03*
X773943Y114633D03*
X771131Y111788D03*
X769775Y107977D03*
X766769Y140138D03*
X773420Y143462D03*
X771774Y167518D03*
X772328Y153728D03*
X771426Y158026D03*
X764850Y249792D03*
X766320Y264892D03*
X763320D03*
X771630Y258102D03*
X762420Y280562D03*
X777420Y277962D03*
X773220Y296262D03*
X769789Y296231D03*
X777467Y296315D03*
X769860Y302462D03*
X772866Y311558D03*
X771377Y314139D03*
X777283Y320892D03*
X771490Y354942D03*
X768490D03*
X777420Y354962D03*
X774490Y354942D03*
X765000Y354862D03*
X771960Y375162D03*
X767960Y369662D03*
X776100Y375100D03*
X776000Y369662D03*
X764000D03*
X766195Y393212D03*
X773245Y398212D03*
X766195Y403212D03*
Y413212D03*
X773245Y403212D03*
Y408212D03*
X768910Y403260D03*
X771050Y416940D03*
X766195Y418212D03*
Y423212D03*
Y428212D03*
X768701Y418662D03*
X774982Y446908D03*
X772365Y454862D03*
X768720Y459862D03*
X765315Y454862D03*
Y459862D03*
X772365D03*
X765360Y475412D03*
X765315Y464862D03*
X765335Y469552D03*
X772364Y475062D03*
X772365Y469862D03*
X765315Y479862D03*
Y488862D03*
X772365D03*
X776170Y493422D03*
X766510Y493452D03*
X765386Y483572D03*
X773530Y507062D03*
X765810Y506342D03*
X769745Y502600D03*
X775378Y502502D03*
X765521Y525364D03*
X769220Y530362D03*
X765720D03*
X772220D03*
X777020D03*
X772020Y746562D03*
X774384Y744088D03*
X762562Y746444D03*
X769921Y742095D03*
X767421D03*
X764921D03*
X769337Y760775D03*
X762617Y758885D03*
X768520Y1379962D03*
Y1384062D03*
Y1375462D03*
X768620Y1392762D03*
Y1397262D03*
X775375Y1403561D03*
X767820Y1410262D03*
Y1414762D03*
X763152Y1581893D03*
Y1577893D03*
Y1573793D03*
X773952Y1580493D03*
X768714Y1571203D03*
X769452Y1584393D03*
X770252Y1587268D03*
X763152Y1590893D03*
Y1594893D03*
X774052Y1590293D03*
X776922Y1590444D03*
X764920Y1695347D03*
X766880Y1689020D03*
X766603Y1721797D03*
X772208Y1731911D03*
X785095Y49388D03*
X785180Y120947D03*
X792680D03*
X790180D03*
X787680D03*
X783940Y118637D03*
X786440D03*
X788940D03*
X781440D03*
X782553Y150031D03*
Y152531D03*
X779893Y147521D03*
Y150021D03*
X785135Y281822D03*
Y267822D03*
X780820Y278262D03*
X785135Y274822D03*
X785200Y271400D03*
X780617Y296345D03*
X794057Y301569D03*
X794220Y296062D03*
X785220Y284762D03*
X792943Y312642D03*
X784415Y313734D03*
X779120Y306162D03*
X793896Y309026D03*
X793820Y304962D03*
X779120Y303410D03*
Y308755D03*
X794600Y360600D03*
X785000Y355000D03*
X779920Y354962D03*
X782420D03*
X790120Y354862D03*
X792620D03*
X787600Y354900D03*
X787925Y387900D03*
X795520Y393462D03*
X791075Y388000D03*
X781195Y393212D03*
X781320Y398212D03*
X787720Y408362D03*
X781195Y413212D03*
Y423212D03*
X785560Y417902D03*
X781195Y418212D03*
X791590Y417050D03*
X788120Y422942D03*
X791040Y422892D03*
X793660Y422842D03*
X785720Y427862D03*
X789230Y414942D03*
X780020Y438287D03*
X781410Y431822D03*
X780020Y441437D03*
Y445287D03*
X784730Y432682D03*
X787320Y444862D03*
Y439862D03*
X791582Y435352D03*
X781205Y454402D03*
X780315Y459862D03*
X787320Y454862D03*
Y449862D03*
Y459862D03*
X787360Y469862D03*
X780340Y468982D03*
Y474862D03*
X786220Y464862D03*
X796315Y469290D03*
X780315Y464862D03*
X783340Y474802D03*
X782690Y488862D03*
X793220Y493362D03*
X781170Y493422D03*
X785800Y482762D03*
X793875Y483262D03*
X778670Y493422D03*
X783600Y502462D03*
X793673Y512862D03*
X783400Y511902D03*
X789720Y589862D03*
X785220Y581362D03*
X789720Y587362D03*
X792720Y589862D03*
X789720Y581862D03*
X791720Y593862D03*
X793720Y595862D03*
X783100Y593582D03*
X791969Y618384D03*
X794720Y617862D03*
X783507Y761875D03*
X794157Y761295D03*
X782515Y766702D03*
X791140Y761693D03*
X788225Y1388683D03*
X791260Y1388662D03*
X790380Y1432132D03*
X792208Y1731911D03*
X805095Y49388D03*
X797443Y271469D03*
X806300Y279662D03*
X809700Y273562D03*
X808800Y267900D03*
X810920Y280062D03*
X798204Y279146D03*
X795190Y298572D03*
X797924Y298358D03*
X798620Y312773D03*
X806450Y310362D03*
X803620Y302962D03*
X805870Y304812D03*
X799720Y300462D03*
X795920Y312662D03*
X803280Y354982D03*
X800646Y354921D03*
X809800Y360600D03*
X802200D03*
X806588Y351097D03*
X795220Y354862D03*
X806000Y360600D03*
X798400D03*
X805910Y355012D03*
X797900Y354800D03*
X799800Y368700D03*
X810781Y372615D03*
X802220Y393727D03*
X803150Y408512D03*
X795600Y402500D03*
X795520Y398212D03*
X800352Y408389D03*
X803120Y428762D03*
X797720Y428412D03*
X798370Y439932D03*
X799458Y431217D03*
X802010Y439940D03*
X802790Y433832D03*
X795320Y439862D03*
X805720Y432902D03*
X801750Y444330D03*
X795320Y444862D03*
X810860Y454862D03*
X802810D03*
X795320D03*
Y449862D03*
X802810Y464862D03*
Y449862D03*
X810860Y459862D03*
X802810D03*
X795320D03*
X810860Y449862D03*
X795370Y474862D03*
X798990D03*
X802865D03*
X795320Y464862D03*
X810815Y474862D03*
X810860Y464862D03*
X810815Y469862D03*
X807220Y493362D03*
X801940Y485932D03*
X804510Y486122D03*
X809510D03*
X799230Y485922D03*
X812510Y486422D03*
X801567Y512942D03*
X802790Y495652D03*
X805470Y510522D03*
X807640Y506672D03*
X808100Y509900D03*
X797420Y512503D03*
X805445Y587582D03*
X798720Y585362D03*
X810720Y586862D03*
X811143Y605265D03*
X798220Y597362D03*
X808860Y603802D03*
X807945Y594362D03*
X803220D03*
X797200Y599883D03*
X797720Y617862D03*
X795720Y614862D03*
X796702Y761195D03*
X810850Y770272D03*
X799577Y760985D03*
X807000Y757562D03*
X806323Y1343076D03*
X812130Y1343022D03*
X809210Y1343062D03*
X804100Y1435010D03*
X800000Y1431100D03*
X804652Y1581793D03*
Y1573793D03*
X812652Y1577793D03*
X801652Y1584539D03*
X812698Y1587047D03*
X804652Y1597793D03*
Y1585993D03*
X799152Y1586507D03*
X804652Y1589793D03*
Y1609793D03*
X825095Y49388D03*
X819114Y115223D03*
X827114D03*
X823114D03*
X821118Y134632D03*
X825698Y139062D03*
X824498Y145198D03*
X814570Y145952D03*
X814531Y139851D03*
X820900Y147112D03*
X813900Y269698D03*
X815060Y280072D03*
X813490Y273862D03*
X816220Y277162D03*
X827403Y286625D03*
X816420Y287062D03*
X813293D03*
X826300Y311962D03*
X823800D03*
X813855Y354008D03*
X820936Y356956D03*
X821164Y372312D03*
X818000Y378800D03*
X813210Y374292D03*
X815710D03*
X825003Y389012D03*
Y397276D03*
X819220Y397664D03*
X824980Y405260D03*
Y409260D03*
Y413260D03*
X819220Y412264D03*
X823600Y421194D03*
X821720Y428437D03*
X815310Y440100D03*
X818500Y451700D03*
X816810Y464862D03*
X816500Y476800D03*
X825100Y468900D03*
X824860Y464862D03*
X816400Y472900D03*
X820720Y493862D03*
X822415Y479600D03*
X821720Y511082D03*
X814305Y499503D03*
X819320Y502347D03*
X821720Y527082D03*
Y519082D03*
Y523082D03*
X815040Y590772D03*
X820220Y586862D03*
X814220Y582530D03*
X823720Y594862D03*
X820470Y595112D03*
X815120Y593582D03*
X820613Y744641D03*
X823589Y746924D03*
X822374Y757039D03*
X814770Y763874D03*
X815789Y1008845D03*
X814234Y1340465D03*
X826090Y1334362D03*
Y1339362D03*
Y1329362D03*
Y1344362D03*
X820920Y1344342D03*
X818420D03*
X815652Y1582570D03*
Y1573793D03*
X813352Y1590893D03*
X812652Y1593793D03*
X815551D03*
X818652Y1590444D03*
X812652Y1605793D03*
Y1601793D03*
X812208Y1731911D03*
X836779Y68008D03*
X836126Y62681D03*
X828600Y61752D03*
X839898Y87248D03*
X837791Y85186D03*
X841584Y94181D03*
X837250Y93221D03*
X831297Y104206D03*
X842864Y110296D03*
X831114Y115223D03*
X839360Y114862D03*
X835114Y115223D03*
X845220Y135862D03*
Y129362D03*
X829114Y150273D03*
Y147123D03*
X836502Y161553D03*
X828145Y160362D03*
X838220Y163862D03*
X835220D03*
X837320Y175112D03*
X842720Y181360D03*
X837975Y210064D03*
X837160Y218212D03*
Y213207D03*
X844526Y204968D03*
X838820Y206872D03*
X830339Y228143D03*
X837500Y229642D03*
X829680Y264580D03*
X836210Y272452D03*
X829720Y277562D03*
X829800Y271562D03*
X840063Y285022D03*
X839450Y272662D03*
X835400Y268800D03*
X829620Y280345D03*
X829820Y275045D03*
X840850Y278948D03*
X829320Y296762D03*
X834400Y283862D03*
X834900Y293462D03*
X829720Y292762D03*
X839860Y294702D03*
X827620Y302962D03*
X830417Y311865D03*
X828222Y359960D03*
X835471Y363003D03*
X843133Y366158D03*
X833300Y386500D03*
X838784Y392880D03*
X836300Y418800D03*
X832400Y427100D03*
X840400Y418900D03*
X839200Y434300D03*
X841300Y446800D03*
X831720Y457700D03*
X839640Y449612D03*
X832700Y446800D03*
X830600Y449200D03*
X838220Y459562D03*
X841200Y456500D03*
X842600Y477200D03*
X842341Y474241D03*
X832720Y494862D03*
X829720D03*
X841795Y492862D03*
X838645D03*
X830870Y480010D03*
X832590Y512888D03*
X829745Y498082D03*
Y502082D03*
X832370Y525849D03*
X843287Y527817D03*
X834635Y515447D03*
X830480Y527817D03*
X841461Y525849D03*
X840990Y529786D03*
X828009Y587913D03*
X831705Y593877D03*
X829230Y582772D03*
X831700Y596962D03*
X831530Y651932D03*
X830587Y741205D03*
X833120Y743392D03*
X838587Y766825D03*
X841827Y766795D03*
X837127Y758976D03*
X829420Y758422D03*
X841997Y773085D03*
X838020Y1232432D03*
X832090Y1326862D03*
X828799Y1336870D03*
X828910Y1331756D03*
X832090Y1331862D03*
Y1336862D03*
X828910Y1341725D03*
X832090Y1341862D03*
X843652Y1584539D03*
X841152Y1586507D03*
X832208Y1731911D03*
X845095Y49388D03*
X858629Y60293D03*
X850015Y87341D03*
X843855Y87711D03*
X847472Y94754D03*
X854577Y99651D03*
X854107Y91232D03*
X850280Y113852D03*
X847660Y113962D03*
X853100Y113762D03*
X856776Y129268D03*
X846846Y127064D03*
X854100Y132972D03*
X854220Y135862D03*
Y129362D03*
X854200Y138562D03*
X851895Y160262D03*
X848745Y160187D03*
X848709Y156752D03*
X848360Y182872D03*
X845720Y181362D03*
X849710Y212062D03*
X845220Y216532D03*
X855858Y212425D03*
X855933Y215375D03*
X860050Y215310D03*
X854706Y229878D03*
X852206D03*
X847580Y232222D03*
X853828Y265057D03*
X854333Y276117D03*
X854338Y280027D03*
Y283527D03*
X853828Y269043D03*
X850133Y271049D03*
X861865Y273730D03*
X852800Y288562D03*
X853200Y297462D03*
X850093Y286625D03*
X855480Y299692D03*
X856243Y286447D03*
X856700Y304862D03*
X859920Y308852D03*
X848000Y374622D03*
X851396Y369614D03*
X859734Y373032D03*
X859740Y399081D03*
X846040Y399210D03*
X856842Y410760D03*
X846490Y422131D03*
X857560Y417762D03*
X844200Y418800D03*
X850610Y444352D03*
X847830Y443892D03*
X843810Y453322D03*
X851606Y447927D03*
X844210Y455902D03*
X846700Y473000D03*
Y476900D03*
X855200D03*
X857620Y492862D03*
X848710Y505641D03*
X858600Y511130D03*
X848620Y509752D03*
X853070Y515447D03*
X860345Y522162D03*
X857195D03*
X859888Y593970D03*
X859054Y583752D03*
X845523Y582126D03*
X856698Y594011D03*
X856520Y751262D03*
X853200Y751062D03*
X859450Y750462D03*
X854687Y761685D03*
X844957Y763065D03*
X854620Y1242125D03*
X854237Y1250358D03*
X846652Y1581793D03*
Y1573793D03*
X854652Y1577793D03*
X857652Y1582570D03*
Y1573793D03*
X854777Y1586968D03*
X846652Y1597793D03*
X855352Y1590893D03*
X854652Y1593793D03*
X846652Y1585993D03*
X857551Y1593793D03*
X846652Y1589793D03*
X854652Y1605793D03*
Y1601793D03*
X846652Y1609793D03*
X852208Y1731911D03*
X865095Y49388D03*
X862930Y70072D03*
X866330D03*
X876124Y66072D03*
X868187Y72006D03*
X860937Y71877D03*
X861350Y61672D03*
X876124Y86072D03*
Y106072D03*
Y126072D03*
X862452Y151590D03*
X874295Y163862D03*
X867620Y154362D03*
X871145Y163862D03*
X863488Y176332D03*
X871580Y183370D03*
X875169Y185113D03*
X871980Y199500D03*
X864859Y187110D03*
X873200Y194262D03*
X871890Y196740D03*
X877971Y196652D03*
X867528Y231788D03*
X875543Y266447D03*
X867700Y268262D03*
X860833Y276817D03*
X863933Y276917D03*
X875543Y269347D03*
X863747Y280870D03*
X867237Y273325D03*
X868552Y285537D03*
X862043Y290047D03*
X874243Y287047D03*
X877322Y296051D03*
X872320Y304936D03*
X869820D03*
X867320D03*
X864820D03*
X867922Y376450D03*
X875922Y379793D03*
X860531Y375826D03*
X870700Y382415D03*
Y390620D03*
Y394620D03*
Y386476D03*
Y398620D03*
Y402581D03*
X868113Y409372D03*
X871320Y416752D03*
X870513Y414276D03*
X862320Y431462D03*
X863415Y445829D03*
X860574Y445404D03*
X861080Y459742D03*
X870360Y493042D03*
X862620Y503162D03*
Y499062D03*
Y507162D03*
X868110Y499142D03*
X865290Y499032D03*
X865810Y521862D03*
X860345Y513062D03*
X866820Y736562D03*
X863925Y737697D03*
X864680Y751582D03*
X874155Y756993D03*
X864700Y778300D03*
X860652Y1590444D03*
X872208Y1731911D03*
X892214Y141891D03*
X886280Y174085D03*
X878327Y183169D03*
X876695Y171362D03*
Y176862D03*
X887520Y171362D03*
Y176862D03*
X878220Y192055D03*
X877724Y200837D03*
X878220Y187449D03*
X888929Y209223D03*
X891620Y209662D03*
X888929Y206723D03*
X891620Y207162D03*
X880943Y283347D03*
X884003Y278712D03*
X883870Y275802D03*
X883909Y281862D03*
X879587Y270004D03*
X883870Y272652D03*
X880943Y286347D03*
X880473Y329370D03*
X882520Y327562D03*
X885020D03*
X887520D03*
X890422Y333879D03*
X893440Y336232D03*
X887869Y386618D03*
X883472Y382910D03*
X890820Y389362D03*
X890920Y386352D03*
X887590Y471552D03*
X889439Y489599D03*
Y492999D03*
X887671Y487831D03*
Y494767D03*
X878931Y509051D03*
X878941Y503813D03*
X881680Y504742D03*
Y508142D03*
X884512Y523800D03*
X882410Y526132D03*
X888130Y532612D03*
X891530D03*
X886362Y534380D03*
X887810Y582442D03*
X886500Y739162D03*
X889000Y737562D03*
X885310Y736442D03*
X886720Y741902D03*
X878152Y876760D03*
X878192Y879910D03*
X884747Y871745D03*
X879100Y912608D03*
X884619Y916477D03*
X892317Y915872D03*
X881372Y920655D03*
X880102Y923235D03*
X889439Y1437938D03*
X891560Y1435510D03*
X888652Y1581793D03*
Y1573793D03*
X885652Y1584539D03*
X888652Y1597793D03*
Y1585993D03*
X883152Y1586507D03*
X888652Y1589793D03*
Y1609793D03*
X892208Y1731911D03*
X908620Y188899D03*
X903930Y202885D03*
X903980Y210355D03*
X903930Y217059D03*
X896620Y209662D03*
X894120D03*
Y207162D03*
X896620D03*
X903980Y224529D03*
X906120Y261252D03*
X894770Y283062D03*
X893500Y339062D03*
X896540Y341132D03*
X908675Y455386D03*
X899625Y473856D03*
X902260Y473153D03*
Y475653D03*
X903124Y470797D03*
X900020Y470672D03*
X896060Y481222D03*
Y484622D03*
X893321Y480293D03*
X893311Y485531D03*
X907678Y488177D03*
X895340Y497882D03*
Y501282D03*
X893572Y503050D03*
Y496114D03*
X900061Y510962D03*
X906127Y496343D03*
X901829Y512730D03*
Y516130D03*
X900061Y517898D03*
X893450Y516862D03*
X901230Y531612D03*
X904630D03*
X893298Y534380D03*
X899462Y533380D03*
X906398D03*
X894897Y871745D03*
X897000Y891895D03*
X894375Y913692D03*
X894965Y917422D03*
X898062Y976652D03*
Y969716D03*
X899830Y971484D03*
Y974884D03*
X907770Y1045242D03*
X894830Y1435970D03*
X896652Y1577793D03*
X899652Y1582570D03*
Y1573793D03*
X896672Y1587073D03*
X897352Y1590893D03*
X896652Y1593793D03*
X899551D03*
X902652Y1590444D03*
X896652Y1605793D03*
Y1601793D03*
X912214Y141891D03*
X917680Y174999D03*
Y177999D03*
Y171999D03*
X920246Y184138D03*
X922726Y176302D03*
X922100Y181791D03*
X917386Y184114D03*
X909386Y195925D03*
X924920Y196199D03*
X923836Y193563D03*
X909386Y203011D03*
Y210098D03*
Y217185D03*
Y224271D03*
Y231358D03*
X914550Y239924D03*
X923897Y445545D03*
X927034Y445594D03*
X912984Y458135D03*
X909584D03*
X913913Y455396D03*
X919279Y461244D03*
X924447Y463012D03*
X921047D03*
X909190Y473392D03*
X912288Y472430D03*
X920682Y494586D03*
X918532Y492445D03*
X927154Y492103D03*
X924623Y492097D03*
X918078Y495177D03*
X921189Y492086D03*
X918212Y497677D03*
X918131Y503330D03*
X921060Y506086D03*
X923783Y506076D03*
X918212Y500777D03*
X909984Y496330D03*
X926173Y512391D03*
X920980Y503393D03*
X913394Y521662D03*
X916794D03*
X909600Y521162D03*
X911720Y511662D03*
X911626Y523430D03*
X918562D03*
X924647Y526808D03*
X922879Y531976D03*
Y528576D03*
X924647Y533744D03*
X918420Y804062D03*
X909720Y798861D03*
Y794862D03*
X913720Y799362D03*
X914152Y803294D03*
X924600Y824262D03*
X921757Y962082D03*
X916974Y962108D03*
X923403Y983327D03*
X923930Y976652D03*
X917980Y974952D03*
X923322Y990227D03*
X924440Y996852D03*
X914838Y985989D03*
X918720Y1009937D03*
X921880Y1525110D03*
X924380D03*
X921880Y1527610D03*
X924380D03*
X919488Y1660733D03*
X918020Y1672860D03*
X914500Y1671400D03*
X912208Y1731911D03*
X932214Y141891D03*
X938160Y173389D03*
X935550Y173329D03*
X940720Y173389D03*
X938160Y176389D03*
X935550Y176329D03*
X940720Y176389D03*
X940424Y184190D03*
X936424D03*
X927133Y189386D03*
X935496Y195925D03*
X935770Y191419D03*
X939270D03*
X940410Y188852D03*
X935496Y203012D03*
X925320Y203399D03*
X935496Y210098D03*
Y217185D03*
Y224272D03*
Y231358D03*
X930472Y246093D03*
X938603Y240063D03*
X933122Y246115D03*
X933686Y242922D03*
X935454Y241154D03*
X933217Y380693D03*
Y384693D03*
X941059Y427911D03*
Y424511D03*
X940709Y460438D03*
X938437Y455454D03*
X932724Y455538D03*
X926215Y461244D03*
X937447Y457862D03*
X934047D03*
X928394Y472201D03*
Y474701D03*
X932373Y495175D03*
X929234Y494915D03*
X938588Y485197D03*
X932089Y492691D03*
X929654Y492103D03*
X929698Y503595D03*
X940596Y498648D03*
X932218Y499314D03*
X939872Y495813D03*
X932089Y505986D03*
X932289Y502986D03*
X926637Y506069D03*
X929281Y506086D03*
X931720Y524862D03*
X939097Y527257D03*
X940550Y517400D03*
X940140Y514925D03*
X933773Y530479D03*
X930731D03*
X941050Y532252D03*
Y528852D03*
X928231Y530479D03*
X936273Y530478D03*
X939282Y534020D03*
X938742Y803831D03*
X931573Y816109D03*
X927470Y815112D03*
X927200Y811462D03*
X935052Y812630D03*
X934260Y808312D03*
X938371Y809311D03*
X930786Y811785D03*
X925220Y817862D03*
X928237Y824844D03*
X926469Y826612D03*
X931496Y962082D03*
X926823D03*
X940170Y962842D03*
X930233Y983298D03*
X930274Y990237D03*
X939740Y987762D03*
X936998Y985750D03*
X932310Y996812D03*
X929221Y1014664D03*
X927220Y1012362D03*
X931220D03*
X939380Y1525110D03*
X926880D03*
X929380D03*
X931880D03*
X934380D03*
X936880D03*
X926880Y1527610D03*
X929380D03*
X931880D03*
X934380D03*
X936880D03*
X939380D03*
X938652Y1581393D03*
X928152Y1584539D03*
X938652Y1593393D03*
Y1585393D03*
X925152Y1586507D03*
X938652Y1589393D03*
X933979Y1661327D03*
X929979Y1661352D03*
X942100Y1671100D03*
X932208Y1731911D03*
X952214Y141891D03*
X957420Y153699D03*
X945720Y173389D03*
X943220D03*
X945720Y176389D03*
X943220D03*
X948400Y176499D03*
X949120Y184912D03*
X949710Y198289D03*
X941634Y199051D03*
Y193451D03*
X944250Y194489D03*
Y197889D03*
X957020Y193299D03*
X949550Y192819D03*
X951354Y209437D03*
Y203837D03*
X944880Y210959D03*
Y216559D03*
Y230697D03*
Y225097D03*
X954874Y232071D03*
X954904Y225741D03*
X957020Y264862D03*
X953046Y390103D03*
X951181Y391916D03*
X950660Y399472D03*
X956487Y394831D03*
X942646Y400793D03*
X949920Y404602D03*
X942827Y422743D03*
Y429679D03*
X944032Y437631D03*
Y434231D03*
X945800Y432463D03*
Y439399D03*
X946492Y460410D03*
X945447Y463012D03*
X942047D03*
X946727Y507952D03*
Y504552D03*
X954420Y511252D03*
Y500552D03*
Y497152D03*
X956188Y495384D03*
Y502320D03*
X948495Y502784D03*
X948693Y509497D03*
X956188Y509484D03*
X954420Y514652D03*
X954390Y527596D03*
X956188Y516420D03*
X947190Y527330D03*
X945524Y515483D03*
X944261Y517871D03*
X941740Y512922D03*
X942610Y515350D03*
X952622Y529364D03*
X945100Y534464D03*
X955123Y533642D03*
X948415Y534313D03*
X956518Y531567D03*
X957220Y582862D03*
X953594Y787477D03*
X956700Y786862D03*
X954447Y791735D03*
X951043Y796140D03*
X950190Y791382D03*
X944272Y803410D03*
X943366Y798707D03*
X946786Y795287D03*
X947921Y799761D03*
X941400Y810062D03*
X944170Y962842D03*
X946865Y974077D03*
X953235Y972642D03*
X949560Y981392D03*
X946938Y991162D03*
X943720Y985772D03*
X951560Y997422D03*
X956800Y1663725D03*
X956600Y1666875D03*
X952208Y1731911D03*
X972214Y141891D03*
X960420Y153699D03*
X962604Y165313D03*
X962458Y162398D03*
X965150Y193412D03*
X966720Y198099D03*
X970720D03*
X961120Y193299D03*
X963520Y214699D03*
X960703Y212668D03*
X971471Y242358D03*
X968384Y242051D03*
X965884D03*
X960020Y264862D03*
X963020D03*
X962570Y282812D03*
X962882Y314512D03*
X967239Y320073D03*
X963854Y320113D03*
X963300Y347962D03*
X965792Y350959D03*
X962623Y350642D03*
X965420Y365719D03*
X970730Y377872D03*
X963856Y394202D03*
X960059Y387004D03*
X972986Y393171D03*
X972220Y386251D03*
Y390239D03*
X975670Y392063D03*
X963856Y398302D03*
X965890Y405967D03*
X963720Y439862D03*
X970054Y478773D03*
X961320Y476242D03*
X970054Y485709D03*
X968286Y483941D03*
Y480541D03*
X966720Y511362D03*
X960620Y509462D03*
X972379Y509303D03*
X964347Y509462D03*
X970788Y501230D03*
X964347Y501262D03*
X969351Y512416D03*
X957790Y527596D03*
X963930Y533362D03*
X967330D03*
X959558Y529364D03*
X962162Y535130D03*
X969098D03*
X959351Y533566D03*
X958755Y657078D03*
X960920Y644762D03*
Y649762D03*
Y654762D03*
X963720Y647262D03*
Y657262D03*
Y652262D03*
X963520Y665062D03*
X958866Y662378D03*
X960820Y665062D03*
X960920Y659762D03*
X963720Y662262D03*
X959100Y789862D03*
X963610Y981292D03*
X959535Y990477D03*
X963780Y997496D03*
X967750Y1376460D03*
X965904Y1554364D03*
X960904D03*
X969000Y1554262D03*
X965086Y1603984D03*
X962086D03*
X972208Y1731911D03*
X975688Y152950D03*
Y149950D03*
X990501Y152397D03*
X986369Y155358D03*
X975690Y157220D03*
X983811Y156694D03*
X985499Y168753D03*
X988835Y185443D03*
X981445Y181058D03*
X990115Y173039D03*
X987320Y194599D03*
Y198099D03*
Y201599D03*
X977220Y201399D03*
X986020Y191099D03*
X987259Y276094D03*
X981470Y268532D03*
X988818Y346372D03*
X985016Y344659D03*
X974791Y339990D03*
X986182Y361062D03*
X978000Y362462D03*
X988723Y369650D03*
X991934Y368443D03*
X989500Y376362D03*
X979380Y373082D03*
X988908Y373392D03*
X986400Y383123D03*
X983770Y373962D03*
X979766Y377507D03*
X977949Y384205D03*
X980916Y384286D03*
X980856Y392502D03*
X986955Y391939D03*
X983629Y397628D03*
X979559Y399362D03*
X983970Y392562D03*
X991369Y408252D03*
X988159Y409068D03*
X979240Y425212D03*
X983760Y424292D03*
X980092Y421289D03*
X984254Y418379D03*
X987440Y431193D03*
X985672Y432961D03*
X980720Y512362D03*
X986400Y503200D03*
X983720Y512362D03*
X976283Y534226D03*
X986273Y532996D03*
X980535Y532643D03*
X986418Y530019D03*
X975900Y1265062D03*
X987920Y1290662D03*
X985320Y1288762D03*
X992306Y1295049D03*
X979373Y1342724D03*
X984270Y1554364D03*
X989270D03*
X995000Y150883D03*
X1001500D03*
X995180Y153689D03*
X1002735Y153943D03*
X999735D03*
X1001101Y165510D03*
X999915Y180548D03*
X996415D03*
X992505Y180553D03*
X993205Y174053D03*
X993305Y170953D03*
X996415Y172579D03*
X1002920Y174799D03*
X990220Y195699D03*
Y199199D03*
X1008120Y198293D03*
X990495Y212923D03*
X990220Y202699D03*
X1000610Y211039D03*
X1005640Y210969D03*
X1001195Y219898D03*
X1005120Y230399D03*
X1002500Y266862D03*
X998500Y269862D03*
X1002500D03*
X994743Y289843D03*
X1001065Y304622D03*
Y307122D03*
Y309622D03*
X1006232Y343983D03*
X1001440Y359702D03*
X994553Y365711D03*
X994689Y379348D03*
X1006201Y370004D03*
X999440Y371782D03*
X996922Y367764D03*
X997598Y382952D03*
X997612Y391804D03*
X1006221Y382945D03*
X997900Y400720D03*
X994322Y404090D03*
X1005123Y414662D03*
X997617Y412383D03*
X997394Y415578D03*
X991770Y418835D03*
X993387Y429827D03*
X993012Y421570D03*
X997225Y419162D03*
X990840Y431193D03*
X992608Y432961D03*
X1005720Y498862D03*
X1003220Y512862D03*
X1005520Y510932D03*
X999720Y512862D03*
X991097Y529902D03*
X991237Y533043D03*
X1008560Y589682D03*
X1002640Y594692D03*
X1005960Y594682D03*
X1005373Y748826D03*
X995120Y773122D03*
X994942Y777055D03*
X996675Y1286985D03*
X996320Y1280683D03*
Y1284062D03*
X997920Y1278762D03*
X994574Y1297318D03*
X1007636Y1554364D03*
X992466Y1554262D03*
X996698Y1604000D03*
X993698D03*
X992208Y1731911D03*
X1021908Y60392D03*
Y120392D03*
X1012214Y141826D03*
X1015300Y148736D03*
X1012187Y148749D03*
X1008129Y150948D03*
X1012791Y157596D03*
X1006435Y172843D03*
X1009895Y192359D03*
X1008067Y194356D03*
X1020645Y190499D03*
X1011320Y202169D03*
X1019935Y206463D03*
Y203333D03*
X1019355Y218423D03*
X1019802Y214099D03*
X1010005Y208424D03*
X1011720Y229699D03*
X1019355Y222423D03*
X1019530Y226423D03*
X1007820Y229999D03*
X1018000Y263862D03*
X1022000Y264362D03*
X1014500Y263862D03*
X1010500D03*
X1018000Y266862D03*
X1022002Y267342D03*
X1010500Y266862D03*
X1006500D03*
X1014500D03*
Y269862D03*
X1018000D03*
X1022002Y270142D03*
X1006500Y269862D03*
X1010500D03*
X1021118Y294290D03*
X1010828Y304822D03*
Y307322D03*
Y309822D03*
X1021419Y305704D03*
X1020720Y310937D03*
X1015520Y302862D03*
X1013500Y344900D03*
X1009800Y343800D03*
X1021695Y364518D03*
X1006710Y372931D03*
X1015096Y373758D03*
X1017163Y367963D03*
X1009883Y367955D03*
X1015638Y382968D03*
X1015637Y391334D03*
X1006589Y392017D03*
X1010420Y416062D03*
X1006750Y401010D03*
X1015657Y401013D03*
X1015420Y410862D03*
X1021259Y420548D03*
X1007249Y422682D03*
X1011611Y430038D03*
X1017511D03*
X1009009Y419948D03*
X1021239Y416974D03*
X1016261Y432888D03*
X1012861D03*
X1008720Y498362D03*
X1019145Y503823D03*
X1024200Y510362D03*
X1020392Y521826D03*
X1011720Y589362D03*
X1018720Y592362D03*
X1016360Y594682D03*
X1016220Y590862D03*
X1021720Y601862D03*
X1019000Y601042D03*
X1021654Y606302D03*
X1011160Y594682D03*
X1010630Y748741D03*
X1007873Y748826D03*
X1007600Y1298250D03*
X1007610Y1295040D03*
X1016012Y1554262D03*
X1012636Y1554364D03*
X1012208Y1731911D03*
X1038609Y49388D03*
X1027520Y122732D03*
X1037650Y128842D03*
X1026620Y125662D03*
X1034229Y128953D03*
X1032894Y155185D03*
X1023220Y187574D03*
X1025000Y264362D03*
X1031502Y267342D03*
X1028202D03*
X1025102D03*
X1037618Y261200D03*
X1031702Y264130D03*
X1033133Y272564D03*
X1031502Y270142D03*
X1029833Y272564D03*
X1026733D03*
X1023633D03*
X1028202Y270142D03*
X1025102D03*
X1036915Y290969D03*
X1025862Y291727D03*
X1032317Y291284D03*
X1036278Y303993D03*
Y307393D03*
X1033285Y353627D03*
X1029395Y375844D03*
X1025004Y374662D03*
X1031950Y383771D03*
Y387171D03*
X1031153Y390152D03*
X1029094Y383070D03*
Y387872D03*
X1026820Y394362D03*
X1033860Y400802D03*
X1038320Y407062D03*
Y404462D03*
X1026548Y400571D03*
X1035920Y428962D03*
Y420062D03*
Y417462D03*
X1038294Y506504D03*
X1027190Y510672D03*
X1026370Y503562D03*
X1032155Y509737D03*
X1029220Y520032D03*
X1025530Y519627D03*
X1033040Y519852D03*
X1038130Y518417D03*
X1038220Y589862D03*
X1040720Y591862D03*
X1030980Y598722D03*
X1023740Y596152D03*
X1036480Y596272D03*
X1024154Y601152D03*
X1029630Y601252D03*
X1026654Y596152D03*
X1035760Y592952D03*
X1033260Y601272D03*
X1038260D03*
X1033817Y735612D03*
X1036954Y734669D03*
X1030660Y735082D03*
X1031002Y1554364D03*
X1036002D03*
X1028298Y1604000D03*
X1025298D03*
X1032208Y1731911D03*
X1040970Y128332D03*
X1053028Y246518D03*
X1053428Y261118D03*
X1040924Y286073D03*
X1043720Y363462D03*
X1043629Y375078D03*
Y372578D03*
X1054820Y370162D03*
X1044120Y366362D03*
X1049100Y390162D03*
X1040120Y393962D03*
X1042720D03*
X1046156Y442699D03*
X1041420Y443962D03*
X1043920D03*
X1050470Y447062D03*
X1053690Y520760D03*
X1043720Y589362D03*
X1045720Y591672D03*
X1050200Y598062D03*
X1050390Y604172D03*
X1043260Y601272D03*
X1045760Y596272D03*
X1048260Y601272D03*
X1053200Y612162D03*
X1051680Y614772D03*
X1053745Y742341D03*
X1054368Y1554364D03*
X1039298Y1554262D03*
X1056898Y1604000D03*
X1052208Y1731911D03*
X1058609Y49388D03*
X1067220Y145362D03*
X1066820Y151632D03*
X1067220Y142862D03*
Y148362D03*
X1058028Y246518D03*
X1055528D03*
X1068093Y265503D03*
X1058428Y261118D03*
X1055928D03*
X1067618Y273800D03*
X1070718Y273700D03*
X1067718Y288500D03*
X1070618D03*
X1067718Y285600D03*
X1070618D03*
X1072310Y364422D03*
X1059943Y435314D03*
X1062120Y477462D03*
X1056190Y520760D03*
X1058220Y585862D03*
X1061470D03*
X1056280Y601232D03*
X1056220Y605052D03*
X1055205Y744853D03*
X1066462Y1520088D03*
X1062464Y1554262D03*
X1059368Y1554364D03*
X1059898Y1604000D03*
X1078609Y49388D03*
X1075100Y55682D03*
X1071920Y53862D03*
X1084146Y67102D03*
X1079114Y75775D03*
X1080168Y90721D03*
X1078270Y93462D03*
X1081282Y180937D03*
X1086756Y187540D03*
X1084130Y298342D03*
X1086630D03*
X1076353Y363966D03*
X1078853D03*
X1077270Y369061D03*
Y374131D03*
Y379251D03*
X1087330Y369061D03*
Y374131D03*
Y379251D03*
X1078151Y413911D03*
X1078120Y411262D03*
X1084245Y435437D03*
X1078545Y435637D03*
X1081045D03*
X1087280Y435437D03*
X1073724Y476867D03*
X1081906Y472577D03*
X1076598Y477087D03*
X1081930Y477132D03*
X1079320Y473892D03*
X1076820D03*
X1076739Y506461D03*
X1073589D03*
X1077751Y522235D03*
X1082220Y522362D03*
X1085720Y522422D03*
X1073250Y582332D03*
X1084637Y744635D03*
X1074010Y1510650D03*
X1077734Y1554364D03*
X1085830Y1554262D03*
X1082734Y1554364D03*
X1084000Y1647110D03*
X1072208Y1731911D03*
X1098609Y49388D03*
X1097794Y67881D03*
X1094644Y67992D03*
X1102561Y78461D03*
X1102480Y133722D03*
X1105580Y132822D03*
X1100630Y130376D03*
X1099030Y245140D03*
X1089130Y298342D03*
X1091630D03*
X1094130D03*
X1105553Y356475D03*
X1089660Y408560D03*
X1095820Y420762D03*
X1090245Y435437D03*
X1096477Y744385D03*
X1093497Y744655D03*
X1105480Y1517982D03*
X1101600Y1554364D03*
X1104750Y1549346D03*
X1095436Y1603944D03*
X1092436D03*
X1088790Y1641830D03*
X1094225Y1671710D03*
X1091880Y1673720D03*
X1092072Y1734244D03*
X1118609Y49388D03*
X1110977Y55505D03*
X1110754Y60028D03*
X1113594Y69862D03*
X1109020Y80592D03*
X1118309Y111687D03*
X1115860Y113883D03*
X1118486Y208942D03*
X1120190Y255652D03*
X1117820Y456132D03*
X1113207Y744455D03*
X1118110Y1398010D03*
X1115853Y1426342D03*
Y1435532D03*
X1117574Y1448604D03*
X1114400Y1518237D03*
X1110725Y1518046D03*
X1109118Y1526046D03*
X1113725Y1530935D03*
X1115802Y1615010D03*
X1117407Y1628495D03*
X1113990Y1631370D03*
X1113325Y1627975D03*
X1117182Y1625460D03*
X1106480Y1641275D03*
X1113110Y1666460D03*
X1108320Y1680200D03*
X1112130Y1711600D03*
X1112252Y1706170D03*
X1112200Y1709000D03*
X1114150Y1715726D03*
X1110663Y1719189D03*
X1119200Y1730300D03*
Y1727200D03*
X1114300Y1722700D03*
X1119300Y1724100D03*
X1111866Y1737108D03*
X1132856Y52926D03*
X1129948Y66786D03*
X1132547Y64864D03*
X1129997Y69864D03*
X1122278Y107549D03*
X1120420Y109829D03*
X1124858Y197309D03*
X1128485Y198159D03*
X1133041Y194137D03*
X1124360Y259712D03*
X1125409Y305797D03*
X1120544Y312200D03*
X1129995Y301637D03*
X1122059Y305673D03*
X1124985Y302578D03*
X1127402Y456174D03*
X1136051Y503324D03*
X1124120Y643762D03*
X1136720Y641362D03*
X1133720Y642862D03*
X1129420Y644062D03*
X1122980Y741312D03*
X1127972Y747250D03*
X1135750Y1255672D03*
X1129729Y1385200D03*
X1124679D03*
X1127179D03*
X1127788Y1397126D03*
X1135709Y1397119D03*
X1133209D03*
X1131629Y1420615D03*
X1129029D03*
X1134229D03*
X1123674Y1414936D03*
X1121174D03*
X1123674Y1417536D03*
Y1420136D03*
X1121174Y1417536D03*
Y1420136D03*
X1131629Y1423722D03*
X1129029D03*
X1134229D03*
X1123674Y1422736D03*
X1121174D03*
X1131042Y1436061D03*
X1135942D03*
X1133512D03*
X1131042Y1430461D03*
X1135942D03*
X1133512D03*
X1134429Y1426829D03*
X1122879Y1431474D03*
Y1434024D03*
X1125995Y1439780D03*
X1136004Y1447858D03*
X1126117Y1450504D03*
X1123379Y1443583D03*
X1133169Y1445690D03*
X1129169Y1442998D03*
X1135568Y1442923D03*
X1129169Y1445719D03*
X1127008Y1524203D03*
X1135748Y1524187D03*
X1127008Y1550285D03*
X1133780Y1550301D03*
X1132142Y1555301D03*
X1132187Y1582738D03*
X1135187D03*
X1132187Y1590738D03*
X1135187D03*
X1120472Y1615010D03*
X1124862D03*
X1127377Y1628485D03*
X1131632Y1625969D03*
X1131866Y1737108D03*
X1138609Y49388D03*
X1145603Y73679D03*
X1140242Y101135D03*
X1152720Y180862D03*
X1150914Y197407D03*
X1148795Y213731D03*
X1141957Y227277D03*
X1144457D03*
X1139457D03*
X1148354Y222677D03*
X1146670Y230110D03*
X1147700Y362731D03*
X1140465Y379592D03*
X1142302Y366532D03*
X1137315Y379592D03*
X1147700Y368041D03*
X1148220Y501362D03*
X1138551Y503324D03*
X1144720Y501362D03*
Y498662D03*
X1142967Y592097D03*
X1138500Y586362D03*
X1142127Y586452D03*
X1140697Y608762D03*
X1150140Y610362D03*
X1142790Y611122D03*
X1144810Y613762D03*
X1150272Y638346D03*
X1142674Y1287608D03*
X1144247Y1385200D03*
X1149297D03*
X1146797D03*
X1146118Y1397126D03*
X1138209Y1397119D03*
X1150843Y1415126D03*
X1148243D03*
X1150843Y1417726D03*
X1148243D03*
X1150732Y1420326D03*
X1142629Y1420615D03*
X1145573Y1420631D03*
X1139429Y1420615D03*
X1136829D03*
X1145573Y1423738D03*
X1136829Y1423722D03*
X1145542Y1426861D03*
X1137029Y1426829D03*
X1146563Y1436334D03*
X1141903D03*
X1144233Y1435584D03*
X1139573D03*
X1149469Y1437098D03*
X1151669Y1435698D03*
Y1438598D03*
X1137311Y1445191D03*
X1147203Y1441968D03*
X1149569Y1440098D03*
X1151669Y1441498D03*
X1147203Y1439068D03*
X1150821Y1459607D03*
Y1456587D03*
X1145108Y1476732D03*
X1138430Y1524150D03*
X1151497Y1524187D03*
X1153465Y1550301D03*
X1149528D03*
X1145410Y1540640D03*
X1143060Y1538380D03*
X1141654Y1550301D03*
X1137717Y1558020D03*
X1141690Y1552920D03*
X1152187Y1574738D03*
X1142187D03*
X1145187D03*
X1142187Y1582738D03*
X1145187D03*
X1152187D03*
X1141525Y1597630D03*
X1152187Y1590738D03*
X1142187D03*
X1145187D03*
X1140750Y1604330D03*
X1150380Y1602590D03*
X1139392Y1620851D03*
X1146960Y1618960D03*
X1152257Y1628910D03*
X1158609Y49388D03*
X1155703Y73679D03*
X1160720Y180862D03*
X1165440Y176450D03*
X1168710Y176590D03*
X1165000Y190962D03*
X1162500D03*
X1164300Y197262D03*
X1159460Y194090D03*
X1163732Y204887D03*
X1160732D03*
X1160630Y213870D03*
X1158172Y230157D03*
X1159753Y361281D03*
X1159460Y366025D03*
X1156790Y363231D03*
Y373231D03*
X1161690Y374110D03*
X1164320Y451062D03*
X1156100Y456342D03*
X1167190Y526922D03*
X1153467Y586462D03*
X1158300Y585862D03*
X1170740Y602132D03*
X1153490Y610322D03*
X1159912Y638216D03*
X1166722Y636206D03*
X1158762Y642266D03*
X1168402Y642136D03*
X1155962Y746193D03*
X1156609Y1286685D03*
X1167829Y1385200D03*
X1162779D03*
X1165279D03*
X1165931Y1397126D03*
X1154714Y1398295D03*
X1157786Y1398252D03*
X1167172Y1420615D03*
X1153913Y1420606D03*
Y1415406D03*
Y1418006D03*
X1159124D03*
Y1420606D03*
Y1415406D03*
X1161724D03*
Y1420606D03*
Y1418006D03*
X1156524Y1415406D03*
Y1420606D03*
Y1418006D03*
X1167172Y1423722D03*
X1153913Y1423206D03*
X1159124D03*
X1161724D03*
X1156524D03*
X1161022Y1431499D03*
Y1433999D03*
X1164138Y1439780D03*
X1154288Y1432502D03*
X1155964Y1440864D03*
X1164260Y1450423D03*
X1158954Y1450274D03*
X1161522Y1443630D03*
X1167312Y1442998D03*
Y1445964D03*
X1159386Y1464253D03*
Y1466753D03*
X1156386Y1464253D03*
Y1466753D03*
X1159386Y1469253D03*
X1156386D03*
X1153821Y1459607D03*
Y1456587D03*
X1159386Y1461753D03*
X1159476Y1458918D03*
X1156386Y1461753D03*
X1156476Y1458918D03*
X1159446Y1456113D03*
X1156446D03*
X1167245Y1524187D03*
X1159371D03*
X1163308D03*
X1155433D03*
X1165276Y1550301D03*
X1169213D03*
X1157402D03*
X1161339D03*
X1161595Y1574738D03*
X1164595D03*
X1155187D03*
X1161595Y1582738D03*
X1164595D03*
X1155187D03*
X1163079Y1601479D03*
X1161595Y1590738D03*
X1164595D03*
X1155187D03*
X1168192Y1604130D03*
X1152950Y1616470D03*
X1165950Y1617729D03*
X1169460Y1606630D03*
Y1616630D03*
Y1611630D03*
X1152930Y1633880D03*
X1158030Y1619250D03*
X1164830Y1628830D03*
X1163970Y1620600D03*
X1169325Y1642600D03*
X1158325D03*
X1162383Y1652505D03*
X1164830Y1654632D03*
X1159930D03*
X1161076Y1680624D03*
X1157700Y1681100D03*
X1174120Y57111D03*
X1175926Y69151D03*
X1180676Y106858D03*
X1187413Y143132D03*
X1181420Y157962D03*
X1181700Y186962D03*
X1173314Y176452D03*
X1184510Y188962D03*
X1173065Y194174D03*
X1183460Y205342D03*
X1181470Y208802D03*
X1172865Y210174D03*
X1181500Y222162D03*
X1172795Y222174D03*
X1180398Y289814D03*
X1186653Y302242D03*
X1171540Y310902D03*
X1181450Y306052D03*
X1174120Y355362D03*
X1169690Y526922D03*
X1172720Y527862D03*
X1172310Y584562D03*
X1181300Y584762D03*
X1174980Y585632D03*
X1174880Y592652D03*
X1170337Y607327D03*
X1173990Y602192D03*
X1177570Y602052D03*
X1175217Y595762D03*
X1176362Y636076D03*
X1180262Y642216D03*
X1183230Y739102D03*
X1173020Y745972D03*
X1175573Y1286765D03*
X1172573D03*
X1182747Y1385200D03*
X1185297D03*
X1184661Y1397126D03*
X1171752Y1397119D03*
X1176752D03*
X1174252D03*
X1183716Y1420631D03*
X1180772Y1420615D03*
X1174972D03*
X1177572D03*
X1172372D03*
X1169772D03*
X1183716Y1423738D03*
X1174972Y1423722D03*
X1172372D03*
X1169772D03*
X1174085Y1436061D03*
Y1430461D03*
X1171655Y1436061D03*
X1169185D03*
X1171655Y1430461D03*
X1169185D03*
X1183685Y1426861D03*
X1175172Y1426829D03*
X1172572D03*
X1184706Y1436334D03*
X1180046D03*
X1182376Y1435584D03*
X1177716D03*
X1174147Y1447858D03*
X1171342Y1445650D03*
X1175454Y1445191D03*
X1173711Y1442923D03*
X1179922Y1524203D03*
X1171182Y1524187D03*
X1179922Y1550285D03*
X1184330Y1573260D03*
X1184290Y1570080D03*
X1171595Y1574738D03*
X1174595D03*
X1171595Y1582738D03*
X1174595D03*
X1183410Y1594450D03*
X1183440Y1591640D03*
X1171595Y1590738D03*
X1174595D03*
X1178140Y1601100D03*
X1184200Y1599900D03*
X1183320Y1597080D03*
X1184501Y1606521D03*
X1169968Y1602370D03*
X1174550Y1615630D03*
X1178250Y1609100D03*
X1184200Y1602700D03*
X1185030Y1633010D03*
X1182470Y1618914D03*
X1172530Y1623020D03*
X1176900Y1627510D03*
X1185030Y1624660D03*
X1180325Y1642600D03*
X1173383Y1652505D03*
X1184383D03*
X1181930Y1654632D03*
X1175830D03*
X1170930D03*
X1183076Y1680624D03*
X1172076D03*
X1198609Y49388D03*
X1194478Y56986D03*
X1188720Y56755D03*
X1191700Y56822D03*
X1197520Y56962D03*
X1201158Y57130D03*
X1189393Y60183D03*
X1185500Y101400D03*
X1190700Y99000D03*
X1188700Y100700D03*
X1185400Y104000D03*
X1197627Y132859D03*
X1193532Y132644D03*
X1194800Y143112D03*
X1197414Y161592D03*
X1191020Y170862D03*
X1185420Y153762D03*
X1200720Y184862D03*
X1196100Y188962D03*
X1193500D03*
X1200720Y187862D03*
X1200963Y212648D03*
X1192600Y217662D03*
X1193000Y204486D03*
X1195500D03*
X1195100Y217662D03*
X1200830Y206002D03*
X1188600Y225962D03*
X1194840Y240672D03*
X1187013Y238972D03*
X1194840Y236592D03*
X1199720Y252362D03*
X1196720D03*
X1188810Y296088D03*
X1186280Y298972D03*
X1199027Y588714D03*
X1193198Y586172D03*
X1195698D03*
X1198198D03*
X1200698D03*
X1189902Y642086D03*
X1185687Y744475D03*
X1187797Y1385200D03*
X1189135Y1397529D03*
X1187736Y1420387D03*
X1188986Y1415287D03*
Y1417887D03*
X1186386Y1415287D03*
Y1417887D03*
X1191486Y1415287D03*
Y1417887D03*
X1190444Y1420384D03*
X1194750Y1424672D03*
X1197700Y1432672D03*
X1191930Y1424647D03*
X1187412Y1437498D03*
X1189612Y1436098D03*
X1191918Y1432516D03*
X1198010Y1441902D03*
X1185346Y1442128D03*
X1187512Y1440498D03*
X1189612Y1441898D03*
X1185346Y1439228D03*
X1189612Y1438998D03*
X1198880Y1457162D03*
X1187720Y1517688D03*
X1187830Y1522188D03*
X1198546Y1520188D03*
X1187830Y1526688D03*
X1198546Y1524688D03*
X1187720Y1536362D03*
X1198485Y1534313D03*
X1198436Y1529362D03*
X1187720Y1531862D03*
Y1553692D03*
X1198497Y1539667D03*
X1187720Y1548772D03*
X1198436Y1546492D03*
X1187720Y1544292D03*
X1198436Y1551192D03*
Y1556192D03*
X1197181Y1563587D03*
X1198436Y1561062D03*
X1187720Y1558682D03*
Y1563182D03*
X1194510Y1563076D03*
X1187600Y1622064D03*
X1201600Y1633790D03*
X1199400Y1627800D03*
X1190895Y1642910D03*
X1186000Y1640000D03*
X1197400Y1654942D03*
X1192500D03*
X1186830Y1654632D03*
X1193646Y1680934D03*
X1201106Y1677873D03*
X1190735Y1688390D03*
X1194793Y1698295D03*
X1201505Y1688435D03*
X1192340Y1700422D03*
X1197240D03*
X1193174Y1726414D03*
X1191866Y1737108D03*
X1213026Y56742D03*
X1216176D03*
X1201800Y94600D03*
X1202860Y120392D03*
X1215763Y114363D03*
X1206093Y120362D03*
X1204800Y108900D03*
X1206900Y115900D03*
X1215800Y111300D03*
X1201700Y110000D03*
X1202920Y117162D03*
X1210910Y129502D03*
X1206114Y132962D03*
X1206434Y129492D03*
X1206694Y139512D03*
X1214573Y148909D03*
X1214415Y153962D03*
X1206664Y158952D03*
X1214091Y164962D03*
X1214593Y168962D03*
X1214534Y157462D03*
X1214054Y186092D03*
X1208518Y174162D03*
X1203858Y185451D03*
X1213720Y200309D03*
X1204420Y195362D03*
X1213720Y189362D03*
X1204220D03*
X1213720Y195362D03*
X1215720Y204862D03*
X1203200Y202514D03*
X1219060Y213312D03*
X1210084Y224362D03*
X1206660Y224742D03*
X1213540Y224792D03*
X1207220Y247148D03*
X1217720Y249862D03*
X1207220Y243998D03*
X1210900Y265300D03*
X1208365Y271151D03*
X1204475Y350684D03*
X1205165Y380962D03*
X1218870Y418082D03*
X1214000Y599262D03*
X1208980Y598462D03*
X1207100Y600882D03*
X1204880Y754032D03*
X1211277Y744265D03*
X1206757Y744455D03*
X1210288Y754081D03*
X1202300Y753962D03*
X1207607Y754095D03*
X1202600Y759662D03*
X1215896Y756942D03*
X1206432Y758995D03*
X1202307Y757082D03*
X1205820Y1652910D03*
X1210830Y1676500D03*
X1217210Y1684520D03*
X1212305Y1688700D03*
X1216363Y1698605D03*
X1205563Y1698340D03*
X1207180Y1685680D03*
X1208010Y1700467D03*
X1213910Y1700732D03*
X1203110Y1700467D03*
X1203939Y1726459D03*
X1214834Y1726724D03*
X1211866Y1737108D03*
X1218609Y49388D03*
X1228420Y58862D03*
X1230250Y89450D03*
X1228425Y91500D03*
X1222100Y91600D03*
X1225100Y91500D03*
X1225700Y108962D03*
X1228704Y112122D03*
X1232182Y110659D03*
X1224614Y116962D03*
X1219534Y116492D03*
X1223500Y111162D03*
X1223100Y127300D03*
X1226400Y125200D03*
X1226093Y134262D03*
X1229500Y125100D03*
X1223100Y130700D03*
X1226093Y152792D03*
X1234093Y144962D03*
X1226093Y140962D03*
X1222593D03*
X1222920Y144909D03*
Y148909D03*
X1222593Y168962D03*
X1222890Y157002D03*
X1226093Y156962D03*
X1222594Y154242D03*
X1226093Y168162D03*
X1225874Y163462D03*
X1222720Y163362D03*
X1226093Y177962D03*
X1222724Y176102D03*
X1226093Y172962D03*
X1223134Y190802D03*
X1225574Y188662D03*
X1228520Y202162D03*
X1229720Y197302D03*
X1226093Y193462D03*
X1225320Y200162D03*
X1233282Y201875D03*
X1223720Y217862D03*
Y205862D03*
X1223180Y210552D03*
X1233780Y214572D03*
X1231720Y217862D03*
Y209862D03*
X1232000Y244332D03*
Y248332D03*
X1219220Y243862D03*
Y247148D03*
X1230720Y380362D03*
X1227500Y380400D03*
X1221220Y380362D03*
X1232720Y377862D03*
X1224300Y380400D03*
X1223650Y520672D03*
X1230650D03*
X1227150D03*
X1219060Y757272D03*
X1223327Y757615D03*
X1228320Y758598D03*
X1218810Y1700732D03*
X1231866Y1737108D03*
X1238609Y49388D03*
X1236620Y58862D03*
X1239907Y95008D03*
X1241010Y110782D03*
X1243808Y116832D03*
X1250010Y117121D03*
X1244200Y112862D03*
X1249362Y111600D03*
X1241035Y114399D03*
X1247333Y121999D03*
X1234746Y136040D03*
X1240728Y136198D03*
X1240904Y151592D03*
X1238604Y150062D03*
X1241100Y145842D03*
X1242520Y165362D03*
X1244120Y167462D03*
X1246272Y164889D03*
X1243100Y160181D03*
X1236410Y201462D03*
X1236593Y197462D03*
X1236584Y205762D03*
X1236593Y209562D03*
X1236584Y217462D03*
X1236520Y213462D03*
X1245486Y203000D03*
X1245593Y211762D03*
X1236620Y221562D03*
X1245614Y227462D03*
X1245574Y234042D03*
X1244720Y230362D03*
X1245593Y219662D03*
X1239045Y224062D03*
X1245593Y241462D03*
Y237462D03*
X1240500Y248332D03*
Y244332D03*
X1246444Y256098D03*
X1236720Y257362D03*
X1252040Y306480D03*
X1243589Y379595D03*
X1236720Y377862D03*
X1234720Y380362D03*
X1248150Y520672D03*
X1244650D03*
X1241150D03*
X1237650D03*
X1234150D03*
X1242260Y757602D03*
X1258609Y49388D03*
X1261227Y52061D03*
X1258727D03*
X1263454Y83060D03*
X1266464Y83090D03*
X1264098Y88787D03*
X1262320Y96012D03*
X1262800Y101100D03*
X1264620Y92724D03*
X1258539Y100900D03*
X1252520Y92022D03*
X1258539Y109263D03*
X1260641Y114399D03*
X1252961Y111903D03*
X1264220Y110462D03*
X1250424Y108943D03*
X1257581Y114579D03*
X1266093Y129962D03*
X1256093Y143462D03*
Y149462D03*
X1264663Y158946D03*
X1254994Y157382D03*
X1265010Y162222D03*
X1264685Y175506D03*
X1261899Y174648D03*
X1253624Y201362D03*
X1267315Y220701D03*
X1264874Y217462D03*
X1256504D03*
X1255613Y209568D03*
X1265207Y208442D03*
X1259703Y209808D03*
X1253440Y230552D03*
X1253860Y235622D03*
X1256070Y229512D03*
X1256593Y233972D03*
Y225972D03*
X1253950Y246692D03*
X1266715Y244692D03*
X1254370Y241302D03*
X1265065Y249982D03*
X1256494Y243177D03*
X1256574Y238662D03*
X1266518Y237042D03*
X1256584Y248002D03*
X1256454Y252122D03*
X1264854Y253996D03*
Y256496D03*
X1258883Y280558D03*
X1258250Y292986D03*
X1263150Y294726D03*
X1267150Y305998D03*
X1256220Y434362D03*
X1261220Y454362D03*
X1253220Y451362D03*
X1267220D03*
X1260220Y477362D03*
X1255920Y511362D03*
X1251650Y520672D03*
X1255150D03*
X1256787Y749605D03*
X1258667Y751405D03*
X1255520Y747362D03*
X1263486Y739949D03*
X1253586Y1334649D03*
X1257586D03*
X1257672Y1351008D03*
X1251866Y1737108D03*
X1276820Y58142D03*
X1282360Y58132D03*
X1279580D03*
X1278300Y81232D03*
X1279390Y87697D03*
X1275820Y87962D03*
X1270329Y101011D03*
X1266722Y101005D03*
X1278456Y96187D03*
X1279415Y90847D03*
X1281704Y95402D03*
X1279485Y105752D03*
X1282824Y108872D03*
X1271284Y108971D03*
X1276745Y125850D03*
X1275807Y132922D03*
X1278949Y123567D03*
X1282764Y135398D03*
X1281600Y137962D03*
X1277820Y140682D03*
X1281093Y144516D03*
X1271954Y159143D03*
X1271593Y165962D03*
X1278093Y184462D03*
X1278993Y193262D03*
X1273093Y200038D03*
X1278183Y201262D03*
X1275493Y193962D03*
X1272893Y191262D03*
X1271315Y220701D03*
X1282568Y212722D03*
X1267773Y208373D03*
X1273093Y213962D03*
X1275727Y209597D03*
X1267618Y225382D03*
X1277661Y225685D03*
X1267593Y229462D03*
X1278783Y221386D03*
X1282176Y221436D03*
X1282654Y226309D03*
X1278320Y239292D03*
X1282293Y248962D03*
X1279493Y248662D03*
X1282645Y255671D03*
Y252271D03*
X1280223Y256841D03*
X1279841Y253052D03*
X1277771Y255173D03*
X1273754Y256504D03*
X1275557Y269477D03*
Y272436D03*
X1282653Y269446D03*
X1278557Y272436D03*
Y269477D03*
X1272557Y272436D03*
X1276800Y276562D03*
X1269960Y294536D03*
X1272530Y429362D03*
X1284220D03*
X1280270Y434362D03*
X1272220D03*
X1278380Y463362D03*
X1276220Y477362D03*
X1283220D03*
X1269220D03*
X1274420Y463362D03*
X1275576Y730879D03*
X1266727Y752955D03*
X1280135Y1340002D03*
Y1337402D03*
X1272707Y1334865D03*
X1279812Y1353552D03*
X1279334Y1356089D03*
X1275856Y1358098D03*
X1271990Y1358079D03*
X1276891Y1362891D03*
X1282928Y1361833D03*
X1269012Y1371693D03*
Y1368293D03*
X1271866Y1737108D03*
X1291280Y58262D03*
X1293860Y58312D03*
X1285201Y58121D03*
X1293430Y84072D03*
X1293454Y81232D03*
X1289210D03*
X1298640Y93062D03*
X1292880Y93162D03*
X1292899Y98519D03*
X1294354Y103166D03*
Y105912D03*
X1291704Y109427D03*
X1288093Y125962D03*
X1284930Y124922D03*
X1291478Y137745D03*
X1286150Y131092D03*
X1295053Y140181D03*
X1285793Y141562D03*
X1292293Y143162D03*
X1288258Y145501D03*
X1283781Y149115D03*
X1297605Y145824D03*
X1283781Y155788D03*
X1283425Y179272D03*
X1283397Y202085D03*
X1287943Y233748D03*
X1284437Y230280D03*
X1293893Y237962D03*
X1285710Y249182D03*
X1290293Y247562D03*
X1288637Y240448D03*
X1292630Y240462D03*
X1286611Y260908D03*
X1290005Y293768D03*
X1295278Y297056D03*
X1290322D03*
X1294500Y299692D03*
X1291100D03*
X1295887Y315571D03*
X1291500Y312862D03*
Y315362D03*
X1291420Y320662D03*
Y318162D03*
X1295540Y440902D03*
X1301310Y440862D03*
X1291220Y463362D03*
X1294440Y477267D03*
X1296630Y463462D03*
X1300220Y477362D03*
X1284220Y463362D03*
X1289936Y732539D03*
X1294937Y746965D03*
X1290520Y746562D03*
X1292904Y782048D03*
X1292572Y785575D03*
X1292614Y789910D03*
X1297298Y790982D03*
X1295150Y1323217D03*
X1298150D03*
X1291010Y1323307D03*
X1288010D03*
X1290102Y1365789D03*
X1286102Y1365051D03*
X1294312Y1367279D03*
X1292840Y1364821D03*
X1286102Y1368107D03*
X1291866Y1737108D03*
X1311960Y49672D03*
X1301820Y58672D03*
X1314741Y68652D03*
X1311424D03*
X1308174D03*
X1311960Y58152D03*
X1311260Y83032D03*
X1310857Y78542D03*
X1307120Y78562D03*
X1310906Y97807D03*
X1314406Y97756D03*
X1300454Y95302D03*
X1308274Y104162D03*
X1314059Y93877D03*
X1307244Y118452D03*
X1306836Y108242D03*
X1302080Y117032D03*
X1302060Y113852D03*
X1302964Y124633D03*
X1300990Y121812D03*
X1315156Y130656D03*
X1314920Y135361D03*
X1301993Y140462D03*
X1313117Y250605D03*
X1314685Y248651D03*
X1313950Y261612D03*
X1307431Y256099D03*
X1309283Y254162D03*
X1311275Y252297D03*
X1305552Y257974D03*
X1308736Y284948D03*
X1312136D03*
X1308790Y290172D03*
X1302450Y290072D03*
X1307798Y287561D03*
X1313246Y287631D03*
X1307042Y292636D03*
X1303642D03*
X1307442Y306998D03*
X1304042D03*
X1308220Y304262D03*
X1303120Y304162D03*
X1307677Y322996D03*
X1311077D03*
X1314450Y319841D03*
X1312845Y324764D03*
X1305909D03*
X1317100Y553900D03*
X1308600Y653500D03*
X1303576Y659671D03*
X1311420Y738262D03*
X1305187Y735630D03*
X1315020Y739862D03*
X1307469Y787772D03*
X1303017Y785837D03*
X1301034Y784165D03*
X1304260Y788265D03*
X1309930Y789852D03*
X1306701Y794779D03*
X1305117Y797125D03*
X1309210Y792802D03*
X1304066Y1323578D03*
X1305056Y1337104D03*
Y1326704D03*
Y1334504D03*
Y1329304D03*
Y1331904D03*
X1311820Y1330518D03*
Y1333018D03*
X1314936Y1338799D03*
X1312650Y1342572D03*
X1311866Y1737108D03*
X1318609Y49388D03*
X1316459Y58697D03*
X1330102Y59025D03*
X1322248Y68487D03*
X1321279Y58767D03*
X1317831Y68652D03*
X1322415Y75480D03*
X1327920Y84418D03*
X1322906Y94212D03*
X1319968Y98266D03*
X1316478Y92970D03*
X1329891Y99455D03*
X1329646Y104954D03*
X1322906Y109733D03*
X1330273Y128373D03*
X1323958Y146227D03*
X1326493Y249562D03*
X1323912Y245111D03*
X1317893Y257462D03*
X1328393Y264262D03*
X1320387Y258901D03*
X1325769Y259001D03*
X1325414Y293556D03*
X1328814D03*
X1319903Y299176D03*
X1323303D03*
X1319125Y296540D03*
X1324081D03*
X1324636Y290920D03*
X1329592D03*
X1319618Y318073D03*
X1325080Y323902D03*
X1316218Y318073D03*
X1328480Y323902D03*
X1330248Y325670D03*
X1323312D03*
X1321386Y319841D03*
X1329977Y334384D03*
X1330101Y540049D03*
X1327601D03*
X1328530Y747702D03*
X1325210Y744322D03*
X1322110Y1342755D03*
X1318110Y1342017D03*
X1326320Y1344245D03*
X1324848Y1341787D03*
X1318110Y1345073D03*
X1338609Y49388D03*
X1333190Y58825D03*
X1346720Y82912D03*
X1347640Y101950D03*
X1345583Y91307D03*
X1336549Y105970D03*
X1339280Y126175D03*
X1344631Y127244D03*
X1332497Y133931D03*
X1343034Y141698D03*
X1333811Y235348D03*
X1343362Y283155D03*
X1336761Y293404D03*
X1340161D03*
X1335947Y290755D03*
X1340903D03*
X1335145Y332616D03*
X1341431Y322693D03*
X1331745Y332616D03*
X1338031Y322693D03*
X1345424Y328981D03*
X1343656Y330749D03*
X1343199Y324461D03*
X1336263D03*
X1336913Y334384D03*
X1344720Y423162D03*
X1337220D03*
X1342220D03*
X1339720D03*
X1333143Y540049D03*
X1340420Y538422D03*
Y541822D03*
X1338652Y536654D03*
Y543590D03*
X1335643Y540048D03*
X1336187Y755635D03*
X1339784Y1306506D03*
X1337184D03*
X1337663Y1301001D03*
X1343968Y1300579D03*
X1340663Y1301001D03*
X1337184Y1309106D03*
Y1314306D03*
Y1311706D03*
X1343948Y1317092D03*
Y1319592D03*
X1344532Y1328161D03*
X1347397Y1325320D03*
X1331866Y1737108D03*
X1348610Y84712D03*
X1349480Y77072D03*
X1366369Y83820D03*
X1350550Y101632D03*
X1349570Y104147D03*
X1356223Y131569D03*
X1353394Y131812D03*
X1348620Y136162D03*
X1362793Y145262D03*
X1349704Y145385D03*
X1357888Y145893D03*
X1349220Y140362D03*
X1361111Y236448D03*
X1363846Y279848D03*
X1349362Y283155D03*
X1353902Y287540D03*
X1359902D03*
X1348824Y328981D03*
X1358371Y332275D03*
X1361771D03*
X1350592Y330749D03*
X1355200Y337843D03*
X1351800D03*
X1356968Y339611D03*
X1350032D03*
X1363539Y334043D03*
X1356603D03*
X1356220Y581862D03*
X1356047Y680000D03*
X1358907Y681262D03*
X1361727Y680665D03*
X1353982Y1287048D03*
X1362382D03*
X1359382D03*
X1350982D03*
X1354238Y1329329D03*
X1350238Y1328591D03*
X1358448Y1330819D03*
X1356976Y1328361D03*
X1350238Y1331647D03*
X1355357Y1396020D03*
X1364860Y1455172D03*
X1362410Y1445272D03*
X1351866Y1737108D03*
X1378839Y87626D03*
X1366124Y101529D03*
X1366369Y92450D03*
X1378550Y110692D03*
X1366714Y109506D03*
X1366868Y147341D03*
X1369593Y147462D03*
X1369916Y154132D03*
X1379969Y176330D03*
X1370586Y176366D03*
X1376991Y176430D03*
X1373591D03*
X1370405Y186938D03*
X1377597Y197604D03*
X1375300Y208422D03*
X1369479Y208384D03*
X1370636Y227292D03*
X1369410Y224504D03*
X1375619Y236261D03*
X1375257Y229756D03*
X1373493Y227762D03*
X1378452Y236055D03*
X1377742Y244372D03*
Y250372D03*
X1377626Y258914D03*
Y264914D03*
X1369846Y279848D03*
X1372381Y661428D03*
X1371931Y672978D03*
Y685278D03*
X1370207Y682245D03*
X1372243Y697108D03*
Y709108D03*
Y721108D03*
X1375463Y1287048D03*
X1372463D03*
X1371912Y1303480D03*
X1376208Y1303319D03*
X1371912Y1300880D03*
X1376208Y1300719D03*
Y1295586D03*
X1371912Y1295747D03*
Y1298280D03*
X1376208Y1298119D03*
X1369312Y1303480D03*
Y1300880D03*
Y1295747D03*
Y1298280D03*
X1376076Y1317092D03*
Y1319592D03*
X1379192Y1325373D03*
X1377214Y1327653D03*
X1377054Y1394028D03*
X1376666Y1402778D03*
X1376686Y1399758D03*
X1367316Y1399053D03*
Y1403458D03*
X1370577Y1421899D03*
X1377060Y1411231D03*
X1367436Y1414778D03*
X1370891Y1410306D03*
X1378417Y1415292D03*
X1367316Y1407458D03*
X1367889Y1419235D03*
X1371960Y1436172D03*
X1365040Y1431142D03*
X1377075Y1425014D03*
X1365235Y1428637D03*
X1370250Y1433715D03*
X1367620Y1431472D03*
X1367170Y1453142D03*
X1368842Y1449261D03*
X1364800Y1449231D03*
X1368980Y1457122D03*
X1370041Y1460374D03*
X1371866Y1737108D03*
X1393250Y93802D03*
X1383480Y88932D03*
X1389609Y145291D03*
X1389443Y147859D03*
X1386684Y145017D03*
X1386404Y149008D03*
X1394182Y171470D03*
X1398182D03*
X1386780Y197668D03*
X1395321D03*
X1395960Y226422D03*
X1393460D03*
X1386868Y222937D03*
X1384017Y223697D03*
X1386138Y225411D03*
X1384895Y221346D03*
X1381951Y221420D03*
X1381235Y236020D03*
X1383734Y243329D03*
Y237329D03*
X1388778Y250661D03*
X1390600Y248262D03*
X1388908Y260301D03*
X1386237Y265620D03*
Y275200D03*
X1385190Y501242D03*
X1390220Y497742D03*
X1392685Y498992D03*
X1387550Y502922D03*
X1387600Y499182D03*
X1391260Y507082D03*
X1381131Y656378D03*
Y668378D03*
X1395831Y666278D03*
X1386931Y660978D03*
X1381131Y680278D03*
X1396031Y680678D03*
X1386931Y675478D03*
X1387143Y690208D03*
X1380731Y692208D03*
X1395631Y695108D03*
X1380731Y704208D03*
X1387143Y704708D03*
X1380731Y716208D03*
X1395631Y709608D03*
X1387143Y719235D03*
X1395631Y724135D03*
X1382920Y733725D03*
X1391408Y738625D03*
X1384173Y1161549D03*
X1384089Y1153369D03*
X1386673Y1161520D03*
Y1153340D03*
X1384173Y1169599D03*
X1386673Y1169570D03*
X1386366Y1329329D03*
X1382366Y1328591D03*
X1390576Y1330819D03*
X1389104Y1328361D03*
X1382366Y1331647D03*
X1396311Y1385712D03*
X1398680Y1380582D03*
X1390474Y1385142D03*
X1387074Y1384272D03*
X1388813Y1393160D03*
X1396115Y1405289D03*
X1390513Y1395452D03*
X1387066Y1401734D03*
X1387291Y1408163D03*
X1396115Y1412789D03*
X1396615Y1420289D03*
X1387470Y1418302D03*
X1385109Y1410427D03*
X1390170Y1423942D03*
X1387068Y1413991D03*
X1384695Y1425047D03*
X1381066Y1425008D03*
X1393630Y1426562D03*
X1388557Y1431645D03*
X1395907Y1430227D03*
X1395443Y1434700D03*
X1398569Y1437860D03*
X1383429Y1427652D03*
X1392620Y1446708D03*
X1389220D03*
X1382600Y1563480D03*
X1391655Y1570037D03*
X1391055Y1565037D03*
X1384840Y1565640D03*
X1386790Y1563610D03*
X1392475Y1576097D03*
X1396600Y1582500D03*
Y1594000D03*
Y1590200D03*
Y1586400D03*
X1393000Y1590300D03*
X1395325Y1606862D03*
X1386200Y1645700D03*
X1386600Y1641400D03*
X1391866Y1737108D03*
X1412954Y138742D03*
X1409558Y151948D03*
X1404402Y138742D03*
X1407029Y152732D03*
X1410370Y138742D03*
X1406970D03*
X1409558Y156904D03*
X1407029Y156132D03*
X1407613Y177159D03*
X1398770D03*
X1402258Y184263D03*
X1411101D03*
X1409716Y171696D03*
X1401240Y171672D03*
X1401341Y177159D03*
X1404829Y184263D03*
X1404741Y177159D03*
X1408229Y184263D03*
X1407178Y171684D03*
X1403778D03*
X1404071Y197668D03*
X1412851D03*
X1404630Y220018D03*
X1412270Y230952D03*
X1413900Y225212D03*
X1396900Y228932D03*
X1405436Y238378D03*
X1400207Y238257D03*
X1407913Y1161569D03*
X1410413Y1153369D03*
X1407913D03*
X1410613Y1161569D03*
X1407913Y1170069D03*
X1410613D03*
X1410819Y1287198D03*
X1407819D03*
X1399419D03*
X1402419D03*
X1404040Y1303480D03*
X1408336Y1303319D03*
X1404040Y1300880D03*
X1408336Y1300719D03*
Y1295586D03*
X1404040Y1295747D03*
Y1298280D03*
X1408336Y1298119D03*
X1401440Y1303480D03*
Y1300880D03*
Y1295747D03*
Y1298280D03*
X1408204Y1317092D03*
Y1319592D03*
X1411320Y1325373D03*
X1408969Y1327645D03*
X1401655Y1384676D03*
X1406461Y1383862D03*
X1415171Y1383692D03*
X1412961Y1387387D03*
X1412608Y1391687D03*
X1403615Y1405289D03*
X1411115D03*
X1414362Y1402191D03*
X1411115Y1412789D03*
X1403615Y1420289D03*
X1411115D03*
X1414786Y1426890D03*
X1413440Y1436774D03*
X1409680Y1430613D03*
X1401371Y1434592D03*
X1410477Y1440117D03*
X1410038Y1434670D03*
X1405876Y1453298D03*
X1403687Y1444711D03*
X1400287D03*
X1403350Y1516435D03*
X1400220Y1518862D03*
X1403590Y1532255D03*
X1403350Y1521335D03*
X1409248Y1528862D03*
X1403740Y1548375D03*
X1403590Y1537155D03*
X1403740Y1543475D03*
X1400160Y1543342D03*
X1404433Y1565037D03*
X1400695Y1570037D03*
X1400715Y1565037D03*
X1407440Y1557552D03*
X1404433Y1570037D03*
X1402536Y1576097D03*
X1398700Y1597800D03*
X1407200Y1591400D03*
X1402680Y1597700D03*
X1411070Y1603282D03*
X1401300Y1619917D03*
X1400000Y1630362D03*
X1410900Y1624800D03*
X1400000Y1626362D03*
Y1642362D03*
Y1634362D03*
Y1638362D03*
X1410500Y1638862D03*
X1396900Y1642100D03*
X1411866Y1737108D03*
X1420222Y184263D03*
X1418268Y171696D03*
X1413950Y184263D03*
X1423110D03*
X1417350D03*
X1426510D03*
X1413350Y220018D03*
X1416020D03*
X1424690D03*
X1424520Y225002D03*
X1416810Y225422D03*
X1428640Y230022D03*
X1428336Y232762D03*
X1415340Y231812D03*
X1418630Y220018D03*
X1422030D03*
X1431430Y251265D03*
X1413847Y239528D03*
X1426020Y261501D03*
X1431430Y256383D03*
Y264060D03*
X1428940Y269292D03*
X1426647Y329050D03*
X1417022Y621419D03*
X1418494Y1329329D03*
X1414494Y1328591D03*
X1422704Y1330819D03*
X1421232Y1328361D03*
X1414494Y1331647D03*
X1418990Y1387452D03*
X1422594Y1383301D03*
X1419995Y1397492D03*
X1415620Y1396652D03*
X1419055Y1392497D03*
X1426872Y1405811D03*
X1423256Y1403728D03*
X1424255Y1396612D03*
X1421480Y1415731D03*
X1422371Y1407722D03*
X1421371Y1411719D03*
X1421864Y1419730D03*
X1419991Y1423404D03*
X1429345Y1433695D03*
X1424930Y1433850D03*
X1416272Y1433949D03*
X1421435Y1430415D03*
X1419746Y1435932D03*
X1427349Y1442776D03*
X1414264Y1439494D03*
X1419256Y1440258D03*
X1423829Y1442776D03*
X1414350Y1516435D03*
X1426020Y1521535D03*
X1414590Y1532255D03*
X1414350Y1521335D03*
X1427120Y1537355D03*
X1414590Y1537155D03*
X1414740Y1543475D03*
Y1548375D03*
X1427320Y1548575D03*
X1416800Y1564862D03*
X1425620Y1556662D03*
X1428403Y1581378D03*
X1418241Y1583441D03*
X1422145Y1575362D03*
X1416060Y1574922D03*
X1422680Y1582100D03*
X1419450Y1596150D03*
X1423700Y1600400D03*
X1426680Y1603262D03*
X1425770Y1633772D03*
X1429250Y1623391D03*
X1419270Y1631000D03*
X1413230Y1641042D03*
X1438609Y49388D03*
X1434600Y59262D03*
X1441125Y57362D03*
X1438680Y64412D03*
X1444275Y57262D03*
X1432220Y61862D03*
X1440800Y66862D03*
X1447340Y157402D03*
X1429382Y184263D03*
X1442434Y210757D03*
X1441490Y224062D03*
X1438720Y220018D03*
X1430000D03*
X1430120Y225182D03*
X1431636Y230448D03*
X1444570Y238372D03*
X1431933Y238125D03*
X1430130Y259342D03*
X1431431Y267378D03*
X1436436Y300319D03*
X1436120Y315772D03*
X1436270Y312592D03*
X1436335Y309407D03*
X1436320Y305862D03*
Y303362D03*
X1436050Y321352D03*
X1436120Y318272D03*
X1436232Y344176D03*
X1437177Y720965D03*
X1433418Y729104D03*
X1435387Y1161569D03*
X1435837Y1153369D03*
X1432887Y1161569D03*
X1433337Y1153369D03*
X1435387Y1170069D03*
X1432887D03*
X1437258Y1287198D03*
X1445106Y1287158D03*
X1440258Y1287198D03*
X1437182Y1298991D03*
X1434582Y1304191D03*
Y1301591D03*
Y1296458D03*
Y1298991D03*
X1440507Y1302830D03*
Y1300230D03*
X1440536Y1296455D03*
X1437182Y1304191D03*
Y1301591D03*
Y1296458D03*
X1440332Y1317092D03*
Y1319592D03*
X1443448Y1325373D03*
X1441332Y1327793D03*
X1439155Y1399064D03*
X1437443Y1406289D03*
X1444997Y1392885D03*
X1435462Y1393009D03*
Y1396409D03*
X1431717Y1420625D03*
Y1417125D03*
Y1409125D03*
X1431829Y1412370D03*
X1443325Y1410068D03*
X1434312Y1415197D03*
X1443112Y1417929D03*
X1445020Y1412672D03*
X1443676Y1432624D03*
X1431717Y1427632D03*
Y1424125D03*
X1439742Y1436924D03*
X1430204Y1452014D03*
X1434720Y1454862D03*
X1440440Y1454892D03*
X1436330Y1521152D03*
X1436570Y1536972D03*
X1436720Y1548192D03*
X1437140Y1576012D03*
X1444468Y1570610D03*
X1433720Y1569762D03*
X1438300Y1598400D03*
X1440105Y1593352D03*
X1446700Y1598400D03*
X1430250Y1608442D03*
X1438300Y1611000D03*
Y1606800D03*
Y1602600D03*
X1430250Y1612812D03*
X1441800Y1620300D03*
Y1632900D03*
Y1628700D03*
Y1624500D03*
X1438547Y1638212D03*
X1443617D03*
X1431575Y1634842D03*
X1442573Y1649862D03*
X1442587Y1659242D03*
X1438320Y1668292D03*
X1438273Y1671103D03*
X1438220Y1673955D03*
X1446715Y1679957D03*
X1431866Y1737108D03*
X1458609Y49388D03*
X1446000Y67802D03*
X1458720Y153362D03*
Y149362D03*
Y145362D03*
X1450270Y143022D03*
X1450720Y153362D03*
X1448820Y148092D03*
X1458720Y169862D03*
Y165862D03*
Y161862D03*
Y157862D03*
X1450720Y169862D03*
Y161862D03*
X1449740Y166912D03*
X1458720Y181862D03*
Y177862D03*
Y173862D03*
X1450720Y181862D03*
Y177862D03*
Y173862D03*
X1456423Y209362D03*
X1453823Y205982D03*
X1462561D03*
X1457361D03*
X1459961Y210432D03*
X1456150Y214382D03*
X1449110Y233742D03*
X1446830Y236232D03*
X1453670Y278170D03*
X1455600Y297200D03*
X1459312Y341130D03*
X1456770Y342942D03*
X1460849Y343327D03*
X1445777Y362021D03*
X1460600Y352742D03*
X1462790Y359042D03*
X1462870Y355012D03*
X1449777Y362021D03*
X1459900Y370823D03*
X1456700Y369642D03*
X1455920Y373941D03*
X1463600Y374462D03*
X1449777Y371039D03*
X1449296Y410497D03*
X1455642Y409646D03*
X1449296Y407347D03*
X1449600Y402322D03*
X1456777Y418596D03*
Y426546D03*
X1454889Y658712D03*
X1454439Y670262D03*
Y682562D03*
X1454751Y694392D03*
Y706392D03*
X1454439Y718362D03*
X1459057Y733545D03*
X1457597Y739035D03*
X1456237Y726945D03*
X1457620Y736195D03*
X1460187Y729805D03*
X1455692Y731401D03*
X1457714Y741622D03*
X1458911Y1161569D03*
Y1170069D03*
X1453366Y1287198D03*
X1458766D03*
X1461766D03*
X1450366D03*
X1450622Y1329329D03*
X1446622Y1328591D03*
X1454832Y1330819D03*
X1453360Y1328361D03*
X1446622Y1331647D03*
X1459968Y1402765D03*
X1451176Y1399026D03*
X1451198Y1403047D03*
X1461377Y1417844D03*
X1460224Y1407545D03*
X1458138Y1409955D03*
X1461062Y1413246D03*
X1454829Y1439732D03*
X1459135Y1439627D03*
X1459136Y1442241D03*
X1455006Y1447938D03*
X1459111Y1445669D03*
Y1448669D03*
X1457577Y1526689D03*
X1457817Y1542509D03*
X1457967Y1553729D03*
X1458200Y1565037D03*
Y1560037D03*
X1448620Y1556162D03*
X1446600Y1595400D03*
X1456030Y1590302D03*
X1456120Y1586262D03*
X1453600Y1595662D03*
X1460441Y1602441D03*
X1446786Y1610639D03*
X1451500Y1612800D03*
X1451580Y1627990D03*
X1454167Y1638302D03*
X1459127D03*
X1448507Y1638212D03*
X1452757Y1671399D03*
X1446380Y1676291D03*
X1448920Y1675062D03*
X1464200Y67802D03*
X1474142Y61767D03*
X1470220Y145362D03*
X1462000Y153362D03*
X1470220Y169862D03*
X1473090Y204502D03*
X1465179Y213102D03*
X1470101Y207751D03*
X1472335Y209362D03*
X1467761Y205982D03*
X1476858Y225448D03*
X1466940Y230272D03*
X1471308Y230640D03*
X1463833Y230448D03*
X1466958Y244948D03*
X1477700Y236522D03*
X1474660Y252878D03*
X1463808Y244948D03*
X1463833Y235566D03*
X1468620Y258857D03*
X1467230Y252472D03*
X1473820Y265962D03*
X1471510Y252878D03*
X1471690Y259862D03*
X1463950Y258172D03*
X1463330Y264060D03*
X1466660Y273878D03*
X1463510D03*
X1475452Y289708D03*
X1475352Y306308D03*
X1476826Y312177D03*
X1462777Y362021D03*
X1470877Y374496D03*
X1467700Y370953D03*
X1472758Y370817D03*
X1463277Y406446D03*
X1470954D03*
X1475790Y404842D03*
X1465836Y408668D03*
X1470942Y409718D03*
X1475250Y401812D03*
X1473310Y418502D03*
X1469777Y418396D03*
X1469951Y429251D03*
X1469720Y434542D03*
X1469760Y452622D03*
X1471460Y633402D03*
X1468060D03*
X1466292Y631634D03*
X1473228D03*
X1463639Y653662D03*
X1469651Y655992D03*
X1462010Y645842D03*
X1465171Y647132D03*
X1469020Y647102D03*
X1463639Y665662D03*
X1478139Y660892D03*
X1469439Y670262D03*
X1463639Y677562D03*
X1463239Y689492D03*
X1478139Y689892D03*
X1469651Y684992D03*
X1463239Y701492D03*
X1478139Y704392D03*
X1469477Y699475D03*
X1463239Y713492D03*
X1478139Y718892D03*
X1469651Y713992D03*
X1470841Y721493D03*
X1474100Y735662D03*
X1466451Y726992D03*
X1474939Y731892D03*
X1474180Y1300407D03*
X1471180D03*
X1465696Y1303480D03*
X1468296D03*
X1465696Y1300880D03*
X1468296D03*
X1473956Y1341068D03*
X1472460Y1330493D03*
Y1333043D03*
X1475576Y1338799D03*
X1475959Y1385027D03*
X1476000Y1393027D03*
X1465747Y1401405D03*
X1466448Y1421499D03*
X1475935Y1439627D03*
X1475936Y1442241D03*
X1467550Y1439642D03*
X1467536Y1442241D03*
X1467567Y1445669D03*
Y1448669D03*
X1475967Y1445669D03*
Y1448669D03*
X1478320Y1522962D03*
X1472565Y1623635D03*
X1478061Y1633864D03*
X1463767Y1638302D03*
X1476570Y1657974D03*
Y1661124D03*
X1478609Y49388D03*
X1493120Y240412D03*
X1487958Y236062D03*
X1490060Y255378D03*
X1485320Y260362D03*
X1487058Y281456D03*
X1478745Y281508D03*
X1493289Y280027D03*
X1484958Y289656D03*
X1487658D03*
X1478526Y289677D03*
X1481445Y289708D03*
X1484758Y312356D03*
X1487458D03*
X1484858Y305956D03*
X1487558D03*
X1479745Y312208D03*
X1478426Y306277D03*
X1481345Y306308D03*
X1481360Y358792D03*
X1481484Y361688D03*
X1486884Y374338D03*
X1479207D03*
X1481766Y372288D03*
X1489443D03*
X1494784Y374188D03*
X1486040Y368392D03*
X1478203Y406207D03*
X1488500Y410152D03*
X1481766Y406238D03*
X1490384Y407292D03*
X1493384Y411313D03*
X1482650Y411190D03*
X1495527Y406215D03*
X1493384Y419263D03*
X1481384Y419392D03*
X1486880Y416863D03*
X1484805Y427577D03*
X1489310Y426822D03*
X1478539Y675462D03*
X1491840Y1300447D03*
X1482750Y1342755D03*
X1478750Y1342017D03*
X1486960Y1344245D03*
X1485488Y1341787D03*
X1478750Y1345073D03*
X1481155Y1387742D03*
X1481255Y1382042D03*
X1478559Y1385027D03*
X1481159Y1384727D03*
X1481155Y1396342D03*
Y1398942D03*
Y1390342D03*
X1478600Y1393027D03*
X1481107Y1393095D03*
X1479658Y1405397D03*
X1485301Y1409442D03*
X1485274Y1406911D03*
X1485380Y1412202D03*
X1479671Y1410411D03*
Y1412911D03*
Y1407911D03*
X1482201Y1409442D03*
X1482174Y1406911D03*
X1482280Y1412202D03*
X1485387Y1420002D03*
X1481918Y1425579D03*
X1484395Y1439598D03*
X1484336Y1442241D03*
X1484442Y1445557D03*
Y1448557D03*
X1482830Y1525162D03*
X1478724Y1637189D03*
X1480800Y1663600D03*
X1491866Y1737108D03*
X1498609Y49388D03*
X1510500Y125992D03*
X1505821Y215802D03*
X1508959D03*
X1503020D03*
X1499922Y211240D03*
X1505378Y225502D03*
X1496720Y225292D03*
X1504484Y234562D03*
X1508410Y230842D03*
X1510017Y225516D03*
X1501840Y225502D03*
X1512420Y239116D03*
X1509571Y239053D03*
X1507860Y249792D03*
X1510810Y249742D03*
X1509040Y243362D03*
X1504890Y249862D03*
X1506600Y239092D03*
X1504650Y254392D03*
X1508049Y280056D03*
X1498984Y282797D03*
X1508558Y291175D03*
X1512244Y311522D03*
X1504602Y312867D03*
X1505922Y304583D03*
X1509539Y308467D03*
X1496200Y359522D03*
X1498184Y361723D03*
X1497880Y373062D03*
X1498184Y369798D03*
X1495150Y369842D03*
X1503450Y382693D03*
Y385843D03*
X1497770Y732502D03*
X1509638Y738627D03*
X1509350Y741315D03*
X1504747Y747293D03*
X1503514Y801361D03*
Y797961D03*
X1494840Y1300447D03*
X1504588Y1353316D03*
Y1355816D03*
X1505570Y1364212D03*
X1507704Y1361597D03*
X1510027Y1425825D03*
X1507617Y1424045D03*
X1518608Y49377D03*
X1522920Y113030D03*
Y116180D03*
X1513900Y117762D03*
X1518575Y138662D03*
X1526675Y140117D03*
X1526083Y146225D03*
X1524770Y195792D03*
X1521115Y193262D03*
X1521201Y215551D03*
X1524539D03*
X1522009Y210825D03*
X1518110Y215551D03*
X1526998Y209645D03*
X1527732Y219488D03*
X1514520Y231116D03*
X1526152Y225114D03*
X1513110Y247412D03*
X1514593Y249698D03*
Y235116D03*
X1513759Y263676D03*
X1519758Y265161D03*
X1522786Y262558D03*
X1522258Y265161D03*
X1516683Y278437D03*
X1519833Y277297D03*
X1511624Y291175D03*
X1522258Y288956D03*
X1517669Y291516D03*
X1522883Y305187D03*
X1519336Y303426D03*
X1520094Y306543D03*
X1514369Y308467D03*
X1526216Y306909D03*
X1524505Y748912D03*
X1515940Y795815D03*
Y799215D03*
X1522066Y1312808D03*
X1526066D03*
X1518066D03*
X1515066D03*
X1511066D03*
X1510738Y1345539D03*
Y1342432D03*
X1518538Y1345539D03*
Y1342432D03*
X1515938Y1345539D03*
Y1342432D03*
X1513338Y1345539D03*
Y1342432D03*
X1521138D03*
X1524338D03*
X1518738Y1348646D03*
X1516138D03*
X1514878Y1365553D03*
X1510878Y1364815D03*
X1519088Y1367043D03*
X1517616Y1364585D03*
X1510878Y1367871D03*
X1512177Y1427795D03*
X1516137Y1432135D03*
X1513657Y1429985D03*
X1511866Y1737108D03*
X1529002Y32290D03*
X1544010Y27552D03*
X1536310Y47492D03*
X1534818Y66801D03*
Y71793D03*
X1539774Y66801D03*
Y71793D03*
X1541774Y69297D03*
X1532818D03*
X1534774Y103093D03*
X1529818D03*
X1534060Y100162D03*
X1530660D03*
X1533520Y110662D03*
X1535320Y113062D03*
X1529500Y122122D03*
X1535575Y118862D03*
X1529500Y129602D03*
X1540090Y122782D03*
X1536925Y129937D03*
X1529500Y125862D03*
X1535520Y151562D03*
X1529233Y153162D03*
X1535450Y155262D03*
X1542401Y141561D03*
X1545447Y156035D03*
X1531750Y199762D03*
X1537262Y197834D03*
X1534720Y199803D03*
X1528720Y199862D03*
X1533385Y193108D03*
X1529610Y211614D03*
X1533148D03*
X1531824Y207677D03*
X1534194Y217519D03*
X1532590Y225432D03*
X1529670Y225522D03*
X1535561Y225393D03*
X1531110Y264862D03*
X1539150Y267132D03*
X1528716Y306909D03*
X1533716D03*
X1536216D03*
X1534899Y310447D03*
X1540937Y576522D03*
X1536527Y589012D03*
X1539720Y589862D03*
Y581862D03*
X1540989Y616587D03*
X1540377Y634165D03*
X1535052Y1325904D03*
X1532552Y1334504D03*
X1535052D03*
X1529952D03*
X1532552Y1339704D03*
X1529952D03*
X1537652Y1325904D03*
Y1334504D03*
X1532552Y1337104D03*
X1529952D03*
X1538510Y1346392D03*
X1531302Y1342204D03*
X1535892Y1346354D03*
Y1343754D03*
X1527282Y1345555D03*
Y1342448D03*
X1538757Y1356355D03*
X1527182Y1348651D03*
X1538757Y1360855D03*
Y1365355D03*
X1531866Y1737108D03*
X1547768Y3010D03*
X1555635Y16999D03*
Y21991D03*
X1553635Y19495D03*
X1556413D03*
X1553486Y23935D03*
X1548530D03*
X1546530Y25931D03*
X1555486D03*
X1547429Y28406D03*
Y37106D03*
X1554515Y28406D03*
Y37106D03*
X1549308Y26431D03*
X1552708D03*
X1554515Y40020D03*
Y48720D03*
X1547429Y40020D03*
Y48720D03*
X1554818Y69297D03*
X1556818Y66801D03*
Y71793D03*
X1543818Y75297D03*
X1552774D03*
X1550774Y77793D03*
Y72801D03*
X1545818Y77793D03*
Y72801D03*
X1554239Y138263D03*
X1552960Y124359D03*
X1553189Y127781D03*
X1556049Y147711D03*
X1545763Y159305D03*
X1554723Y200375D03*
X1557560Y196912D03*
X1551160Y189342D03*
X1557900Y220362D03*
X1557760Y214792D03*
X1550353Y217352D03*
X1557320Y203297D03*
X1554723Y224529D03*
X1559400Y229832D03*
X1554723Y248945D03*
X1559387Y589340D03*
X1547312Y579080D03*
X1543720Y581862D03*
X1548720D03*
X1552720Y589862D03*
Y581862D03*
X1554727Y631527D03*
X1554753Y628860D03*
X1553312Y636815D03*
X1559354Y655716D03*
Y659116D03*
X1550417Y677045D03*
X1550487Y681565D03*
X1550057Y693485D03*
X1548479Y706088D03*
X1550320Y696562D03*
X1550917Y704332D03*
X1550390Y709885D03*
X1551866Y1737108D03*
X1567768Y3010D03*
X1560591Y16999D03*
Y21991D03*
X1569808Y16999D03*
Y21991D03*
X1574764Y16999D03*
Y21991D03*
X1562591Y19495D03*
X1567808D03*
X1570586D03*
X1573986D03*
X1559813D03*
X1567659Y23935D03*
X1562703D03*
X1560703Y25931D03*
X1569659D03*
X1574876D03*
X1561602Y28406D03*
Y37106D03*
X1568688Y28406D03*
Y37106D03*
X1563481Y26431D03*
X1566881D03*
X1568688Y40020D03*
Y48720D03*
X1561602Y40020D03*
Y48720D03*
X1563774Y69297D03*
X1561774Y66801D03*
Y71793D03*
X1565818Y75297D03*
X1574774D03*
X1572774Y77793D03*
Y72801D03*
X1567818Y77793D03*
Y72801D03*
X1559860Y240002D03*
X1573560Y245078D03*
X1574760Y251032D03*
X1559722Y243110D03*
X1570675Y267857D03*
X1575169Y303929D03*
X1573246Y306650D03*
X1572396Y309450D03*
X1563714Y572792D03*
X1567114D03*
X1561494Y584292D03*
X1559557Y593290D03*
X1560717Y648522D03*
X1564690Y663302D03*
X1564768Y708159D03*
X1570720Y729362D03*
X1562871Y732316D03*
Y735716D03*
X1571577Y747145D03*
X1567547Y755485D03*
X1571920Y762662D03*
X1568490Y758162D03*
X1570374Y760093D03*
X1587768Y3010D03*
X1583981Y16999D03*
Y21991D03*
X1588937Y16999D03*
Y21991D03*
X1576764Y19495D03*
X1581981D03*
X1590937D03*
X1584759D03*
X1588159D03*
X1576876Y23935D03*
X1581832D03*
X1591050D03*
X1583832Y25931D03*
X1589050D03*
X1575775Y28406D03*
Y37106D03*
X1582862Y28406D03*
Y37106D03*
X1589948Y28406D03*
Y37106D03*
X1577654Y26431D03*
X1591828D03*
X1581054D03*
X1589948Y40020D03*
Y48720D03*
X1582862Y40020D03*
Y48720D03*
X1575775Y40020D03*
Y48720D03*
X1576818Y69297D03*
X1585774D03*
X1578818Y66801D03*
Y71793D03*
X1583774Y66801D03*
Y71793D03*
X1587818Y75297D03*
X1589818Y77793D03*
Y72801D03*
X1576589Y300927D03*
X1590915Y755793D03*
X1591866Y1737108D03*
X1607768Y3010D03*
X1598155Y16999D03*
Y21991D03*
X1603111Y16999D03*
Y21991D03*
X1596155Y19495D03*
X1605111D03*
X1598933D03*
X1602333D03*
X1596006Y23935D03*
X1598006Y25931D03*
X1597035Y28406D03*
Y37106D03*
X1604122Y28406D03*
Y37106D03*
X1595228Y26431D03*
X1604122Y40020D03*
Y48720D03*
X1597035Y40020D03*
Y48720D03*
X1598818Y69297D03*
X1607774D03*
X1600818Y66801D03*
Y71793D03*
X1605774Y66801D03*
Y71793D03*
X1596774Y75297D03*
X1594774Y77793D03*
Y72801D03*
X1603778Y189943D03*
X1603726Y198061D03*
X1603747Y192951D03*
X1603530Y202402D03*
X1596444Y215526D03*
X1603706Y211526D03*
X1603580Y206902D03*
X1604200Y234642D03*
X1604240Y227892D03*
X1603920Y222922D03*
X1604040Y219692D03*
X1604270Y231490D03*
X1598030Y251002D03*
X1604290Y242472D03*
X1604240Y238242D03*
X1602980Y560002D03*
X1607200Y583962D03*
X1598440Y736692D03*
X1592760Y736652D03*
X1595600D03*
X1606788Y756199D03*
X1602788D03*
X1606980Y1449922D03*
X1621920Y25962D03*
X1622220Y49862D03*
X1620818Y69297D03*
X1622818Y66801D03*
Y71793D03*
X1609818Y75297D03*
X1618774D03*
X1616774Y77793D03*
Y72801D03*
X1611818Y77793D03*
Y72801D03*
X1623881Y117627D03*
Y129627D03*
X1615800Y584062D03*
X1612980Y623762D03*
Y626362D03*
X1615580Y650092D03*
Y657762D03*
X1612980D03*
Y650092D03*
X1615580Y660362D03*
X1612980D03*
X1615580Y684092D03*
X1612980D03*
X1615580Y694362D03*
X1612980D03*
X1615580Y691762D03*
X1612980D03*
Y718092D03*
X1615580D03*
X1610100Y725152D03*
X1610788Y756199D03*
X1614788D03*
X1618788D03*
X1614116Y1411169D03*
X1623448Y1420028D03*
Y1417428D03*
Y1414828D03*
Y1412228D03*
X1612630Y1418842D03*
X1615062Y1421241D03*
X1613047Y1415669D03*
X1615597Y1433669D03*
X1614927Y1426076D03*
Y1429896D03*
X1624353Y1428766D03*
Y1431316D03*
X1617215Y1440822D03*
X1611866Y1737108D03*
X1634021Y16999D03*
Y21991D03*
X1638977Y16999D03*
Y21991D03*
X1632021Y19495D03*
X1634799D03*
X1638199D03*
X1631872Y23935D03*
X1626916D03*
X1624916Y25931D03*
X1633872D03*
X1639089D03*
X1625814Y28406D03*
Y37106D03*
X1632901Y28406D03*
Y37106D03*
X1639988Y28406D03*
Y37106D03*
X1627694Y26431D03*
X1631094D03*
X1625814Y40020D03*
Y48720D03*
X1632901Y40020D03*
Y48720D03*
X1639988Y40020D03*
Y48720D03*
X1629774Y69297D03*
X1627774Y66801D03*
Y71793D03*
X1633022Y75297D03*
X1635022Y77793D03*
X1639978D03*
Y72801D03*
X1635022D03*
X1636393Y181778D03*
X1635032Y196188D03*
X1632899Y213012D03*
X1633111Y206693D03*
X1632342Y216015D03*
X1635835Y343002D03*
X1642135Y414202D03*
X1636800Y429982D03*
X1639800D03*
X1636800Y426982D03*
X1639800D03*
X1636800Y438982D03*
X1639800D03*
X1636800Y435982D03*
X1639800D03*
X1636800Y432982D03*
X1639800D03*
X1638928Y756199D03*
X1630928D03*
X1634928D03*
X1638277Y1269065D03*
X1640812Y1270020D03*
X1637183Y1394411D03*
X1639683D03*
X1629262Y1394418D03*
X1634683Y1394411D03*
X1625948Y1417428D03*
Y1412228D03*
X1633103Y1417907D03*
X1630503D03*
X1635703D03*
X1633103Y1421014D03*
X1630503D03*
X1635703D03*
X1638303Y1417907D03*
Y1421014D03*
X1625948Y1414828D03*
Y1420028D03*
X1635903Y1424121D03*
X1638503D03*
X1632516Y1427753D03*
Y1433353D03*
X1634986Y1427753D03*
Y1433353D03*
X1637416Y1427753D03*
Y1433353D03*
X1630643Y1440290D03*
X1627469Y1437072D03*
X1627591Y1447796D03*
X1637478Y1445150D03*
X1624853Y1440875D03*
X1634643Y1442982D03*
X1638785Y1442483D03*
X1637042Y1440215D03*
X1630643Y1443090D03*
X1631866Y1737108D03*
X1648194Y16999D03*
Y21991D03*
X1653150Y16999D03*
Y21991D03*
X1640977Y19495D03*
X1646194D03*
X1655150D03*
X1648972D03*
X1652372D03*
X1641089Y23935D03*
X1646045D03*
X1648045Y25931D03*
X1654161Y28406D03*
Y37106D03*
X1647074Y28406D03*
Y37106D03*
X1641867Y26431D03*
X1645267D03*
X1647074Y40020D03*
Y48720D03*
X1654161Y40020D03*
Y48720D03*
X1644022Y69297D03*
X1652978D03*
X1646022Y66801D03*
Y71793D03*
X1650978Y66801D03*
Y71793D03*
X1655022Y75297D03*
X1641978D03*
X1657022Y77793D03*
Y72801D03*
X1652610Y394727D03*
X1652810Y407402D03*
X1650020Y408952D03*
X1647310Y408922D03*
X1650020Y411452D03*
X1647310Y411422D03*
X1647110Y434177D03*
X1654110D03*
X1652113Y527325D03*
X1652138Y524071D03*
X1651890Y520540D03*
X1657755Y517910D03*
X1651931Y540071D03*
Y536071D03*
X1649291Y556057D03*
X1651112Y545572D03*
X1645530Y549160D03*
X1653230Y549322D03*
X1642720Y560862D03*
X1656238Y592113D03*
X1649833Y594946D03*
X1653794Y594956D03*
X1653774Y598576D03*
X1649844Y598555D03*
X1656955Y611090D03*
X1645300Y612202D03*
X1653220Y620662D03*
X1645681Y624011D03*
X1648581D03*
X1651481D03*
X1654809Y638101D03*
X1653319Y642311D03*
X1652351Y639573D03*
X1648811Y628277D03*
X1647081Y626211D03*
X1645917Y628917D03*
Y633577D03*
X1645167Y631247D03*
Y635907D03*
X1650081Y626111D03*
X1651711Y628277D03*
X1651635Y651836D03*
X1652581Y646311D03*
X1643582Y652601D03*
X1655637Y646311D03*
X1641082Y652601D03*
X1649363Y649485D03*
X1654809Y672101D03*
X1652351Y673573D03*
X1645681Y658011D03*
X1648581D03*
X1648811Y662277D03*
X1647081Y660211D03*
X1645917Y662917D03*
Y667577D03*
X1645167Y665247D03*
Y669907D03*
X1650081Y660111D03*
X1651481Y658011D03*
X1651711Y662277D03*
X1641082Y686601D03*
X1651635Y685836D03*
X1652581Y680311D03*
X1653319Y676311D03*
X1643582Y686601D03*
X1655113Y680835D03*
X1649363Y683485D03*
X1654809Y706101D03*
X1648811Y696277D03*
X1645167Y703907D03*
X1645917Y701577D03*
X1645167Y699247D03*
X1645917Y696917D03*
X1650081Y694111D03*
X1645681Y692011D03*
X1647081Y694211D03*
X1648581Y692011D03*
X1651711Y696277D03*
X1651481Y692011D03*
X1641082Y720601D03*
X1651635Y719836D03*
X1652581Y714311D03*
X1653319Y710311D03*
X1652351Y707573D03*
X1643582Y720601D03*
X1655637Y714311D03*
X1649363Y717485D03*
X1651509Y756492D03*
X1656188Y1394736D03*
X1647592Y1394418D03*
X1655779Y1417618D03*
Y1412418D03*
Y1415018D03*
X1644103Y1417907D03*
X1647047Y1417923D03*
Y1421030D03*
X1653279Y1412418D03*
X1650679D03*
X1653279Y1415018D03*
X1650679D03*
X1653168Y1417618D03*
X1650557D03*
X1640903Y1417907D03*
X1647016Y1424153D03*
X1641047Y1432876D03*
X1645707D03*
X1643377Y1433626D03*
X1648037D03*
X1655762Y1429794D03*
X1648677Y1436220D03*
X1653243Y1435690D03*
X1651043Y1434190D03*
X1653243Y1432790D03*
X1651143Y1437190D03*
X1653243Y1438590D03*
X1648677Y1439120D03*
X1655295Y1453879D03*
X1652295D03*
X1655295Y1456899D03*
X1652295D03*
X1648947Y1476695D03*
X1646958Y1501553D03*
X1651866Y1737108D03*
X1671050Y23935D03*
X1669050Y25931D03*
X1669948Y28406D03*
Y37106D03*
X1671828Y26431D03*
X1669948Y40020D03*
Y48720D03*
X1666022Y69297D03*
X1668022Y66801D03*
Y71793D03*
X1672978Y66801D03*
Y71793D03*
X1663978Y75297D03*
X1661978Y77793D03*
Y72801D03*
X1668100Y180852D03*
X1668030Y200580D03*
X1666690Y193290D03*
X1674432Y216981D03*
X1672596Y220541D03*
X1666074Y229710D03*
X1660176Y231100D03*
X1670400Y229462D03*
X1668426Y222432D03*
X1664866Y225162D03*
X1660861Y227548D03*
X1659610Y394727D03*
X1663610D03*
X1661110Y434177D03*
X1664970Y472112D03*
X1662447Y480619D03*
X1663376Y515531D03*
X1667376D03*
X1665790Y523417D03*
X1670004Y537065D03*
Y543065D03*
Y531065D03*
X1662262Y537334D03*
X1659740Y542222D03*
X1661872Y534703D03*
X1660243Y532071D03*
X1660866Y546749D03*
X1668917Y549992D03*
X1666902Y555115D03*
X1663502D03*
X1664040Y569642D03*
X1668040D03*
X1672040D03*
X1665700Y583462D03*
X1661510Y583442D03*
X1672770Y580512D03*
X1669770D03*
X1658738Y592113D03*
X1661238D03*
X1664997Y604762D03*
X1662120Y604782D03*
X1664197Y602191D03*
X1669222Y604490D03*
X1670700Y594562D03*
X1672500Y596462D03*
X1660660Y602273D03*
X1657220Y620662D03*
X1663720Y620434D03*
X1664410Y617953D03*
X1668920Y617637D03*
X1660754Y609837D03*
X1669397Y614064D03*
X1663471Y609837D03*
X1659458Y637149D03*
X1658085Y639511D03*
X1659914Y649681D03*
X1666686Y757162D03*
X1673226Y1394411D03*
X1667405Y1394418D03*
X1659260Y1394693D03*
X1658390Y1420218D03*
Y1415018D03*
Y1412418D03*
Y1417618D03*
X1663590Y1420218D03*
X1660990D03*
Y1415018D03*
Y1417618D03*
Y1412418D03*
X1663590Y1415018D03*
Y1417618D03*
Y1412418D03*
X1668646Y1417907D03*
Y1421014D03*
X1671246Y1417907D03*
Y1421014D03*
X1670659Y1427753D03*
X1673129D03*
X1670659Y1433353D03*
X1673129D03*
X1657438Y1438156D03*
X1662496Y1428791D03*
Y1431291D03*
X1665612Y1437072D03*
X1660428Y1447566D03*
X1667577Y1447545D03*
X1662996Y1440922D03*
X1672786Y1442982D03*
X1668786Y1440290D03*
Y1443256D03*
X1657920Y1453405D03*
X1660920D03*
X1657860Y1466545D03*
Y1464045D03*
X1657950Y1456210D03*
X1657860Y1459045D03*
Y1461545D03*
X1660950Y1456210D03*
X1660860Y1466545D03*
Y1464045D03*
Y1459045D03*
Y1461545D03*
X1666123Y1497362D03*
Y1493362D03*
Y1501362D03*
X1665940Y1512862D03*
X1666110Y1504662D03*
X1666123Y1524862D03*
Y1537862D03*
Y1533862D03*
Y1520862D03*
Y1541862D03*
Y1553557D03*
Y1545862D03*
X1671673Y1550815D03*
X1666198Y1565557D03*
X1666123Y1557557D03*
X1666198Y1561557D03*
X1671660Y1569412D03*
X1666198Y1585321D03*
Y1581321D03*
X1671866Y1737108D03*
X1678155Y16999D03*
Y21991D03*
X1683111Y16999D03*
Y21991D03*
X1676155Y19495D03*
X1685111D03*
X1678933D03*
X1682333D03*
X1676006Y23935D03*
X1685223D03*
X1678006Y25931D03*
X1683223D03*
X1677035Y28406D03*
Y37106D03*
X1684122Y28406D03*
Y37106D03*
X1686001Y26431D03*
X1689401D03*
X1675228D03*
X1677035Y40020D03*
Y48720D03*
X1684122Y40020D03*
Y48720D03*
X1688156Y69297D03*
X1674978D03*
X1677156Y75297D03*
X1686112D03*
X1684112Y77793D03*
Y72801D03*
X1679156Y77793D03*
Y72801D03*
X1678994Y217231D03*
X1676300Y219762D03*
X1681900Y227962D03*
X1690208Y421855D03*
X1686154Y434160D03*
X1689095Y462640D03*
X1683394Y469878D03*
X1683476Y473378D03*
X1684356Y476290D03*
X1682810Y465940D03*
X1684940Y463030D03*
X1681602Y485180D03*
X1684356Y485628D03*
X1677464Y491790D03*
X1685779Y491230D03*
X1690229Y481845D03*
X1687238Y485496D03*
X1681817Y495290D03*
X1681612Y499290D03*
X1675664Y513802D03*
X1690999Y513107D03*
X1683702Y514687D03*
X1676600Y523902D03*
X1688768Y518107D03*
X1682004Y537065D03*
X1682180Y543065D03*
X1676004D03*
X1682004Y531065D03*
X1676004D03*
X1689544Y543874D03*
X1689506Y539882D03*
X1679941Y552222D03*
X1678860Y556752D03*
X1676040Y569627D03*
X1683369Y562698D03*
Y566098D03*
X1676644Y655345D03*
Y652745D03*
X1679244Y655345D03*
X1681864Y655286D03*
X1679244Y652745D03*
X1676624Y642404D03*
X1676644Y644945D03*
Y647545D03*
Y650145D03*
X1679244Y642345D03*
X1681864Y642286D03*
X1679244Y644945D03*
Y647545D03*
X1681864Y644886D03*
Y647486D03*
Y650086D03*
Y652686D03*
X1679244Y650145D03*
X1673860Y726522D03*
X1681810Y752955D03*
X1686135Y1394418D03*
X1675926Y1394411D03*
X1678426D03*
X1687860Y1415179D03*
X1689210Y1417679D03*
X1687860Y1412579D03*
X1685190Y1417923D03*
X1676446Y1417907D03*
X1679046D03*
X1682246D03*
X1676446Y1421014D03*
X1685190Y1421030D03*
X1673846Y1417907D03*
Y1421014D03*
X1676646Y1424121D03*
X1685159Y1424153D03*
X1675559Y1427753D03*
Y1433353D03*
X1674046Y1424121D03*
X1679190Y1432876D03*
X1683850D03*
X1681520Y1433626D03*
X1686180D03*
X1686820Y1436520D03*
X1688886Y1434790D03*
X1688986Y1437790D03*
X1675621Y1445150D03*
X1676928Y1442483D03*
X1675185Y1440215D03*
X1686820Y1439420D03*
X1680720Y1487062D03*
X1679508Y1503421D03*
Y1498303D03*
X1678340Y1500862D03*
X1679508Y1517803D03*
X1677930Y1520362D03*
X1679508Y1522921D03*
Y1543921D03*
Y1538803D03*
X1678340Y1541362D03*
X1679508Y1563380D03*
Y1583880D03*
X1678230Y1590542D03*
X1674220Y1585321D03*
X1692328Y16999D03*
Y21991D03*
X1697284Y16999D03*
Y21991D03*
X1690328Y19495D03*
X1699284D03*
X1696506D03*
X1693106D03*
X1703617Y26459D03*
X1700217D03*
X1690179Y23935D03*
X1692179Y25931D03*
X1691208Y28406D03*
Y37106D03*
X1698295Y28406D03*
Y37106D03*
X1705381Y28406D03*
Y37106D03*
X1703570Y50649D03*
X1700170D03*
X1698295Y48720D03*
X1697824Y39974D03*
X1691208Y40020D03*
Y48720D03*
X1705381D03*
X1697112Y69297D03*
X1690156Y66801D03*
Y71793D03*
X1695112Y66801D03*
Y71793D03*
X1699156Y75297D03*
X1701156Y77793D03*
Y72801D03*
X1695950Y96437D03*
X1697725Y205120D03*
X1702490Y204780D03*
X1693987Y230174D03*
Y233174D03*
X1703487Y232174D03*
X1698220Y369652D03*
X1704444Y407045D03*
X1699809Y403985D03*
X1695579D03*
X1702959Y404243D03*
X1707780Y410738D03*
X1697161Y406602D03*
X1692429Y403985D03*
X1697914Y427155D03*
X1698014Y424055D03*
X1701124Y423802D03*
X1694050Y416643D03*
X1695455Y422287D03*
X1707544Y431745D03*
X1707568Y420370D03*
X1701124Y433650D03*
X1697214Y433655D03*
X1704624Y433650D03*
X1690140Y434160D03*
X1700846Y455894D03*
X1697648Y463724D03*
X1693720Y455862D03*
X1697220D03*
X1693648Y463724D03*
X1702760Y478207D03*
X1696760D03*
X1702127Y468719D03*
X1693236Y472650D03*
X1702760Y490207D03*
X1696760D03*
Y484207D03*
X1691151Y493678D03*
X1689943Y479304D03*
X1696120Y506937D03*
X1703720Y509362D03*
X1701811Y501318D03*
X1701635Y497177D03*
X1699300Y498632D03*
X1697210Y500802D03*
X1694050Y501422D03*
X1693711Y498527D03*
X1691129Y501697D03*
X1707200Y498962D03*
X1699553Y513107D03*
X1707552Y506731D03*
X1707716Y513562D03*
X1702930Y526102D03*
X1699265Y525507D03*
X1696851Y515607D03*
X1693701D03*
X1699265Y521507D03*
X1690999Y525507D03*
X1701726Y518107D03*
X1699291Y537507D03*
X1699251Y529507D03*
X1699666Y541507D03*
X1699251Y533642D03*
X1691104Y530503D03*
X1691445Y535011D03*
X1704886Y534564D03*
X1689769Y537339D03*
X1699107Y555783D03*
X1699297Y549507D03*
X1702270Y552742D03*
X1703306Y550064D03*
X1698048Y705662D03*
X1701320Y705678D03*
X1698020Y702962D03*
X1696402Y709533D03*
X1699110Y727452D03*
X1705035Y729210D03*
X1704973Y753019D03*
X1703310Y749455D03*
X1690620Y760702D03*
X1691412Y1372492D03*
Y1367492D03*
Y1369992D03*
Y1377492D03*
Y1374992D03*
Y1382492D03*
Y1379992D03*
X1690809Y1393970D03*
X1699150Y1393613D03*
X1690460Y1415179D03*
Y1412579D03*
X1691918Y1417676D03*
X1692960Y1415179D03*
Y1412579D03*
X1693404Y1421939D03*
X1699593Y1428384D03*
X1697820Y1423616D03*
X1699545Y1425868D03*
X1699437Y1431295D03*
X1691086Y1436290D03*
Y1433390D03*
X1693392Y1429808D03*
X1699457Y1439185D03*
Y1447805D03*
X1691086Y1439190D03*
X1691988Y1498303D03*
X1704723Y1500862D03*
X1691988Y1517803D03*
X1704723Y1520362D03*
X1691988Y1538803D03*
X1704723Y1541362D03*
X1691988Y1558262D03*
X1705003Y1564057D03*
X1705723Y1583821D03*
X1691866Y1737108D03*
X1707220Y15662D03*
X1715210Y18282D03*
X1714589Y21562D03*
X1714520Y37162D03*
X1709589Y26062D03*
X1719589Y25862D03*
X1717089D03*
X1710106Y48720D03*
Y40020D03*
X1720895Y68062D03*
X1716875D03*
X1710920Y82162D03*
X1708112Y75297D03*
X1706112Y77793D03*
Y72801D03*
X1708000Y99122D03*
X1712520Y117862D03*
X1712720Y111862D03*
X1719943Y112667D03*
Y116667D03*
X1713418Y130862D03*
X1721418Y135327D03*
X1717418D03*
X1714180Y154790D03*
X1717140Y148910D03*
X1711700Y140200D03*
X1717619Y165909D03*
X1718110Y159040D03*
X1719530Y162950D03*
X1717280Y174970D03*
X1722078Y189483D03*
X1720310Y191252D03*
X1707159Y210080D03*
X1721400Y374462D03*
X1713720Y381152D03*
X1717220D03*
X1719200Y371162D03*
X1713720Y391652D03*
Y384652D03*
Y388152D03*
X1717220Y391652D03*
Y388152D03*
Y384652D03*
X1707444Y407045D03*
X1709000Y413362D03*
X1706500D03*
X1711144Y425945D03*
X1709000Y415862D03*
X1706500D03*
X1721220Y458362D03*
X1713977Y457137D03*
X1708977Y458542D03*
X1711477Y465229D03*
Y468379D03*
X1708760Y478031D03*
X1721936Y469263D03*
X1716134Y478443D03*
X1715711Y474399D03*
X1713977Y470804D03*
X1708977D03*
X1708760Y490207D03*
Y484207D03*
X1716148Y483720D03*
X1716087Y495665D03*
X1716156Y487685D03*
X1716278Y491676D03*
X1707552Y503331D03*
X1709844Y516106D03*
X1710500Y538162D03*
X1707610Y534113D03*
X1709356Y541144D03*
X1709680Y545432D03*
X1716110Y532632D03*
X1707346Y547504D03*
X1717987Y569705D03*
X1709027Y655141D03*
X1716480Y691410D03*
X1710550Y691327D03*
X1712824Y696476D03*
X1710122Y703509D03*
X1713920Y700962D03*
X1709828Y719283D03*
X1713450Y728222D03*
X1719727Y1472088D03*
X1718149Y1496270D03*
X1717149Y1505895D03*
X1720174D03*
X1717988Y1520951D03*
X1711988D03*
X1717149Y1513945D03*
X1720174D03*
X1714988Y1520951D03*
X1708988D03*
X1717988Y1530445D03*
X1714988D03*
X1708988D03*
X1711988D03*
X1711866Y1737108D03*
X1727768Y3010D03*
X1732320Y28162D03*
X1728820D03*
X1725320D03*
X1726720Y49862D03*
X1733720D03*
X1730220D03*
X1736040Y41792D03*
X1732810Y52482D03*
X1736040Y44292D03*
X1730140Y52552D03*
X1727600Y52582D03*
X1729520Y61762D03*
X1729620Y57262D03*
X1725320Y67962D03*
X1730820Y76362D03*
X1726918Y101967D03*
X1738220Y98862D03*
X1736720Y101862D03*
X1729080Y118132D03*
X1739720Y120892D03*
X1728999Y112895D03*
X1733378Y134907D03*
X1736508D03*
X1730765Y151362D03*
X1733920D03*
X1723670Y149102D03*
X1728320Y169862D03*
X1723240Y185200D03*
X1737704Y183139D03*
X1723090Y173072D03*
Y177072D03*
X1734857Y184865D03*
X1737470Y177147D03*
X1738200Y193862D03*
X1737500Y217962D03*
Y214962D03*
Y211962D03*
Y208962D03*
Y226962D03*
Y223962D03*
Y220962D03*
X1725344Y359334D03*
X1737260Y368132D03*
X1732660Y372692D03*
X1725400Y372062D03*
X1728300Y377787D03*
X1725500Y383662D03*
X1733780Y390620D03*
X1729810D03*
X1737660D03*
X1737434Y398990D03*
X1727760Y420415D03*
X1734290Y423820D03*
X1727700Y417265D03*
X1739316Y480939D03*
X1725473Y474859D03*
X1730954Y478062D03*
X1725522Y482869D03*
X1733354Y490869D03*
Y486869D03*
X1724431Y1336311D03*
X1734717Y1404340D03*
X1729700Y1462932D03*
X1733200D03*
X1736700D03*
X1736400Y1458942D03*
Y1455442D03*
X1731600Y1457230D03*
X1726120Y1490262D03*
X1726149Y1496270D03*
X1724649Y1513945D03*
X1727674D03*
X1729310Y1520951D03*
X1735310D03*
X1724649Y1505895D03*
X1727674D03*
X1726310Y1530445D03*
X1732310D03*
X1729310D03*
X1735310D03*
X1726310Y1520951D03*
X1732310D03*
X1731866Y1737108D03*
X1747768Y3010D03*
X1754090Y16302D03*
X1753388Y28360D03*
X1748400Y37262D03*
X1751065Y39017D03*
X1754620Y39062D03*
X1747720Y31862D03*
Y34362D03*
X1753398Y48720D03*
X1740858Y72330D03*
Y79830D03*
Y74830D03*
Y82330D03*
X1754398Y100307D03*
X1745220Y98862D03*
X1741720D03*
X1743720Y101862D03*
X1740220D03*
X1748720Y97362D03*
X1745485Y119539D03*
X1745010Y122952D03*
X1750820Y119972D03*
X1747482Y121367D03*
X1741222Y151527D03*
X1738520Y151362D03*
X1751220Y147562D03*
X1748465D03*
X1747591Y171733D03*
X1754120Y171562D03*
X1750920Y171662D03*
X1751084Y190928D03*
X1752200Y197762D03*
X1748500Y193862D03*
X1745500D03*
X1741200D03*
X1754234Y190836D03*
X1752078Y216728D03*
X1740500Y217962D03*
Y214962D03*
Y211962D03*
Y208962D03*
X1747600Y209062D03*
X1744600D03*
X1751800Y206762D03*
X1752078Y226728D03*
Y224228D03*
Y221728D03*
Y219228D03*
X1740500Y226962D03*
Y223962D03*
Y220962D03*
X1754307Y262186D03*
X1751068Y262123D03*
X1754245Y269724D03*
X1751068Y266048D03*
X1754307Y266111D03*
X1754414Y275329D03*
X1752165Y273901D03*
X1749565D03*
X1751006Y269661D03*
X1749595Y276711D03*
X1752195D03*
X1746484Y279682D03*
X1745000Y299862D03*
X1756204Y301695D03*
X1752000Y306562D03*
X1748989Y380206D03*
X1756933Y372452D03*
X1744380Y382892D03*
X1744510Y377452D03*
X1747080Y435870D03*
X1746720Y464862D03*
X1740831Y489362D03*
X1740886Y493960D03*
X1752316Y703969D03*
Y695669D03*
X1752217Y692988D03*
X1752276Y720529D03*
X1752316Y712269D03*
X1746970Y1451872D03*
X1738740Y1451742D03*
X1750970Y1459172D03*
Y1456172D03*
X1740200Y1462932D03*
X1745111Y1463262D03*
X1747677Y1507388D03*
X1744677D03*
X1747304Y1524976D03*
X1744304D03*
X1751866Y1737108D03*
X1767768Y3010D03*
X1762420Y21562D03*
X1765238Y22062D03*
X1768026Y24165D03*
X1769669Y15244D03*
X1761998Y15187D03*
X1765260Y18262D03*
X1757320Y15872D03*
X1758672Y26431D03*
X1755272D03*
X1760475Y28360D03*
X1769900Y37732D03*
X1767220Y26962D03*
X1758669Y50649D03*
X1755269D03*
X1760485Y48720D03*
X1762738Y53262D03*
X1767220Y53342D03*
X1767185Y48817D03*
X1767400Y39915D03*
X1769274Y50742D03*
X1771774Y53682D03*
X1759700Y57662D03*
X1764400Y57462D03*
X1758063Y68637D03*
X1758573Y87107D03*
Y83607D03*
X1768168Y80497D03*
X1758568Y79697D03*
X1765068Y80397D03*
X1767170Y83607D03*
X1767990Y76797D03*
X1760478Y90027D03*
X1770368Y72691D03*
X1766278Y93627D03*
X1764678Y122927D03*
X1758300Y128242D03*
X1768483Y166260D03*
X1763435Y166862D03*
X1765870Y179392D03*
X1765820Y182282D03*
X1767300Y174587D03*
X1755078Y216928D03*
X1761500Y214062D03*
X1765000D03*
X1768500D03*
X1766880Y234842D03*
Y231842D03*
X1758500Y231822D03*
Y234822D03*
X1755378Y233528D03*
X1755078Y219428D03*
Y221928D03*
Y224428D03*
X1763731Y283817D03*
X1766725Y282981D03*
X1763731Y279517D03*
X1760398Y279548D03*
X1766765Y279433D03*
X1757439Y279611D03*
X1760398Y283848D03*
X1759509Y292434D03*
X1762549Y286704D03*
X1757439Y283911D03*
X1768045Y295238D03*
X1765053Y295188D03*
X1762285Y295137D03*
X1759629Y295164D03*
X1767309Y290994D03*
X1763045Y289691D03*
X1759529Y289864D03*
X1766655Y286531D03*
X1760104Y301648D03*
X1767455Y302651D03*
X1764955Y301951D03*
X1758563Y310478D03*
X1754963D03*
X1769230D03*
X1770520Y364148D03*
X1756800Y364048D03*
X1770520Y368148D03*
X1768757Y380498D03*
X1756800Y368048D03*
X1770280Y372452D03*
X1770220Y377452D03*
Y382952D03*
X1757066Y435721D03*
X1767300Y461393D03*
X1765670Y458012D03*
X1757650Y461393D03*
X1767300Y465893D03*
X1768560Y539042D03*
X1766060D03*
X1768317Y686375D03*
X1764112Y703948D03*
X1761612D03*
X1764112Y695648D03*
X1763570Y693192D03*
X1761612Y695648D03*
X1755112Y703948D03*
Y695648D03*
X1755013Y692967D03*
X1757612Y703948D03*
Y695648D03*
X1764072Y720508D03*
X1761572D03*
X1764112Y712248D03*
X1761612D03*
X1755072Y720508D03*
X1755112Y712248D03*
X1757572Y720508D03*
X1757612Y712248D03*
X1758352Y1317368D03*
Y1322168D03*
X1760160Y1476032D03*
X1763730Y1483712D03*
Y1480712D03*
X1763830Y1490782D03*
Y1487782D03*
X1782305Y13647D03*
X1775556Y21471D03*
X1775830Y26522D03*
X1777754Y37746D03*
X1781774Y54462D03*
X1774274Y50742D03*
X1776710Y53562D03*
X1779411Y50692D03*
X1774328Y60087D03*
X1779778Y70027D03*
X1774328Y62987D03*
X1775580Y73330D03*
X1785178Y86927D03*
X1779778Y72927D03*
X1787790Y85132D03*
X1781485Y88192D03*
X1785142Y76032D03*
X1773611Y88293D03*
X1785178Y89927D03*
X1782000Y128455D03*
X1771915Y128393D03*
X1782000Y125955D03*
Y123455D03*
X1771915Y125893D03*
Y123393D03*
X1784238Y150744D03*
X1780320Y153162D03*
X1774950Y167392D03*
X1779500Y171692D03*
X1780320Y177602D03*
X1777520Y178403D03*
Y173903D03*
X1782600Y175932D03*
X1778778Y216928D03*
X1783878D03*
X1772000Y214062D03*
X1786690Y234782D03*
Y231782D03*
X1783800Y231762D03*
Y234762D03*
X1775140Y234792D03*
Y231792D03*
X1778778Y219428D03*
Y221928D03*
X1783878Y224428D03*
Y226928D03*
Y219428D03*
Y221928D03*
X1779226Y275604D03*
X1783563Y273471D03*
X1786089D03*
X1771029Y295164D03*
X1771229Y291064D03*
X1786089Y287641D03*
X1783563D03*
X1777354Y295489D03*
X1772863Y310478D03*
X1783018Y301729D03*
X1782324Y410432D03*
Y403932D03*
Y425432D03*
Y418932D03*
X1782420Y443987D03*
X1773870Y438222D03*
X1782420Y447137D03*
X1781470Y452065D03*
X1776160Y592792D03*
X1778310Y591152D03*
X1781720Y592742D03*
X1771866Y1737108D03*
X1787768Y3010D03*
X1793061Y24659D03*
X1794910Y44573D03*
X1799920Y52594D03*
X1788238Y82292D03*
Y78062D03*
Y74912D03*
X1797324Y161465D03*
X1803215Y154032D03*
X1797663Y269571D03*
X1800189D03*
X1790563Y273471D03*
X1793089D03*
X1793269Y287641D03*
X1790743D03*
X1791619Y294441D03*
X1789093D03*
X1802763Y308671D03*
X1795763D03*
X1798289D03*
X1788763D03*
X1791289D03*
X1803129Y362293D03*
X1800160Y362542D03*
X1800340Y387062D03*
X1802929Y385293D03*
X1791494Y386536D03*
X1795479Y408056D03*
X1792450Y410615D03*
X1792507Y403932D03*
X1795468Y421334D03*
X1792220Y425432D03*
X1792335Y418775D03*
X1796020Y451162D03*
X1791888Y683805D03*
X1800107Y1256426D03*
X1795484Y1496401D03*
X1800450Y1505230D03*
X1792645Y1511423D03*
X1798450Y1524830D03*
X1801450D03*
Y1527830D03*
X1795561Y1524729D03*
X1814322Y49388D03*
X1807549Y56415D03*
X1807580Y59397D03*
X1806920Y150862D03*
X1808910Y143902D03*
X1813335Y155435D03*
X1810835Y163986D03*
X1806365Y154032D03*
X1819939Y177243D03*
X1813325Y177257D03*
X1807220Y179897D03*
X1814349Y269634D03*
X1811823D03*
X1807249D03*
X1804723D03*
X1812349Y308734D03*
X1809823D03*
X1805289Y308671D03*
X1820307Y373829D03*
X1817157D03*
X1820144Y398052D03*
X1819374Y410432D03*
X1816224D03*
X1816994Y398052D03*
X1818874Y423932D03*
X1815724D03*
X1810792Y417432D03*
X1818816Y468872D03*
X1812161Y472521D03*
X1814537Y1322105D03*
X1803517Y1495567D03*
X1813700Y1494762D03*
X1807150Y1505675D03*
X1818289Y1501591D03*
X1811494Y1505349D03*
X1813994Y1507891D03*
X1818410Y1525815D03*
X1812250Y1521830D03*
X1811250Y1524830D03*
Y1527830D03*
X1807850D03*
X1804650D03*
Y1524830D03*
X1807850D03*
X1814370Y1528900D03*
X1814210Y1525815D03*
X1818524Y1528991D03*
X1834322Y49388D03*
X1828777Y156520D03*
X1823508Y158868D03*
X1835760Y185772D03*
X1828204Y328654D03*
X1829189Y363731D03*
X1829026Y367701D03*
X1829434Y406348D03*
X1834005Y401421D03*
X1821280Y413432D03*
X1834600Y406442D03*
X1826914Y431718D03*
X1823426Y1507916D03*
X1831994Y1525977D03*
X1835334Y1520921D03*
X1828510Y1525915D03*
X1821710D03*
X1830466Y1606658D03*
X1828880Y1626595D03*
Y1646595D03*
Y1666595D03*
Y1686595D03*
X1841257Y151402D03*
X1838910Y185772D03*
X1844157Y182210D03*
X1848435Y172187D03*
X1838880Y195162D03*
X1843134Y244362D03*
X1850331Y311946D03*
X1840691Y329470D03*
Y349470D03*
Y369470D03*
X1836750Y373632D03*
X1836294Y383592D03*
X1840691Y389470D03*
Y409470D03*
Y429470D03*
Y449470D03*
X1838020Y459121D03*
X1838379Y453921D03*
X1840691Y469470D03*
Y489470D03*
Y509470D03*
Y529470D03*
Y549470D03*
Y569470D03*
Y589470D03*
Y669470D03*
Y1329470D03*
Y1409470D03*
Y1429470D03*
Y1449470D03*
Y1469470D03*
Y1489470D03*
Y1509470D03*
Y1529470D03*
Y1549470D03*
Y1569470D03*
Y1589470D03*
X1854096Y52383D03*
X1854470Y112379D03*
Y152379D03*
Y172379D03*
Y192379D03*
Y212379D03*
Y232379D03*
Y252379D03*
Y272379D03*
Y292379D03*
G54D56*
X922441Y154311D03*
Y243799D03*
G54D30*
X174685Y637367D03*
Y647210D03*
X174393Y668511D03*
Y678354D03*
X205159Y1430034D03*
X195316D03*
X393067Y1354446D03*
X422833D03*
X453169D03*
X468443Y1379662D03*
X482543Y1353962D03*
X526478Y1439952D03*
Y1449795D03*
X708795Y1429579D03*
X718638D03*
X1077638Y133866D03*
X1131715Y1532913D03*
X1168627Y1466363D03*
X1178470D03*
X1175215Y1532913D03*
X1369208Y1353946D03*
X1398974D03*
X1429310D03*
X1444043Y1379362D03*
X1459076Y1353946D03*
X1502956Y1439530D03*
Y1449373D03*
X1670101Y1463655D03*
X1682882Y618174D03*
Y628017D03*
Y669109D03*
Y678952D03*
X1679944Y1463655D03*
X1769790Y194789D03*
Y204632D03*
X1799350Y194789D03*
Y204632D03*
X1836248Y269763D03*
X1826405D03*
X1836248Y299056D03*
X1826405D03*
G54D31*
X186697Y1578182D03*
Y1590094D03*
X191997Y1602380D03*
Y1614292D03*
X194497Y1578182D03*
X206557D03*
X198757D03*
X194497Y1590094D03*
X206557D03*
X198757D03*
X199797Y1614292D03*
Y1602380D03*
X204057Y1614292D03*
Y1602380D03*
X218617Y1578182D03*
X210817D03*
X222877D03*
X218617Y1590094D03*
X210817D03*
X222877D03*
X211857Y1614292D03*
Y1602380D03*
X223917Y1614292D03*
X216117D03*
X223917Y1602380D03*
X216117D03*
X230677Y1578182D03*
X234937D03*
X230677Y1590094D03*
X234937D03*
X228177Y1614292D03*
X235977D03*
X228177Y1602380D03*
X235977D03*
X240237D03*
Y1614292D03*
X242737Y1578182D03*
X246997D03*
X254797D03*
X242737Y1590094D03*
X246997D03*
X254797D03*
X248037Y1602380D03*
Y1614292D03*
X252297Y1602380D03*
Y1614292D03*
X266857Y1578182D03*
X259057D03*
X271117D03*
X266857Y1590094D03*
X259057D03*
X271117D03*
X260097Y1602380D03*
Y1614292D03*
X272157Y1602380D03*
Y1614292D03*
X264357D03*
Y1602380D03*
X278917Y1578182D03*
X283177D03*
X278917Y1590094D03*
X283177D03*
X284217Y1602380D03*
Y1614292D03*
X276417D03*
Y1602380D03*
X288477Y1614292D03*
Y1602380D03*
X290977Y1578182D03*
X295237D03*
X303037D03*
X290977Y1590094D03*
X295237D03*
X303037D03*
X296277Y1614292D03*
Y1602380D03*
X300537D03*
Y1614292D03*
X315097Y1578182D03*
X307297D03*
X319357D03*
X315097Y1590094D03*
X307297D03*
X319357D03*
X308337Y1602380D03*
Y1614292D03*
X320397D03*
X312597D03*
X320397Y1602380D03*
X312597D03*
X327157Y1578182D03*
X331417D03*
X327157Y1590094D03*
X331417D03*
X324657Y1602380D03*
X332457D03*
X324657Y1614292D03*
X332457D03*
X336717Y1602380D03*
Y1614292D03*
X339217Y1578182D03*
X343477D03*
X351277D03*
X339217Y1590094D03*
X343477D03*
X351277D03*
X344517Y1602380D03*
Y1614292D03*
X348777Y1602380D03*
Y1614292D03*
X363337Y1578088D03*
X355537Y1578182D03*
X367597D03*
X363337Y1590094D03*
X355537D03*
X367597D03*
X356577Y1602380D03*
Y1614292D03*
X368637D03*
X360837D03*
X368637Y1602286D03*
X360837Y1602380D03*
X375397Y1578182D03*
Y1590094D03*
X372897Y1602380D03*
X380697D03*
X372897Y1614292D03*
X380697D03*
X482911Y1578182D03*
X478651D03*
X470851D03*
X482911Y1590094D03*
X478651D03*
X470851D03*
X483951Y1614292D03*
Y1602380D03*
X476151D03*
Y1614292D03*
X494971Y1578182D03*
X490711D03*
X494971Y1590094D03*
X490711D03*
X500271Y1614292D03*
Y1602380D03*
X488211Y1614292D03*
Y1602380D03*
X496011D03*
Y1614292D03*
X507031Y1578182D03*
X514831D03*
X502771D03*
X507031Y1590094D03*
X514831D03*
X502771D03*
X512331Y1614292D03*
Y1602380D03*
X508071Y1614292D03*
Y1602380D03*
X531151Y1578182D03*
X519091D03*
X526891D03*
X531151Y1590094D03*
X519091D03*
X526891D03*
X532191Y1614292D03*
Y1602380D03*
X524391Y1614292D03*
Y1602380D03*
X520131D03*
Y1614292D03*
X543211Y1578182D03*
X538951D03*
X543211Y1590094D03*
X538951D03*
X548511Y1614292D03*
Y1602380D03*
X536451D03*
Y1614292D03*
X544251Y1602380D03*
Y1614292D03*
X555271Y1578182D03*
X563071D03*
X551011D03*
X555271Y1590094D03*
X563071D03*
X551011D03*
X560571Y1614292D03*
Y1602380D03*
X556311Y1614292D03*
Y1602380D03*
X579391Y1578182D03*
X567331D03*
X575131D03*
X579391Y1590094D03*
X567331D03*
X575131D03*
X580431Y1614292D03*
X572631D03*
X580431Y1602380D03*
X572631D03*
X568371D03*
Y1614292D03*
X599251Y1578182D03*
X591451D03*
X587191D03*
X599251Y1590094D03*
X591451D03*
X587191D03*
X596751Y1614292D03*
Y1602380D03*
X584691D03*
Y1614292D03*
X592491Y1602380D03*
Y1614292D03*
X615571Y1578182D03*
X603511D03*
X611311D03*
X615571Y1590094D03*
X603511D03*
X611311D03*
X608811Y1602380D03*
Y1614292D03*
X604551Y1602380D03*
Y1614292D03*
X627631Y1578182D03*
X623371D03*
X627631Y1590094D03*
X623371D03*
X628671Y1602380D03*
Y1614292D03*
X620871D03*
Y1602380D03*
X616611Y1614292D03*
Y1602380D03*
X647491Y1578088D03*
X639691Y1578182D03*
X635431D03*
X647491Y1590094D03*
X639691D03*
X635431D03*
X644991Y1614292D03*
Y1602380D03*
X632931D03*
Y1614292D03*
X640731D03*
Y1602380D03*
X651751Y1578182D03*
X659551D03*
X651751Y1590094D03*
X659551D03*
X657051Y1602380D03*
Y1614292D03*
X652791Y1602286D03*
Y1614292D03*
X664851Y1602380D03*
Y1614292D03*
X1194572Y1578182D03*
Y1590094D03*
X1199872Y1614292D03*
Y1602380D03*
X1202372Y1578182D03*
X1214432D03*
X1206632D03*
X1202372Y1590094D03*
X1214432D03*
X1206632D03*
X1207672Y1602380D03*
Y1614292D03*
X1211932D03*
Y1602380D03*
X1218692Y1578182D03*
X1226492D03*
X1230752D03*
X1218692Y1590094D03*
X1226492D03*
X1230752D03*
X1219732Y1614292D03*
Y1602380D03*
X1231792Y1614292D03*
Y1602380D03*
X1223992D03*
Y1614292D03*
X1238552Y1578182D03*
X1242812D03*
X1238552Y1590094D03*
X1242812D03*
X1236052Y1602380D03*
Y1614292D03*
X1243852D03*
Y1602380D03*
X1248112D03*
Y1614292D03*
X1250612Y1578182D03*
X1262672D03*
X1254872D03*
X1250612Y1590094D03*
X1262672D03*
X1254872D03*
X1255912Y1614292D03*
Y1602380D03*
X1260172D03*
Y1614292D03*
X1266932Y1578182D03*
X1274732D03*
X1278992D03*
X1266932Y1590094D03*
X1274732D03*
X1278992D03*
X1267972Y1614292D03*
Y1602380D03*
X1272232D03*
Y1614292D03*
X1280032D03*
Y1602380D03*
X1286792Y1578182D03*
X1298852D03*
X1291052D03*
X1286792Y1590094D03*
X1298852D03*
X1291052D03*
X1284292Y1602380D03*
Y1614292D03*
X1292092D03*
Y1602380D03*
X1296352D03*
Y1614292D03*
X1303112Y1578182D03*
X1310912D03*
X1315172D03*
X1303112Y1590094D03*
X1310912D03*
X1315172D03*
X1304152Y1602380D03*
Y1614292D03*
X1308412Y1602380D03*
Y1614292D03*
X1322972Y1578182D03*
X1327232D03*
X1322972Y1590094D03*
X1327232D03*
X1316212Y1614292D03*
Y1602380D03*
X1328272D03*
Y1614292D03*
X1320472Y1602380D03*
Y1614292D03*
X1335032Y1578182D03*
X1347092D03*
X1339292D03*
X1335032Y1590094D03*
X1347092D03*
X1339292D03*
X1340332Y1602380D03*
Y1614292D03*
X1332532Y1602380D03*
Y1614292D03*
X1344592Y1602380D03*
Y1614292D03*
X1351352Y1578182D03*
X1359152D03*
X1363412D03*
X1351352Y1590094D03*
X1359152D03*
X1363412D03*
X1352392Y1602380D03*
Y1614292D03*
X1356652Y1602380D03*
Y1614292D03*
X1371212Y1578088D03*
X1375472Y1578182D03*
X1371212Y1590094D03*
X1375472D03*
X1364452Y1602380D03*
Y1614292D03*
X1376512Y1602286D03*
Y1614292D03*
X1368712Y1602380D03*
Y1614292D03*
X1383272Y1578182D03*
Y1590094D03*
X1380772Y1602380D03*
Y1614292D03*
X1388572D03*
Y1602380D03*
X1460095Y1578182D03*
Y1590094D03*
X1472155Y1578182D03*
X1467895D03*
X1472155Y1590094D03*
X1467895D03*
X1477455Y1602380D03*
Y1614292D03*
X1473195D03*
Y1602380D03*
X1465395D03*
Y1614292D03*
X1492015Y1578182D03*
X1484215D03*
X1479955D03*
X1492015Y1590094D03*
X1484215D03*
X1479955D03*
X1489515Y1614292D03*
Y1602380D03*
X1485255D03*
Y1614292D03*
X1508335Y1578182D03*
X1496275D03*
X1504075D03*
X1508335Y1590094D03*
X1496275D03*
X1504075D03*
X1501575Y1614292D03*
Y1602380D03*
X1509375D03*
Y1614292D03*
X1497315Y1602380D03*
Y1614292D03*
X1520395Y1578182D03*
X1516135D03*
X1520395Y1590094D03*
X1516135D03*
X1525695Y1614292D03*
Y1602380D03*
X1521435D03*
Y1614292D03*
X1513635D03*
Y1602380D03*
X1540255Y1578182D03*
X1532455D03*
X1528195D03*
X1540255Y1590094D03*
X1532455D03*
X1528195D03*
X1537755Y1614292D03*
Y1602380D03*
X1533495D03*
Y1614292D03*
X1556575Y1578182D03*
X1544515D03*
X1552315D03*
X1556575Y1590094D03*
X1544515D03*
X1552315D03*
X1549815Y1614292D03*
Y1602380D03*
X1557615D03*
Y1614292D03*
X1545555Y1602380D03*
Y1614292D03*
X1568635Y1578182D03*
X1564375D03*
X1568635Y1590094D03*
X1564375D03*
X1573935Y1614292D03*
Y1602380D03*
X1569675Y1614292D03*
Y1602380D03*
X1561875Y1614292D03*
Y1602380D03*
X1588495Y1578182D03*
X1580695D03*
X1576435D03*
X1588495Y1590094D03*
X1580695D03*
X1576435D03*
X1585995Y1614292D03*
Y1602380D03*
X1581735D03*
Y1614292D03*
X1604815Y1578182D03*
X1592755D03*
X1600555D03*
X1604815Y1590094D03*
X1592755D03*
X1600555D03*
X1598055Y1614292D03*
Y1602380D03*
X1605855Y1614292D03*
Y1602380D03*
X1593795Y1614292D03*
Y1602380D03*
X1616875Y1578182D03*
X1612615D03*
X1616875Y1590094D03*
X1612615D03*
X1622175Y1614292D03*
Y1602380D03*
X1617915Y1614292D03*
Y1602380D03*
X1610115Y1614292D03*
Y1602380D03*
X1636735Y1578088D03*
X1628935Y1578182D03*
X1624675D03*
X1636735Y1590094D03*
X1628935D03*
X1624675D03*
X1634235Y1614292D03*
Y1602380D03*
X1629975Y1614292D03*
Y1602380D03*
X1640995Y1578182D03*
X1648795D03*
X1640995Y1590094D03*
X1648795D03*
X1646295Y1614292D03*
Y1602380D03*
X1654095Y1614292D03*
Y1602380D03*
X1642035Y1614292D03*
Y1602286D03*
G54D51*
X793879Y194881D03*
X789942Y204724D03*
X793879Y214567D03*
X805690Y188976D03*
Y220472D03*
X817501Y194881D03*
Y214567D03*
X821438Y204724D03*
X841240Y1407480D03*
X832154Y1411244D03*
X828390Y1420330D03*
X832154Y1429416D03*
X841240Y1433180D03*
X850326Y1411244D03*
X854090Y1420330D03*
X850326Y1429416D03*
X916545Y309459D03*
X911494Y321653D03*
X916545Y333847D03*
X940933Y309459D03*
X928739Y304408D03*
Y338898D03*
X940933Y333847D03*
X945984Y321653D03*
X1003390Y1420330D03*
X1016240Y1407480D03*
X1007154Y1411244D03*
Y1429416D03*
X1016240Y1433180D03*
X1025326Y1411244D03*
X1029090Y1420330D03*
X1025326Y1429416D03*
X1045847Y194881D03*
X1041910Y204724D03*
X1045847Y214567D03*
X1069469Y194881D03*
X1057658Y188976D03*
X1069469Y214567D03*
X1057658Y220472D03*
X1073406Y204724D03*
G54D24*
X70472Y173228D03*
Y236220D03*
G54D44*
X450000Y278543D03*
X460000D03*
X470000D03*
X483500Y246362D03*
X473500D03*
X480000Y278543D03*
X493500Y246362D03*
X490000Y278543D03*
X500000D03*
X498563Y607067D03*
X510000Y278543D03*
X520000D03*
X518563Y607067D03*
X508563D03*
X549236Y1441207D03*
X559236D03*
X569236D03*
X688500Y1601900D03*
Y1611900D03*
Y1621900D03*
X1041435Y143357D03*
Y153357D03*
X1056225Y143131D03*
Y153131D03*
X1041435Y163357D03*
X1056225Y163131D03*
X1099970Y1712570D03*
Y1722570D03*
X1689646Y115669D03*
X1679646D03*
X1689646Y125669D03*
Y135669D03*
X1679646Y125669D03*
Y135669D03*
X1689646Y145669D03*
Y155669D03*
X1679646Y145669D03*
Y155669D03*
X1689646Y165669D03*
X1679646D03*
X1689646Y175669D03*
X1679646D03*
X1771457Y1634646D03*
Y1624646D03*
Y1644646D03*
G54D14*
X27699Y1258727D03*
Y1255381D03*
Y1262074D03*
X43841Y994357D03*
X36399Y1054593D03*
X36449Y1257262D03*
X43841Y1255381D03*
Y1258727D03*
Y1252034D03*
X33546Y1273364D03*
X30746D03*
X57299Y766798D03*
X52541Y957546D03*
Y954200D03*
Y1021129D03*
Y1024475D03*
Y1051247D03*
X57399Y1258727D03*
X52820Y1253862D03*
X60446Y1273364D03*
X49546D03*
X46746D03*
X57399Y1262074D03*
X66099Y780184D03*
Y773491D03*
Y786877D03*
Y803609D03*
Y796916D03*
Y790223D03*
Y847113D03*
Y853806D03*
Y860499D03*
Y863845D03*
Y883924D03*
Y877231D03*
Y870538D03*
Y890617D03*
Y897310D03*
Y900656D03*
Y914042D03*
Y907349D03*
Y927428D03*
Y920735D03*
Y934121D03*
Y944160D03*
Y937467D03*
Y950853D03*
Y980971D03*
Y974278D03*
Y994357D03*
Y987664D03*
Y1027822D03*
Y1021129D03*
Y1047900D03*
Y1041207D03*
Y1034515D03*
Y1061286D03*
Y1054593D03*
Y1074672D03*
Y1067979D03*
Y1091404D03*
Y1081365D03*
Y1084711D03*
Y1098097D03*
Y1111483D03*
Y1104790D03*
Y1128215D03*
Y1118176D03*
Y1121522D03*
Y1141601D03*
Y1134908D03*
Y1148294D03*
Y1154987D03*
Y1158333D03*
Y1171719D03*
Y1165026D03*
Y1185105D03*
Y1178412D03*
Y1191798D03*
Y1208530D03*
Y1201837D03*
Y1195144D03*
X66189Y1257488D03*
X73541Y1255381D03*
Y1258727D03*
Y1252034D03*
X76446Y1273364D03*
X63246D03*
X82241Y770144D03*
X86999Y766798D03*
X82241Y776837D03*
Y786877D03*
Y783530D03*
Y800263D03*
Y793570D03*
Y850459D03*
Y843766D03*
Y867192D03*
Y860499D03*
Y857152D03*
Y873885D03*
Y880577D03*
Y887270D03*
Y897310D03*
Y893963D03*
Y917389D03*
Y910696D03*
Y904003D03*
Y924081D03*
Y934121D03*
Y930774D03*
Y947507D03*
Y940814D03*
Y957546D03*
Y954200D03*
Y977625D03*
Y970932D03*
Y991011D03*
Y984318D03*
Y994357D03*
Y1021129D03*
Y1024475D03*
Y1031168D03*
Y1044554D03*
Y1037861D03*
Y1051247D03*
Y1071326D03*
Y1064633D03*
Y1078018D03*
Y1094751D03*
Y1088058D03*
Y1081365D03*
Y1108137D03*
Y1101444D03*
Y1124869D03*
Y1118176D03*
Y1114829D03*
Y1144948D03*
Y1138255D03*
Y1131562D03*
Y1161680D03*
Y1154987D03*
Y1151641D03*
Y1175066D03*
Y1168373D03*
Y1181759D03*
Y1191798D03*
Y1188452D03*
Y1205184D03*
Y1198491D03*
X87099Y1258727D03*
X82241Y1248688D03*
X84334Y1254263D03*
X92946Y1273364D03*
X90146D03*
X79246D03*
X87099Y1262074D03*
X103241Y994357D03*
X95849Y1257262D03*
X103241Y1255381D03*
Y1258727D03*
Y1252034D03*
X108946Y1273364D03*
X106146D03*
X116567Y766775D03*
X125499Y867192D03*
Y880577D03*
Y873885D03*
Y893963D03*
Y887270D03*
Y917389D03*
Y910696D03*
Y904003D03*
Y930774D03*
Y924081D03*
Y947507D03*
Y940814D03*
Y964239D03*
Y954200D03*
X111941Y957546D03*
Y954200D03*
X125499Y977625D03*
Y970932D03*
Y991011D03*
Y984318D03*
Y1031168D03*
Y1024475D03*
Y1017782D03*
Y1044554D03*
Y1037861D03*
Y1057940D03*
Y1051247D03*
Y1061286D03*
Y1078018D03*
Y1071326D03*
Y1064633D03*
Y1094751D03*
Y1088058D03*
Y1108137D03*
Y1101444D03*
Y1124869D03*
Y1114829D03*
Y1144948D03*
Y1138255D03*
Y1131562D03*
Y1161680D03*
Y1151641D03*
Y1175066D03*
Y1168373D03*
Y1188452D03*
Y1181759D03*
Y1205184D03*
Y1198491D03*
Y1225263D03*
Y1218570D03*
Y1211877D03*
Y1241995D03*
Y1235302D03*
X125412Y1257102D03*
X125499Y1248688D03*
X116799Y1258727D03*
X111941Y1248688D03*
X114191Y1254604D03*
X119846Y1273364D03*
X122646D03*
X116799Y1262074D03*
X132941Y863845D03*
X141641D03*
X132941Y883924D03*
X141641D03*
X132941Y870538D03*
X141641D03*
X132941Y877231D03*
X141641D03*
X132941Y900656D03*
X141641D03*
X132941Y890617D03*
X141641D03*
X132941Y907349D03*
X141641D03*
X132941Y914042D03*
X141641D03*
X132941Y920735D03*
X141641D03*
X132941Y927428D03*
X141641D03*
X132941Y937467D03*
X141641D03*
X132941Y944160D03*
X141641D03*
X132941Y960892D03*
X141641D03*
X132941Y950853D03*
X141641D03*
Y957546D03*
Y954200D03*
X132941Y980971D03*
X141641D03*
X132941Y974278D03*
X141641D03*
X132941Y967585D03*
X141641D03*
X132941Y987664D03*
X141641D03*
Y994357D03*
X132941Y1027822D03*
X141641D03*
X132941Y1017782D03*
X141641D03*
X132941Y1047900D03*
X141641D03*
X132941Y1041207D03*
X141641D03*
X132941Y1034515D03*
X141641D03*
Y1061286D03*
X132941D03*
X141641Y1054593D03*
X132941D03*
X141641Y1057940D03*
Y1074672D03*
X132941D03*
X141641Y1067979D03*
X132941D03*
X141641Y1091404D03*
X132941D03*
X141641Y1084711D03*
X132941D03*
X141641Y1111483D03*
X132941D03*
X141641Y1104790D03*
X132941D03*
X141641Y1098097D03*
X132941D03*
X141641Y1128215D03*
X132941D03*
X141641Y1121522D03*
X132941D03*
X141641Y1141601D03*
X132941D03*
X141641Y1134908D03*
X132941D03*
X141641Y1158333D03*
X132941D03*
X141641Y1148294D03*
X132941D03*
X141641Y1171719D03*
X132941D03*
X141641Y1165026D03*
X132941D03*
X141641Y1185105D03*
X132941D03*
X141641Y1178412D03*
X132941D03*
X141641Y1208530D03*
X132941D03*
X141641Y1201837D03*
X132941D03*
X141641Y1195144D03*
X132941D03*
Y1221916D03*
X141641D03*
X132941Y1215223D03*
X141641D03*
X132941Y1238648D03*
X141641D03*
X132941Y1231955D03*
X141641D03*
X129933Y1238461D03*
X132941Y1245341D03*
X141641D03*
X132941Y1255381D03*
Y1258727D03*
Y1252034D03*
X141641Y1248688D03*
X143675Y1255567D03*
X135846Y1273364D03*
X138646D03*
X132941Y1262074D03*
X146367Y766775D03*
X155199Y867192D03*
X146499D03*
X155199Y880577D03*
X146499D03*
X155199Y873885D03*
X146499D03*
X155199Y893963D03*
X146499D03*
X155199Y887270D03*
X146499D03*
X155199Y917389D03*
X146499D03*
X155199Y910696D03*
X146499D03*
X155199Y904003D03*
X146499D03*
X155199Y930774D03*
X146499D03*
X155199Y924081D03*
X146499D03*
X155199Y947507D03*
X146499D03*
X155199Y940814D03*
X146499D03*
X155199Y964239D03*
X146499D03*
X155199Y954200D03*
X146499D03*
X155199Y977625D03*
X146499D03*
X155199Y970932D03*
X146499D03*
X155199Y991011D03*
X146499D03*
X155199Y984318D03*
X146499D03*
X155199Y1031168D03*
X146499D03*
X155199Y1024475D03*
X146499D03*
X155199Y1017782D03*
X146499D03*
X155199Y1044554D03*
X146499D03*
X155199Y1037861D03*
X146499D03*
X155199Y1057940D03*
X146499D03*
X155199Y1051247D03*
X146499D03*
X155199Y1078018D03*
X146499D03*
X155199Y1071326D03*
X146499D03*
X155199Y1064633D03*
X146499D03*
X155199Y1094751D03*
X146499D03*
X155199Y1088058D03*
X146499D03*
X155199Y1108137D03*
X146499D03*
X155199Y1101444D03*
X146499D03*
X155199Y1124869D03*
X146499D03*
X155199Y1114829D03*
X146499D03*
X155199Y1144948D03*
X146499D03*
X155199Y1138255D03*
X146499D03*
X155199Y1131562D03*
X146499D03*
X155199Y1161680D03*
X146499D03*
X155199Y1151641D03*
X146499D03*
X155199Y1175066D03*
X146499D03*
X155199Y1168373D03*
X146499D03*
X155199Y1188452D03*
X146499D03*
X155199Y1181759D03*
X146499D03*
X155199Y1205184D03*
X146499D03*
X155199Y1198491D03*
X146499D03*
X155199Y1225263D03*
X146499D03*
X155199Y1218570D03*
X146499D03*
X155199Y1211877D03*
X146499D03*
X155199Y1241995D03*
X146499D03*
X155199Y1235302D03*
X146499D03*
X155135Y1257134D03*
X155199Y1248688D03*
X146499D03*
X160130Y1251847D03*
X146499Y1258727D03*
X149546Y1273364D03*
X152346D03*
X146499Y1265420D03*
Y1262074D03*
X176099Y766798D03*
X176199Y867192D03*
X171341Y863845D03*
X162641D03*
X171341Y883924D03*
X162641D03*
X176199Y880577D03*
Y873885D03*
X171341Y877231D03*
X162641D03*
X171341Y870538D03*
X162641D03*
X171341Y900656D03*
X162641D03*
X176199Y893963D03*
Y887270D03*
X171341Y890617D03*
X162641D03*
X176199Y917389D03*
Y910696D03*
Y904003D03*
X171341Y914042D03*
X162641D03*
X171341Y907349D03*
X162641D03*
X176199Y930774D03*
Y924081D03*
X171341Y927428D03*
X162641D03*
X171341Y920735D03*
X162641D03*
X176199Y947507D03*
Y940814D03*
X171341Y944160D03*
X162641D03*
X171341Y937467D03*
X162641D03*
X176199Y964239D03*
Y954200D03*
X171341Y960892D03*
X162641D03*
X171341Y950853D03*
X162641D03*
X171341Y957546D03*
Y954200D03*
Y980971D03*
X162641D03*
X176199Y977625D03*
Y970932D03*
X171341Y974278D03*
X162641D03*
X171341Y967585D03*
X162641D03*
X176199Y991011D03*
Y984318D03*
X171341Y987664D03*
X162641D03*
Y994357D03*
X176199Y1031168D03*
Y1024475D03*
Y1017782D03*
X171341Y1027822D03*
X162641D03*
X171341Y1017782D03*
X162641D03*
X171341Y1047900D03*
X162641D03*
X176199Y1044554D03*
Y1037861D03*
X171341Y1041207D03*
X162641D03*
X171341Y1034515D03*
X162641D03*
X176199Y1057940D03*
Y1051247D03*
X171341Y1061286D03*
X162641D03*
X171341Y1054593D03*
X162641D03*
X176199Y1078018D03*
Y1071326D03*
Y1064633D03*
X171341Y1074672D03*
X162641D03*
X171341Y1067979D03*
X162641D03*
X176199Y1094751D03*
Y1088058D03*
X171341Y1091404D03*
X162641D03*
X171341Y1084711D03*
X162641D03*
X171341Y1111483D03*
X162641D03*
X176199Y1108137D03*
Y1101444D03*
X171341Y1104790D03*
X162641D03*
X171341Y1098097D03*
X162641D03*
X171341Y1128215D03*
X162641D03*
X176199Y1124869D03*
Y1114829D03*
X171341Y1121522D03*
X162641D03*
X176199Y1144948D03*
Y1138255D03*
Y1131562D03*
X171341Y1141601D03*
X162641D03*
X171341Y1134908D03*
X162641D03*
X176199Y1161680D03*
Y1151641D03*
X171341Y1158333D03*
X162641D03*
X171341Y1148294D03*
X162641D03*
X176199Y1175066D03*
Y1168373D03*
X171341Y1171719D03*
X162641D03*
X171341Y1165026D03*
X162641D03*
X176199Y1188452D03*
Y1181759D03*
X171341Y1185105D03*
X162641D03*
X171341Y1178412D03*
X162641D03*
X176199Y1205184D03*
Y1198491D03*
X171341Y1208530D03*
X162641D03*
X171341Y1201837D03*
X162641D03*
X171341Y1195144D03*
X162641D03*
X176199Y1225263D03*
Y1218570D03*
Y1211877D03*
X162641Y1221916D03*
X171341D03*
Y1215223D03*
X162641D03*
X176199Y1241995D03*
Y1235302D03*
X171341Y1238648D03*
X162641D03*
X171341Y1231955D03*
X162641D03*
X176199Y1248688D03*
X171341Y1245341D03*
X162641D03*
X176199Y1258727D03*
X162641Y1255381D03*
Y1258727D03*
Y1252034D03*
X171341Y1248688D03*
X171947Y1255837D03*
X165546Y1273364D03*
X168346D03*
X176199Y1265420D03*
X162641D03*
Y1262074D03*
X176199D03*
X191491Y863845D03*
X184899Y867192D03*
X192341Y883924D03*
Y877231D03*
Y870538D03*
X184899Y880577D03*
Y873885D03*
X192341Y900656D03*
Y890617D03*
X184899Y893963D03*
Y887270D03*
X192341Y914042D03*
Y907349D03*
X184899Y917389D03*
Y910696D03*
Y904003D03*
X191491Y927428D03*
X192341Y920735D03*
X184899Y930774D03*
Y924081D03*
X192341Y937467D03*
Y944160D03*
X184899Y947507D03*
Y940814D03*
X192341Y960892D03*
Y950853D03*
X184899Y964239D03*
Y954200D03*
X192341Y974278D03*
Y980971D03*
Y967585D03*
X184899Y977625D03*
Y970932D03*
X192341Y987664D03*
X184899Y991011D03*
Y984318D03*
X192341Y1027822D03*
Y1017782D03*
X184899Y1031168D03*
Y1024475D03*
Y1017782D03*
X192341Y1047900D03*
Y1041207D03*
Y1034515D03*
X184899Y1044554D03*
Y1037861D03*
X192341Y1054593D03*
Y1061286D03*
X184899Y1057940D03*
Y1051247D03*
Y1061286D03*
X192341Y1074672D03*
Y1067979D03*
X184899Y1078018D03*
Y1071326D03*
Y1064633D03*
X192341Y1091404D03*
X191491Y1084711D03*
X184899Y1094751D03*
Y1088058D03*
X192341Y1111483D03*
Y1104790D03*
Y1098097D03*
X184899Y1108137D03*
Y1101444D03*
X192341Y1128215D03*
Y1121522D03*
X184899Y1124869D03*
Y1114829D03*
X192341Y1141601D03*
Y1134908D03*
X184899Y1144948D03*
Y1138255D03*
Y1131562D03*
X191491Y1158333D03*
X192341Y1148294D03*
X184899Y1161680D03*
Y1151641D03*
X192341Y1171719D03*
Y1165026D03*
X184899Y1175066D03*
Y1168373D03*
X192341Y1185105D03*
Y1178412D03*
X184899Y1188452D03*
Y1181759D03*
X192341Y1208530D03*
Y1201837D03*
Y1195144D03*
X184899Y1205184D03*
Y1198491D03*
X192341Y1221916D03*
Y1215223D03*
X184899Y1225263D03*
Y1218570D03*
Y1211877D03*
X192341Y1238648D03*
X191491Y1231955D03*
X184899Y1241995D03*
Y1235302D03*
X184923Y1258871D03*
X192341Y1245341D03*
X184899Y1248688D03*
X192341Y1255381D03*
Y1258727D03*
Y1252034D03*
X192594Y1271262D03*
X192605Y1268774D03*
X182046Y1273364D03*
X179246D03*
X192341Y1265420D03*
Y1262074D03*
X188119Y1580678D03*
Y1575686D03*
X188897Y1578182D03*
X192297D03*
X188119Y1592590D03*
Y1587598D03*
X188897Y1590094D03*
X192297D03*
X205799Y766798D03*
X205049Y867192D03*
X201041Y863845D03*
X205899Y873885D03*
Y880577D03*
X201041Y883924D03*
Y877231D03*
Y870538D03*
X205899Y893963D03*
Y887270D03*
X201041Y900656D03*
Y890617D03*
X205899Y917389D03*
Y910696D03*
Y904003D03*
X201041Y914042D03*
Y907349D03*
X205049Y930774D03*
Y924081D03*
X201041Y927428D03*
Y920735D03*
X205899Y940814D03*
Y947507D03*
X201041Y937467D03*
Y944160D03*
X205899Y964239D03*
Y954200D03*
X201041Y960892D03*
Y950853D03*
Y957546D03*
Y954200D03*
X205899Y970932D03*
Y977625D03*
X201041Y974278D03*
Y980971D03*
Y967585D03*
X205899Y991011D03*
Y984318D03*
X201041Y987664D03*
Y994357D03*
X205899Y1031168D03*
Y1017782D03*
Y1024475D03*
X201041Y1027822D03*
Y1017782D03*
X205899Y1044554D03*
Y1037861D03*
X201041Y1047900D03*
Y1041207D03*
Y1034515D03*
X205899Y1057940D03*
Y1051247D03*
X201041Y1054593D03*
Y1061286D03*
X205049Y1078018D03*
X205899Y1071326D03*
Y1064633D03*
X201041Y1074672D03*
Y1067979D03*
X205899Y1094751D03*
X205049Y1088058D03*
X201041Y1091404D03*
Y1084711D03*
X205899Y1101444D03*
Y1108137D03*
X201041Y1111483D03*
Y1104790D03*
Y1098097D03*
X205899Y1114829D03*
Y1124869D03*
X201041Y1128215D03*
Y1121522D03*
X205899Y1144948D03*
Y1138255D03*
Y1131562D03*
X201041Y1141601D03*
Y1134908D03*
X205049Y1161680D03*
Y1151641D03*
X201041Y1158333D03*
Y1148294D03*
X205899Y1168373D03*
Y1175066D03*
X201041Y1171719D03*
Y1165026D03*
X205899Y1188452D03*
Y1181759D03*
X201041Y1185105D03*
Y1178412D03*
X205899Y1205184D03*
Y1198491D03*
X201041Y1208530D03*
Y1201837D03*
Y1195144D03*
X205049Y1225263D03*
X205899Y1211877D03*
Y1218570D03*
X201041Y1221916D03*
Y1215223D03*
X205899Y1241995D03*
X205049Y1235302D03*
X201041Y1238648D03*
Y1231955D03*
X205899Y1248688D03*
X201041Y1245341D03*
X205899Y1258727D03*
X201041Y1248688D03*
X201193Y1257900D03*
X206268Y1271348D03*
X206337Y1268720D03*
X205899Y1265420D03*
Y1262074D03*
X193075Y1580678D03*
Y1575686D03*
X200179D03*
X205135D03*
X200179Y1580678D03*
X205135D03*
X200957Y1578182D03*
X204357D03*
X193075Y1592590D03*
Y1587598D03*
X200179Y1592590D03*
X205135D03*
X200179Y1587598D03*
X205135D03*
X198375Y1599884D03*
X193419D03*
X205479D03*
X200957Y1590094D03*
X204357D03*
X193419Y1616788D03*
Y1611796D03*
X198375D03*
X193419Y1604876D03*
X198375D03*
Y1616788D03*
X205479Y1611796D03*
Y1604876D03*
Y1616788D03*
X221191Y863845D03*
X215449Y867192D03*
X222041Y877231D03*
X221191Y870538D03*
X222041Y883924D03*
X214599Y873885D03*
Y880577D03*
X222041Y900656D03*
Y890617D03*
X214599Y893963D03*
Y887270D03*
X222041Y914042D03*
Y907349D03*
X214599Y917389D03*
Y910696D03*
Y904003D03*
X221241Y927428D03*
X222041Y920735D03*
X215449Y930774D03*
Y924081D03*
X222041Y944160D03*
X221191Y937467D03*
X214599Y940814D03*
Y947507D03*
X222041Y960892D03*
Y950853D03*
X214599Y964239D03*
Y954200D03*
X222041Y957546D03*
Y954200D03*
Y980971D03*
Y974278D03*
Y967585D03*
X214599Y970932D03*
Y977625D03*
Y991011D03*
Y984318D03*
X222041Y987664D03*
Y994357D03*
Y1027822D03*
Y1017782D03*
X214599Y1031168D03*
Y1017782D03*
Y1024475D03*
X222041Y1047900D03*
Y1041207D03*
Y1034515D03*
X214599Y1044554D03*
Y1037861D03*
X222041Y1054593D03*
Y1061286D03*
X214599Y1057940D03*
Y1051247D03*
X222041Y1067979D03*
X221191Y1074672D03*
X215449Y1078018D03*
X214599Y1071326D03*
Y1064633D03*
X222041Y1091404D03*
X221191Y1084711D03*
X214599Y1094751D03*
X215449Y1088058D03*
X222041Y1111483D03*
Y1098097D03*
Y1104790D03*
X214599Y1101444D03*
Y1108137D03*
X222041Y1128215D03*
Y1121522D03*
X214599Y1114829D03*
Y1124869D03*
X222041Y1141601D03*
X221191Y1134908D03*
X214599Y1144948D03*
Y1138255D03*
Y1131562D03*
X222041Y1158333D03*
X221191Y1148294D03*
X215449Y1161680D03*
Y1151641D03*
X222041Y1165026D03*
Y1171719D03*
X214599Y1168373D03*
Y1175066D03*
X222041Y1185105D03*
Y1178412D03*
X214599Y1188452D03*
Y1181759D03*
X222041Y1208530D03*
Y1201837D03*
Y1195144D03*
X214599Y1205184D03*
Y1198491D03*
X222041Y1221916D03*
Y1215223D03*
X215449Y1225263D03*
X214599Y1211877D03*
Y1218570D03*
X221191Y1231955D03*
Y1238648D03*
X214599Y1241995D03*
X215449Y1235302D03*
X222041Y1245341D03*
X214824Y1258711D03*
X214599Y1248688D03*
X222041Y1255381D03*
X219660Y1260492D03*
X222041Y1252034D03*
X224987Y1273535D03*
X222041Y1265420D03*
Y1262074D03*
X212239Y1580678D03*
X217195D03*
Y1575686D03*
X212239D03*
X224299D03*
Y1580678D03*
X225077Y1578182D03*
X213017D03*
X216417D03*
X212239Y1587598D03*
X217195D03*
X212239Y1592590D03*
X217195D03*
X224299Y1587598D03*
Y1592590D03*
X210435Y1599884D03*
X222495D03*
X217539D03*
X225077Y1590094D03*
X213017D03*
X216417D03*
X210435Y1611796D03*
Y1604876D03*
Y1616788D03*
X222495D03*
X217539D03*
X222495Y1604876D03*
Y1611796D03*
X217539Y1604876D03*
Y1611796D03*
X235499Y766798D03*
X234749Y867492D03*
X231591Y863845D03*
X235599Y874185D03*
Y880577D03*
X230741Y877231D03*
X231059Y871084D03*
X230741Y883924D03*
X235599Y893963D03*
Y887270D03*
X230741Y900656D03*
Y890617D03*
X235599Y917389D03*
Y910696D03*
Y904003D03*
X230741Y914042D03*
Y907349D03*
X235599Y930774D03*
Y924081D03*
X231541Y927428D03*
X230741Y920735D03*
X235599Y947507D03*
X234859Y940814D03*
X230741Y944660D03*
X231591Y937467D03*
X235599Y964239D03*
Y954200D03*
X230741Y960892D03*
Y950853D03*
X235599Y977625D03*
Y970932D03*
X230741Y980971D03*
Y974278D03*
Y967585D03*
X235599Y991011D03*
X230741Y987664D03*
X235599Y984318D03*
Y1031168D03*
X230741Y1027822D03*
Y1017782D03*
X235599D03*
Y1024475D03*
Y1044554D03*
Y1037861D03*
X230741Y1047900D03*
Y1041207D03*
Y1034515D03*
X235599Y1051247D03*
Y1057940D03*
X230741Y1054593D03*
Y1061286D03*
X234749Y1078018D03*
X235599Y1071326D03*
Y1064633D03*
X230741Y1067979D03*
X231591Y1074672D03*
X235599Y1094751D03*
X234749Y1088058D03*
X230741Y1091404D03*
Y1084711D03*
X235599Y1108137D03*
Y1101444D03*
X230741Y1111483D03*
Y1098097D03*
Y1104790D03*
X234749Y1124869D03*
X235599Y1114829D03*
X230741Y1128215D03*
Y1121522D03*
X235599Y1144948D03*
Y1138255D03*
X234749Y1131562D03*
X230741Y1141601D03*
X231591Y1134908D03*
X235599Y1151641D03*
Y1161680D03*
X230741Y1158333D03*
X231591Y1148294D03*
X235599Y1175066D03*
Y1168373D03*
X230741Y1165026D03*
Y1171719D03*
X235599Y1188452D03*
Y1181759D03*
X230741Y1185105D03*
Y1178412D03*
X235599Y1205184D03*
Y1198491D03*
X230741Y1208530D03*
Y1201837D03*
Y1195144D03*
X234749Y1225263D03*
X235599Y1218570D03*
Y1211877D03*
X230741Y1221916D03*
Y1215223D03*
X235599Y1241995D03*
X235186Y1234977D03*
X231591Y1231955D03*
Y1238648D03*
X235599Y1248688D03*
X230741Y1245341D03*
X235599Y1258727D03*
X230741Y1248688D03*
X227746Y1273364D03*
X240966Y1273143D03*
X238971Y1274353D03*
X235480Y1265406D03*
X235599Y1262074D03*
X229255Y1575686D03*
Y1580678D03*
X236359D03*
Y1575686D03*
X241315Y1580678D03*
Y1575686D03*
X237137Y1578182D03*
X240537D03*
X228477D03*
X229255Y1587598D03*
Y1592590D03*
X236359D03*
Y1587598D03*
X241315Y1592590D03*
Y1587598D03*
X229599Y1599884D03*
X234555D03*
X237137Y1590094D03*
X240537D03*
X228477D03*
X229599Y1604876D03*
Y1611796D03*
X234555Y1604876D03*
Y1611796D03*
X229599Y1616788D03*
X234555D03*
X233268Y1679920D03*
Y1675383D03*
X241142Y1679320D03*
X233268Y1698627D03*
Y1694093D03*
Y1689556D03*
Y1684454D03*
X241142Y1683857D03*
Y1688391D03*
Y1693493D03*
Y1698030D03*
X233268Y1712800D03*
Y1708266D03*
Y1703729D03*
X241142Y1702564D03*
Y1707666D03*
Y1712203D03*
X233268Y1717903D03*
Y1722440D03*
Y1726974D03*
X241142Y1716737D03*
Y1730911D03*
Y1726377D03*
Y1721840D03*
X251741Y766798D03*
X244299Y770144D03*
X251741Y780184D03*
Y773491D03*
X244299Y783530D03*
Y776837D03*
X251741Y803609D03*
Y796916D03*
Y790223D03*
X244299Y800263D03*
Y793570D03*
X250891Y816995D03*
X251741Y810302D03*
X245149Y820341D03*
Y813648D03*
X244299Y806955D03*
X251741Y833727D03*
X250891Y827034D03*
X244299Y830381D03*
X251741Y847113D03*
Y840420D03*
X244299Y850459D03*
Y837074D03*
Y843766D03*
X250891Y863845D03*
Y853806D03*
X245149Y867192D03*
Y857152D03*
X251741Y870538D03*
Y883924D03*
Y877231D03*
X244299Y873885D03*
Y880577D03*
X250891Y900656D03*
X251741Y890617D03*
X244299Y893963D03*
Y887270D03*
X251741Y914042D03*
Y907349D03*
X244299Y917389D03*
Y910696D03*
Y904003D03*
X250891Y927428D03*
X251741Y920735D03*
X245149Y930774D03*
X244299Y924081D03*
X251741Y944160D03*
X250891Y937467D03*
X244299Y947507D03*
X245149Y940814D03*
X251741Y960892D03*
Y950853D03*
X244299Y964239D03*
Y954200D03*
X251741Y957546D03*
Y954200D03*
Y980971D03*
Y974278D03*
Y967585D03*
X244299Y977625D03*
Y970932D03*
X251741Y987664D03*
X244299Y991011D03*
Y984318D03*
X251741Y994357D03*
X244299Y1031168D03*
X251741Y1027822D03*
Y1017782D03*
X244299D03*
Y1024475D03*
X251741Y1047900D03*
Y1041207D03*
Y1034515D03*
X244299Y1044554D03*
Y1037861D03*
X251741Y1061286D03*
Y1054593D03*
X244299Y1051247D03*
Y1057940D03*
Y1061286D03*
X250891Y1074672D03*
Y1067979D03*
X245149Y1078018D03*
X244299Y1071326D03*
Y1064633D03*
X251741Y1091404D03*
Y1084711D03*
X244299Y1094751D03*
X245149Y1088058D03*
X251741Y1104790D03*
X250891Y1111483D03*
X251741Y1098097D03*
X244299Y1108137D03*
Y1101444D03*
X251741Y1128215D03*
X250891Y1121522D03*
X245149Y1124869D03*
X244299Y1114829D03*
X251741Y1134908D03*
Y1141601D03*
X244299Y1144948D03*
Y1138255D03*
X245149Y1131562D03*
X251741Y1158333D03*
Y1148294D03*
X244299Y1151641D03*
Y1161680D03*
X251741Y1171719D03*
Y1165026D03*
X244299Y1175066D03*
Y1168373D03*
X251741Y1185105D03*
Y1178412D03*
X244299Y1188452D03*
Y1181759D03*
X251741Y1208530D03*
Y1201837D03*
X250891Y1195144D03*
X244299Y1205184D03*
Y1198491D03*
X250891Y1221916D03*
X251741Y1215223D03*
X245149Y1225263D03*
X244299Y1218570D03*
Y1211877D03*
X250891Y1231955D03*
X244299Y1241995D03*
X245149Y1235302D03*
X251741Y1238648D03*
X244299Y1248688D03*
X251741Y1245341D03*
X248047Y1259155D03*
X250467Y1259175D03*
X251707Y1252034D03*
X244789Y1260093D03*
X254897Y1274040D03*
X257197Y1273640D03*
X249603Y1266204D03*
X251699Y1265254D03*
X248419Y1575686D03*
X253375D03*
X248419Y1580678D03*
X253375D03*
X249197Y1578182D03*
X252597D03*
X248419Y1587598D03*
X253375D03*
X248419Y1592590D03*
X253375D03*
X246615Y1599884D03*
X241659D03*
X253719D03*
X249197Y1590094D03*
X252597D03*
X241659Y1616788D03*
X246615D03*
Y1604876D03*
X241659D03*
X246615Y1611796D03*
X241659D03*
X253719Y1604876D03*
Y1611796D03*
Y1616788D03*
X249016Y1675383D03*
Y1679920D03*
X256890Y1679320D03*
X249016Y1684454D03*
Y1689556D03*
Y1694093D03*
Y1698627D03*
X256890Y1683857D03*
Y1688391D03*
Y1693493D03*
Y1698030D03*
X249016Y1703729D03*
Y1708266D03*
Y1712800D03*
X256890Y1702564D03*
Y1707666D03*
Y1712203D03*
X249016Y1726974D03*
Y1722440D03*
Y1717903D03*
X256890Y1716737D03*
Y1730911D03*
Y1726377D03*
Y1721840D03*
X260441Y766798D03*
Y780184D03*
Y773491D03*
Y803609D03*
Y796916D03*
Y790223D03*
X261291Y816995D03*
X260441Y810302D03*
Y833727D03*
X261291Y827034D03*
X260441Y847113D03*
Y840420D03*
X261291Y863845D03*
Y853806D03*
X260441Y870538D03*
Y883924D03*
Y877231D03*
Y900656D03*
Y890617D03*
Y914042D03*
Y907349D03*
X261291Y927428D03*
X260441Y920735D03*
Y944160D03*
X261291Y937467D03*
X260441Y960892D03*
Y950853D03*
Y980971D03*
Y974278D03*
Y967585D03*
Y987664D03*
Y1027822D03*
Y1017782D03*
Y1047900D03*
Y1041207D03*
Y1034515D03*
Y1061286D03*
Y1054593D03*
Y1057940D03*
X261291Y1074672D03*
Y1067979D03*
X260441Y1091404D03*
Y1084711D03*
Y1104790D03*
X261291Y1111483D03*
X260441Y1098097D03*
Y1128215D03*
X261291Y1121522D03*
X260441Y1134908D03*
Y1141601D03*
Y1158333D03*
Y1148294D03*
Y1171719D03*
Y1165026D03*
Y1185105D03*
Y1178412D03*
Y1208530D03*
Y1201837D03*
Y1195144D03*
X261291Y1221916D03*
X260441Y1215223D03*
X261291Y1231955D03*
X260441Y1238648D03*
Y1245341D03*
Y1248688D03*
X260479Y1580678D03*
X265435D03*
X260479Y1575592D03*
X265435D03*
X272539Y1575686D03*
Y1580678D03*
X273317Y1578182D03*
X261257D03*
X264657D03*
X260479Y1592590D03*
X265435D03*
X260479Y1587598D03*
X265435D03*
X272539D03*
Y1592590D03*
X258675Y1599884D03*
X270735Y1599790D03*
X265779D03*
X273317Y1590094D03*
X261257D03*
X264657D03*
X258675Y1604876D03*
Y1611796D03*
Y1616788D03*
X270735D03*
X265779D03*
X270735Y1611796D03*
Y1604876D03*
X265779D03*
Y1611796D03*
X264764Y1675383D03*
Y1679920D03*
X272638Y1679320D03*
X264764Y1684454D03*
Y1689556D03*
Y1694093D03*
Y1698627D03*
X272638Y1683857D03*
Y1688391D03*
Y1693493D03*
Y1698030D03*
X264764Y1703729D03*
Y1708266D03*
Y1712800D03*
X272638Y1702564D03*
Y1707666D03*
Y1712203D03*
X264764Y1726974D03*
Y1722440D03*
Y1717903D03*
X272638Y1716737D03*
Y1730911D03*
Y1726377D03*
Y1721840D03*
X277495Y1575686D03*
Y1580678D03*
X284599D03*
X289555D03*
Y1575686D03*
X284599D03*
X285377Y1578182D03*
X288777D03*
X276717D03*
X277495Y1587598D03*
Y1592590D03*
X284599D03*
X289555D03*
X284599Y1587598D03*
X289555D03*
X282795Y1599884D03*
X277839D03*
X289899D03*
X285377Y1590094D03*
X288777D03*
X276717D03*
X282795Y1604876D03*
Y1611796D03*
X277839D03*
Y1604876D03*
X282795Y1616788D03*
X277839D03*
X289899D03*
Y1604876D03*
Y1611796D03*
X280512Y1675383D03*
Y1679920D03*
Y1684454D03*
Y1689556D03*
Y1694093D03*
Y1698627D03*
Y1703729D03*
Y1708266D03*
Y1712800D03*
Y1726974D03*
Y1722440D03*
Y1717903D03*
X296659Y1575686D03*
X301615D03*
X296659Y1580678D03*
X301615D03*
X297437Y1578182D03*
X300837D03*
X296659Y1587598D03*
X301615D03*
X296659Y1592590D03*
X301615D03*
X294855Y1599884D03*
X301959D03*
X297437Y1590094D03*
X300837D03*
X294855Y1616788D03*
Y1604876D03*
Y1611796D03*
X301959Y1604876D03*
Y1611796D03*
Y1616788D03*
X300197Y1679920D03*
Y1675383D03*
Y1698627D03*
Y1694093D03*
Y1689556D03*
Y1684454D03*
Y1712800D03*
Y1708266D03*
Y1703729D03*
Y1717903D03*
Y1722440D03*
Y1726974D03*
X308719Y1580678D03*
X313675D03*
X308719Y1575686D03*
X313675D03*
X320779D03*
Y1580678D03*
X321557Y1578182D03*
X309497D03*
X312897D03*
X308719Y1592590D03*
X313675D03*
X308719Y1587598D03*
X313675D03*
X320779D03*
Y1592590D03*
X306915Y1599884D03*
X318975D03*
X314019D03*
X321557Y1590094D03*
X309497D03*
X312897D03*
X306915Y1604876D03*
Y1611796D03*
Y1616788D03*
X318975D03*
X314019D03*
X318975Y1604876D03*
Y1611796D03*
X314019Y1604876D03*
Y1611796D03*
X308071Y1679320D03*
X315945Y1679920D03*
Y1675383D03*
X308071Y1683857D03*
Y1698030D03*
Y1693493D03*
Y1688391D03*
X315945Y1698627D03*
Y1694093D03*
Y1689556D03*
Y1684454D03*
X308071Y1702564D03*
Y1712203D03*
Y1707666D03*
X315945Y1712800D03*
Y1708266D03*
Y1703729D03*
X308071Y1716737D03*
Y1721840D03*
Y1726377D03*
Y1730911D03*
X315945Y1717903D03*
Y1722440D03*
Y1726974D03*
X325735Y1575686D03*
Y1580678D03*
X332839D03*
X337795D03*
X332839Y1575686D03*
X337795D03*
X333617Y1578182D03*
X337017D03*
X324957D03*
X325735Y1587598D03*
Y1592590D03*
X332839D03*
X337795D03*
X332839Y1587598D03*
X337795D03*
X326079Y1599884D03*
X331035D03*
X338139D03*
X333617Y1590094D03*
X337017D03*
X324957D03*
X326079Y1604876D03*
Y1611796D03*
X331035Y1604876D03*
Y1611796D03*
X326079Y1616788D03*
X331035D03*
X338139D03*
Y1604876D03*
Y1611796D03*
X323819Y1679320D03*
X331693Y1679920D03*
Y1675383D03*
X323819Y1683857D03*
Y1698030D03*
Y1693493D03*
Y1688391D03*
X331693Y1698627D03*
Y1694093D03*
Y1689556D03*
Y1684454D03*
X323819Y1702564D03*
Y1712203D03*
Y1707666D03*
X331693Y1712800D03*
Y1708266D03*
Y1703729D03*
X323819Y1716737D03*
Y1721840D03*
Y1726377D03*
Y1730911D03*
X331693Y1717903D03*
Y1722440D03*
Y1726974D03*
X344899Y1575686D03*
X349855D03*
X344899Y1580678D03*
X349855D03*
X345677Y1578182D03*
X349077D03*
X344899Y1587598D03*
X349855D03*
X344899Y1592590D03*
X349855D03*
X343095Y1599884D03*
X355155D03*
X350199D03*
X345677Y1590094D03*
X349077D03*
X343095Y1616788D03*
Y1604876D03*
Y1611796D03*
X355155Y1604876D03*
Y1611796D03*
X350199Y1604876D03*
Y1611796D03*
X355155Y1616788D03*
X350199D03*
X339567Y1679320D03*
X347441Y1679920D03*
Y1675383D03*
X355315Y1679320D03*
X339567Y1683857D03*
Y1698030D03*
Y1693493D03*
Y1688391D03*
X347441Y1698627D03*
Y1694093D03*
Y1689556D03*
Y1684454D03*
X355315Y1683857D03*
Y1698030D03*
Y1693493D03*
Y1688391D03*
X339567Y1702564D03*
Y1712203D03*
Y1707666D03*
X347441Y1712800D03*
Y1708266D03*
Y1703729D03*
X355315Y1702564D03*
Y1712203D03*
Y1707666D03*
X339567Y1716737D03*
Y1721840D03*
Y1726377D03*
Y1730911D03*
X347441Y1717903D03*
Y1722440D03*
Y1726974D03*
X355315Y1716737D03*
Y1721840D03*
Y1726377D03*
Y1730911D03*
X356959Y1580678D03*
X361915D03*
X356959Y1575592D03*
X361915D03*
X369019Y1575686D03*
Y1580678D03*
X369797Y1578182D03*
X357737D03*
X361137D03*
X356959Y1592590D03*
X361915D03*
X356959Y1587598D03*
X361915D03*
X367215Y1599790D03*
X362259D03*
X369019Y1587598D03*
Y1592590D03*
X369797Y1590094D03*
X357737D03*
X361137D03*
X367215Y1616788D03*
X362259D03*
X367215Y1604876D03*
Y1611796D03*
X362259Y1604876D03*
Y1611796D03*
X380930Y1531402D03*
X384210Y1534152D03*
X373975Y1575686D03*
Y1580678D03*
X373197Y1578182D03*
X373975Y1587598D03*
Y1592590D03*
X379275Y1599884D03*
X374319D03*
X373197Y1590094D03*
X379275Y1604876D03*
Y1611796D03*
X374319Y1604876D03*
Y1611796D03*
X379275Y1616788D03*
X374319D03*
X484333Y1575686D03*
Y1580678D03*
X477229D03*
X472273D03*
Y1575686D03*
X477229D03*
X476451Y1578182D03*
X485111D03*
X473051D03*
X482529Y1599884D03*
X477573D03*
X484333Y1587598D03*
Y1592590D03*
X472273D03*
X477229D03*
Y1587598D03*
X472273D03*
X476451Y1590094D03*
X485111D03*
X473051D03*
X482529Y1616788D03*
X477573D03*
Y1611796D03*
X482529D03*
X477573Y1604876D03*
X482529D03*
X501349Y1580678D03*
X496393D03*
Y1575686D03*
X501349D03*
X489289D03*
Y1580678D03*
X500571Y1578182D03*
X488511D03*
X497171D03*
X501693Y1599884D03*
X494589D03*
X489633D03*
X501349Y1592590D03*
X496393D03*
X501349Y1587598D03*
X496393D03*
X489289D03*
Y1592590D03*
X500571Y1590094D03*
X488511D03*
X497171D03*
X501693Y1611796D03*
Y1604876D03*
Y1616788D03*
X489633Y1611796D03*
X494589Y1604876D03*
X489633D03*
X494589Y1611796D03*
X489633Y1616788D03*
X494589D03*
X497441Y1675383D03*
Y1679920D03*
Y1684454D03*
Y1689556D03*
Y1694093D03*
Y1698627D03*
Y1703729D03*
Y1708266D03*
Y1712800D03*
Y1726974D03*
Y1722440D03*
Y1717903D03*
X508453Y1575686D03*
X513409D03*
X508453Y1580678D03*
X513409D03*
X512631Y1578182D03*
X509231D03*
X513753Y1599884D03*
X506649D03*
X508453Y1587598D03*
X513409D03*
X508453Y1592590D03*
X513409D03*
X512631Y1590094D03*
X509231D03*
X513753Y1616788D03*
Y1604876D03*
Y1611796D03*
X506649D03*
Y1604876D03*
Y1616788D03*
X513189Y1675383D03*
Y1679920D03*
X505315Y1679320D03*
X513189Y1684454D03*
Y1689556D03*
Y1694093D03*
Y1698627D03*
X505315Y1688391D03*
Y1693493D03*
Y1698030D03*
Y1683857D03*
X513189Y1703729D03*
Y1708266D03*
Y1712800D03*
X505315Y1707666D03*
Y1712203D03*
Y1702564D03*
X513189Y1726974D03*
Y1722440D03*
Y1717903D03*
X505315Y1730911D03*
Y1726377D03*
Y1721840D03*
Y1716737D03*
X532573Y1575686D03*
Y1580678D03*
X520513D03*
X525469D03*
X520513Y1575686D03*
X525469D03*
X524691Y1578182D03*
X533351D03*
X521291D03*
X525813Y1599884D03*
X530769D03*
X518709D03*
X532573Y1587598D03*
Y1592590D03*
X525469D03*
X520513D03*
Y1587598D03*
X525469D03*
X524691Y1590094D03*
X533351D03*
X521291D03*
X525813Y1611796D03*
X530769D03*
X525813Y1604876D03*
X530769D03*
Y1616788D03*
X525813D03*
X518709D03*
Y1604876D03*
Y1611796D03*
X528937Y1675383D03*
Y1679920D03*
X521063Y1679320D03*
X528937Y1684454D03*
Y1689556D03*
Y1694093D03*
Y1698627D03*
X521063Y1688391D03*
Y1693493D03*
Y1698030D03*
Y1683857D03*
X528937Y1703729D03*
Y1708266D03*
Y1712800D03*
X521063Y1707666D03*
Y1712203D03*
Y1702564D03*
X528937Y1726974D03*
Y1722440D03*
Y1717903D03*
X521063Y1730911D03*
Y1726377D03*
Y1721840D03*
Y1716737D03*
X549589Y1580678D03*
X544633D03*
X549589Y1575592D03*
X544633D03*
X537529Y1575686D03*
Y1580678D03*
X536751Y1578182D03*
X548811D03*
X545411D03*
X549933Y1599790D03*
X537873Y1599884D03*
X542829D03*
X549589Y1592590D03*
X544633D03*
X549589Y1587598D03*
X544633D03*
X537529D03*
Y1592590D03*
X536751Y1590094D03*
X548811D03*
X545411D03*
X549933Y1611796D03*
Y1604876D03*
Y1616788D03*
X542829D03*
X537873D03*
Y1604876D03*
X542829D03*
X537873Y1611796D03*
X542829D03*
X544685Y1675383D03*
Y1679920D03*
X536811Y1679320D03*
X544685Y1684454D03*
Y1689556D03*
Y1694093D03*
Y1698627D03*
X536811Y1688391D03*
Y1693493D03*
Y1698030D03*
Y1683857D03*
X544685Y1703729D03*
Y1708266D03*
Y1712800D03*
X536811Y1707666D03*
Y1712203D03*
Y1702564D03*
X544685Y1726974D03*
Y1722440D03*
Y1717903D03*
X536811Y1730911D03*
Y1726377D03*
Y1721840D03*
Y1716737D03*
X556693Y1575686D03*
X561649D03*
X556693Y1580678D03*
X561649D03*
X560871Y1578182D03*
X557471D03*
X561993Y1599884D03*
X554889Y1599790D03*
X556693Y1587598D03*
X561649D03*
Y1592590D03*
X556693D03*
X560871Y1590094D03*
X557471D03*
X561993Y1616788D03*
Y1604876D03*
Y1611796D03*
X554889D03*
Y1604876D03*
Y1616788D03*
X552559Y1679320D03*
X564370Y1675383D03*
Y1679920D03*
X552559Y1688391D03*
Y1693493D03*
Y1698030D03*
Y1683857D03*
X564370Y1684454D03*
Y1689556D03*
Y1694093D03*
Y1698627D03*
X552559Y1707666D03*
Y1712203D03*
Y1702564D03*
X564370Y1703729D03*
Y1708266D03*
Y1712800D03*
X552559Y1730911D03*
Y1726377D03*
Y1721840D03*
Y1716737D03*
X564370Y1726974D03*
Y1722440D03*
Y1717903D03*
X580813Y1575686D03*
Y1580678D03*
X573709D03*
X568753D03*
Y1575686D03*
X573709D03*
X572931Y1578182D03*
X581591D03*
X569531D03*
X579009Y1599884D03*
X574053D03*
X566949D03*
X580813Y1587598D03*
Y1592590D03*
X573709D03*
X568753D03*
X573709Y1587598D03*
X568753D03*
X572931Y1590094D03*
X581591D03*
X569531D03*
X574053Y1616788D03*
X579009D03*
Y1611796D03*
X574053D03*
X579009Y1604876D03*
X574053D03*
X566949Y1616788D03*
Y1604876D03*
Y1611796D03*
X580118Y1675383D03*
Y1679920D03*
X572244Y1679320D03*
X580118Y1684454D03*
Y1689556D03*
Y1694093D03*
Y1698627D03*
X572244Y1688391D03*
Y1693493D03*
Y1698030D03*
Y1683857D03*
X580118Y1703729D03*
Y1708266D03*
Y1712800D03*
X572244Y1707666D03*
Y1712203D03*
Y1702564D03*
X580118Y1726974D03*
Y1722440D03*
Y1717903D03*
X572244Y1730911D03*
Y1726377D03*
Y1721840D03*
Y1716737D03*
X597829Y1580678D03*
X592873D03*
X597829Y1575686D03*
X592873D03*
X585769D03*
Y1580678D03*
X597051Y1578182D03*
X584991D03*
X593651D03*
X598173Y1599884D03*
X586113D03*
X591069D03*
X597829Y1592590D03*
X592873D03*
X597829Y1587598D03*
X592873D03*
X585769D03*
Y1592590D03*
X597051Y1590094D03*
X584991D03*
X593651D03*
X598173Y1616788D03*
Y1611796D03*
Y1604876D03*
X586113D03*
X591069D03*
X586113Y1611796D03*
X591069D03*
Y1616788D03*
X586113D03*
X595866Y1675383D03*
Y1679920D03*
X587992Y1679320D03*
X595866Y1684454D03*
Y1689556D03*
Y1694093D03*
Y1698627D03*
X587992Y1688391D03*
Y1693493D03*
Y1698030D03*
Y1683857D03*
X595866Y1703729D03*
Y1708266D03*
Y1712800D03*
X587992Y1707666D03*
Y1712203D03*
Y1702564D03*
X595866Y1726974D03*
Y1722440D03*
Y1717903D03*
X587992Y1730911D03*
Y1726377D03*
Y1721840D03*
Y1716737D03*
X609889Y1575686D03*
X604933D03*
X609889Y1580678D03*
X604933D03*
X609111Y1578182D03*
X605711D03*
X615189Y1599884D03*
X610233D03*
X603129D03*
X609889Y1587598D03*
X604933D03*
X609889Y1592590D03*
X604933D03*
X609111Y1590094D03*
X605711D03*
X615189Y1604876D03*
X610233D03*
X615189Y1611796D03*
X610233D03*
X615189Y1616788D03*
X610233D03*
X603129D03*
Y1611796D03*
Y1604876D03*
X611614Y1675383D03*
Y1679920D03*
X603740Y1679320D03*
X611614Y1684454D03*
Y1689556D03*
Y1694093D03*
Y1698627D03*
X603740Y1688391D03*
Y1693493D03*
Y1698030D03*
Y1683857D03*
X611614Y1703729D03*
Y1708266D03*
Y1712800D03*
X603740Y1707666D03*
Y1712203D03*
Y1702564D03*
X611614Y1726974D03*
Y1722440D03*
Y1717903D03*
X603740Y1730911D03*
Y1726377D03*
Y1721840D03*
Y1716737D03*
X629658Y766478D03*
X620005Y850459D03*
X630754D03*
X620899Y867192D03*
X629599D03*
X620058Y857152D03*
X630481D03*
X620899Y880577D03*
X629599D03*
X620899Y873885D03*
X629599D03*
X630756Y893963D03*
X620899D03*
X629599Y887270D03*
X620899D03*
Y910696D03*
X629599D03*
Y917389D03*
X620899D03*
X629599Y904003D03*
X620899D03*
X630399Y930697D03*
X619905Y930774D03*
X620899Y924081D03*
X629599D03*
Y947507D03*
X620899D03*
X619964Y940814D03*
X630777D03*
X629599Y964239D03*
X620899D03*
X629599Y954200D03*
X620899D03*
Y977625D03*
X629599D03*
Y970932D03*
X620899D03*
Y991011D03*
X629599D03*
Y984318D03*
X620899D03*
Y1031168D03*
X629599D03*
X620899Y1017782D03*
X629599D03*
X620899Y1024475D03*
X629599D03*
X620899Y1044554D03*
X629599D03*
X620899Y1037861D03*
X629599D03*
X620899Y1057940D03*
X629599D03*
Y1051247D03*
X620899D03*
Y1061286D03*
Y1078018D03*
X629599D03*
X630399Y1071326D03*
X619999D03*
X620899Y1064633D03*
X629599D03*
X620899Y1088058D03*
X629599D03*
Y1094751D03*
X620899D03*
Y1108137D03*
X629599D03*
Y1101444D03*
X620899D03*
X630363Y1124674D03*
X620369Y1124969D03*
X630399Y1114829D03*
X620099D03*
X620899Y1131562D03*
X629599D03*
Y1144948D03*
X620899D03*
X629599Y1138255D03*
X620899D03*
X620511Y1161680D03*
X629833Y1161581D03*
X629599Y1151641D03*
X620899D03*
X629599Y1175066D03*
X620899D03*
X629599Y1168373D03*
X620899D03*
X630623Y1188452D03*
X620899D03*
X629599Y1181759D03*
X620899D03*
X629599Y1205184D03*
X620899D03*
Y1198491D03*
X629599D03*
X620899Y1225263D03*
X629599D03*
Y1218570D03*
X620899D03*
X629599Y1211877D03*
X620899D03*
X629599Y1241995D03*
X620899D03*
X630922Y1235302D03*
X620036D03*
X620899Y1248688D03*
X629599D03*
X629931Y1258727D03*
X632080Y1262074D03*
X629699Y1255381D03*
X625246Y1273164D03*
X627646D03*
X631270Y1264942D03*
X629053Y1575686D03*
Y1580678D03*
X621949D03*
X616993D03*
X621949Y1575686D03*
X616993D03*
X621171Y1578182D03*
X629831D03*
X617771D03*
X622293Y1599884D03*
X627249D03*
X629053Y1587598D03*
Y1592590D03*
X621949D03*
X616993D03*
X621949Y1587598D03*
X616993D03*
X621171Y1590094D03*
X629831D03*
X617771D03*
X627249Y1616788D03*
X622293D03*
Y1611796D03*
X627249D03*
X622293Y1604876D03*
X627249D03*
X619488Y1679320D03*
Y1688391D03*
Y1693493D03*
Y1698030D03*
Y1683857D03*
Y1707666D03*
Y1712203D03*
Y1702564D03*
Y1730911D03*
Y1726377D03*
Y1721840D03*
Y1716737D03*
X637041Y847113D03*
X645801D03*
X646819Y853806D03*
X636332Y853955D03*
X645918Y863845D03*
X636266D03*
X637041Y877231D03*
X645741D03*
X637041Y870538D03*
X645741D03*
Y883924D03*
X637041D03*
Y900656D03*
X645741D03*
X637041Y890617D03*
X645741D03*
X637041Y914042D03*
X645741D03*
Y907349D03*
X637041D03*
X646393Y927526D03*
X636026Y927428D03*
X645741Y920735D03*
X637041D03*
X645741Y944160D03*
X637041D03*
X636170Y937467D03*
X646703D03*
X645741Y960892D03*
X637041D03*
Y950853D03*
X645741D03*
X636941Y957546D03*
Y954200D03*
X637041Y980971D03*
X645741D03*
X637041Y974278D03*
X645741D03*
X637041Y967585D03*
X645741D03*
X637041Y987664D03*
X645741D03*
X644257Y1000325D03*
X637041Y1027822D03*
X645741D03*
Y1017782D03*
X637041D03*
X645741Y1047900D03*
X637041D03*
Y1041207D03*
X645741D03*
X637041Y1034515D03*
X645741D03*
X637041Y1061286D03*
X645741D03*
Y1054593D03*
X637041D03*
X636141Y1074672D03*
X646541D03*
X645741Y1067979D03*
X636841D03*
X637041Y1091404D03*
X645741D03*
Y1084711D03*
X636241D03*
X645741Y1111483D03*
X637041D03*
X645741Y1098097D03*
X637041D03*
X645741Y1104790D03*
X637041D03*
Y1121522D03*
X645741D03*
X637041Y1128915D03*
X645741Y1128215D03*
X646584Y1135108D03*
X635744Y1134908D03*
X645741Y1141601D03*
X637041D03*
X645741Y1148294D03*
X637041D03*
X645741Y1158333D03*
X637041D03*
Y1171719D03*
X645741D03*
Y1165026D03*
X637041D03*
Y1185105D03*
X645741D03*
Y1178412D03*
X637041D03*
X645741Y1208530D03*
X637041D03*
X645741Y1201837D03*
X637041D03*
Y1195144D03*
X645741D03*
X636005Y1221916D03*
X646570D03*
X645741Y1215223D03*
X637041D03*
X645741Y1238648D03*
X637041D03*
X635995Y1231862D03*
X646539Y1231955D03*
X645741Y1245341D03*
X637041D03*
X634213Y1258679D03*
X636946Y1258414D03*
X647690Y1260812D03*
X637041Y1252034D03*
X645897Y1248785D03*
X647877Y1254076D03*
X642746Y1273364D03*
X639946D03*
X636877Y1261235D03*
X646069Y1580678D03*
X641113D03*
X646069Y1575592D03*
X641113D03*
X634009Y1575686D03*
Y1580678D03*
X645291Y1578182D03*
X633231D03*
X641891D03*
X646413Y1599790D03*
X639309Y1599884D03*
X634353D03*
X646069Y1592590D03*
X641113D03*
X646069Y1587598D03*
X641113D03*
X634009D03*
Y1592590D03*
X645291Y1590094D03*
X633231D03*
X641891D03*
X646413Y1616788D03*
Y1611796D03*
Y1604876D03*
X639309D03*
X634353D03*
X639309Y1611796D03*
X634353D03*
Y1616788D03*
X639309D03*
X667677Y441636D03*
X659299Y850459D03*
X650599D03*
X659299Y857152D03*
X650599D03*
X649563Y867192D03*
X660299D03*
X659299Y873885D03*
X650599D03*
Y880577D03*
X659299D03*
X650599Y893963D03*
X659299D03*
X650599Y887270D03*
X659299D03*
Y917389D03*
X650599D03*
X659299Y910696D03*
X650599D03*
Y904003D03*
X659299D03*
X660504Y924081D03*
X650599D03*
X660174Y930774D03*
X649661D03*
X659299Y947507D03*
X650599D03*
X659299Y940814D03*
X650599D03*
X659299Y964239D03*
X650599D03*
Y954200D03*
X659299D03*
Y977625D03*
X650599D03*
X659299Y970932D03*
X650599D03*
X659299Y991011D03*
X650599D03*
X659299Y984318D03*
X650599D03*
X659299Y1031168D03*
X650599D03*
X659299Y1017782D03*
X650599D03*
X659299Y1024475D03*
X650599D03*
X659299Y1044554D03*
X650599D03*
X659299Y1037861D03*
X650599D03*
X659299Y1051247D03*
X650599D03*
Y1057940D03*
X659299D03*
X660099Y1078018D03*
X649799D03*
X659299Y1071326D03*
X650599D03*
X659299Y1064633D03*
X650599D03*
X659299Y1094751D03*
X650599D03*
X660099Y1088058D03*
X649799D03*
X650599Y1108137D03*
X659299D03*
X650599Y1101444D03*
X659299D03*
X660199Y1124869D03*
X649932Y1124640D03*
X659299Y1114829D03*
X650599D03*
X659299Y1130762D03*
X650599D03*
X659299Y1138255D03*
X650599D03*
X659299Y1144948D03*
X650599D03*
X659299Y1151641D03*
X650599D03*
Y1161680D03*
X659299D03*
X650599Y1175066D03*
X659299D03*
X650599Y1168373D03*
X659299D03*
X650599Y1188452D03*
X659299D03*
X650599Y1181759D03*
X659299D03*
X650599Y1205184D03*
X659299D03*
X650599Y1198491D03*
X659299D03*
X660070Y1225263D03*
X649913D03*
X659299Y1218570D03*
X650599D03*
X659299Y1211877D03*
X650599D03*
X659299Y1241995D03*
X650599D03*
X660234Y1235302D03*
X649701D03*
X650599Y1248688D03*
X659299D03*
X659546Y1257664D03*
X650599Y1258727D03*
X666741Y1255381D03*
X664630Y1259442D03*
X656446Y1273364D03*
X653646D03*
X649587Y1266766D03*
X661400Y1263522D03*
X654606Y1431203D03*
X653173Y1575686D03*
X658129D03*
X653173Y1580678D03*
X658129D03*
X657351Y1578182D03*
X653951D03*
X663429Y1599884D03*
X658473D03*
X651369Y1599790D03*
X653173Y1587598D03*
X658129D03*
X653173Y1592590D03*
X658129D03*
X657351Y1590094D03*
X653951D03*
X663429Y1604876D03*
X658473D03*
X663429Y1611796D03*
X658473D03*
Y1616788D03*
X663429D03*
X651369D03*
Y1611796D03*
Y1604876D03*
X668329Y411714D03*
X674628Y424313D03*
X671479Y421163D03*
X667660Y429037D03*
X674628Y427462D03*
Y414864D03*
X677778D03*
Y424313D03*
X671479Y414864D03*
X674628Y421163D03*
Y418013D03*
X677778D03*
Y421163D03*
X668329D03*
X677778Y427462D03*
Y430612D03*
X674628Y436911D03*
Y443210D03*
X671479Y430612D03*
Y436911D03*
X677778Y433761D03*
X668329Y436911D03*
X677778Y440061D03*
X674628D03*
X677778Y436911D03*
Y443210D03*
X680928Y440061D03*
X674628Y430612D03*
X671479Y443211D03*
Y462108D03*
X677778Y449510D03*
X668329Y452659D03*
X674628D03*
X671479D03*
X677778D03*
X668329Y455809D03*
X671479Y458959D03*
X674628D03*
X668329D03*
X677778D03*
Y455809D03*
X674628D03*
X668067Y462090D03*
X677778Y462108D03*
X671479Y455809D03*
X680928Y458959D03*
X674628Y449510D03*
Y462108D03*
X677778Y477856D03*
Y471557D03*
Y474707D03*
X671479Y465258D03*
X674628D03*
X668329D03*
X677778D03*
Y468407D03*
X671479Y481006D03*
X667350Y470680D03*
X671479Y474707D03*
X674628Y484006D03*
X668329Y481006D03*
X680299Y766798D03*
X675441Y847113D03*
X666741D03*
X680299Y850459D03*
X676417Y853806D03*
X665890D03*
X680299Y867192D03*
Y857152D03*
X665916Y863845D03*
X676600D03*
X675441Y877231D03*
X666741D03*
X675441Y870538D03*
X666741D03*
Y883924D03*
X675441D03*
X680299Y880577D03*
Y873885D03*
X666741Y900656D03*
X675441D03*
X680299Y893963D03*
Y887270D03*
X666741Y890617D03*
X675441D03*
Y914042D03*
X666741D03*
X680299Y917389D03*
Y910696D03*
Y904003D03*
X666741Y907349D03*
X675441D03*
X676488Y927428D03*
X665896D03*
X675441Y920735D03*
X666741D03*
X680299Y930774D03*
Y924081D03*
X675441Y944160D03*
X666741D03*
X676359Y937467D03*
X665923D03*
X680299Y947507D03*
Y940814D03*
Y964239D03*
X675441Y960892D03*
X666741D03*
X680299Y954200D03*
X666741Y950853D03*
X675441D03*
X666641Y957546D03*
Y954200D03*
X675441Y980971D03*
X666741D03*
X680299Y970932D03*
X675441Y974278D03*
X666741D03*
X675441Y967585D03*
X666741D03*
X680299Y977625D03*
X675441Y987664D03*
X666741D03*
X680299Y991011D03*
Y984318D03*
X672063Y998632D03*
X680299Y1031168D03*
Y1024475D03*
X675441Y1027822D03*
X666741D03*
X675441Y1017782D03*
X666741D03*
X680299D03*
X675441Y1047900D03*
X666741D03*
X680299Y1037861D03*
X675441Y1041207D03*
X666741D03*
X675441Y1034515D03*
X666741D03*
X680299Y1044554D03*
Y1057940D03*
Y1051247D03*
X675441Y1054593D03*
X666741D03*
Y1061286D03*
X675441D03*
X680299D03*
X676341Y1074672D03*
X665841D03*
X675441Y1067979D03*
X666741D03*
X680299Y1078018D03*
Y1071326D03*
Y1064633D03*
X675441Y1091404D03*
X666741D03*
X676241Y1084711D03*
X665941D03*
X680299Y1094751D03*
Y1088058D03*
X666741Y1111483D03*
X675441D03*
X680299Y1108137D03*
Y1101444D03*
X666741Y1104790D03*
X675441D03*
X666741Y1098097D03*
X675441D03*
X666741Y1128215D03*
X675441D03*
X680299Y1124869D03*
Y1114829D03*
X666741Y1121522D03*
X675441D03*
X680299Y1144948D03*
Y1138255D03*
Y1131562D03*
X666741Y1141601D03*
X675441D03*
X666741Y1134908D03*
X675441D03*
X676652Y1148294D03*
X665602D03*
X676241Y1158333D03*
X665941D03*
X680299Y1161680D03*
Y1151641D03*
X675441Y1165026D03*
X666741D03*
X680299Y1175066D03*
Y1168373D03*
X666741Y1171719D03*
X675441D03*
X680299Y1188452D03*
Y1181759D03*
X666741Y1185105D03*
X675441D03*
X666741Y1178412D03*
X675441D03*
X680299Y1205184D03*
Y1198491D03*
X666741Y1208530D03*
X675441D03*
X666741Y1201837D03*
X675441D03*
X666741Y1195144D03*
X675441D03*
X680299Y1218570D03*
Y1225263D03*
X676448Y1221916D03*
X665651D03*
X675441Y1215223D03*
X666741D03*
X680299Y1211877D03*
X675441Y1238648D03*
X666741D03*
X676462Y1231955D03*
X665912D03*
X680299Y1241995D03*
Y1235302D03*
X675441Y1245341D03*
X666741D03*
X676046Y1257964D03*
X680299Y1248688D03*
Y1258727D03*
X666741Y1252034D03*
X675537Y1248885D03*
X677980Y1262074D03*
X672446Y1273364D03*
X669646D03*
X666741Y1262074D03*
X666646Y1264464D03*
X680046Y1264964D03*
X684077Y414864D03*
X680928Y424313D03*
X687227Y414864D03*
X690376Y421163D03*
Y418013D03*
Y414864D03*
X693526Y427462D03*
X687227Y424313D03*
X690376Y427462D03*
X680928Y414864D03*
Y418013D03*
X684077Y421163D03*
X680928Y427462D03*
X684077Y418013D03*
Y427462D03*
X680928Y421163D03*
X684077Y424313D03*
X687227Y427462D03*
X696676D03*
X693526Y421163D03*
Y424313D03*
X690376D03*
X696676Y421163D03*
Y424313D03*
Y418013D03*
Y436911D03*
X693526Y443210D03*
Y440061D03*
Y436911D03*
X690376Y440061D03*
Y433761D03*
X680928Y436911D03*
Y433761D03*
X693526Y430612D03*
X696676Y440061D03*
Y443210D03*
X684077Y430612D03*
Y440061D03*
X687227Y436911D03*
Y443210D03*
X684077D03*
Y436911D03*
X680928Y443210D03*
X690376Y436911D03*
Y443210D03*
X687227Y440061D03*
X693526Y433761D03*
X696676D03*
X684077D03*
X687227Y430612D03*
X690376D03*
X696676D03*
X687227Y433761D03*
X680928Y430612D03*
X687227Y462108D03*
X693526Y452659D03*
Y449510D03*
X696676Y455809D03*
X693526D03*
X690376Y452659D03*
Y458959D03*
X680928Y455809D03*
X693526Y462108D03*
X680928Y449510D03*
X687227D03*
X690376Y462108D03*
X684077Y449510D03*
X680928Y452659D03*
X684077D03*
X687227Y455809D03*
X684077D03*
X680928Y462108D03*
X696676Y449510D03*
Y452659D03*
X690376Y449510D03*
Y455809D03*
X687227Y452659D03*
X693526Y458959D03*
X696676D03*
Y462108D03*
X687227Y458959D03*
X684077D03*
Y468407D03*
X687227Y471557D03*
Y474707D03*
Y477856D03*
X684077Y471557D03*
X690376Y465258D03*
X684077D03*
X680928Y471557D03*
Y474707D03*
Y477856D03*
X696676D03*
X684077D03*
X680928Y468407D03*
X693526Y465258D03*
Y471557D03*
X690376Y468407D03*
Y477856D03*
Y471557D03*
X687227Y465258D03*
X690376Y474707D03*
X687227Y468407D03*
X693526D03*
X684077Y474707D03*
X696676Y465258D03*
Y474707D03*
Y468407D03*
X693526Y474707D03*
X696676Y471557D03*
X693526Y477856D03*
X696441Y847113D03*
X688999Y850459D03*
X696441Y863845D03*
Y853806D03*
X688999Y867192D03*
X689896Y857152D03*
X696441Y883924D03*
Y877231D03*
Y870538D03*
X688999Y880577D03*
Y873885D03*
X696441Y900656D03*
Y890617D03*
X688999Y893963D03*
Y887270D03*
X696441Y914042D03*
Y907349D03*
X688999Y917389D03*
Y910696D03*
Y904003D03*
X696441Y927428D03*
Y920735D03*
X690104Y930774D03*
X688999Y924081D03*
X696441Y944160D03*
Y937467D03*
X688999Y947507D03*
Y940814D03*
X696441Y960892D03*
Y950853D03*
X688999Y964239D03*
Y954200D03*
X696441Y957546D03*
Y954200D03*
Y980971D03*
Y974278D03*
Y967585D03*
X688999Y970932D03*
Y977625D03*
X696441Y987664D03*
X688999Y991011D03*
Y984318D03*
X696441Y994357D03*
Y1027822D03*
Y1017782D03*
X688999Y1031168D03*
Y1024475D03*
Y1017782D03*
X696441Y1047900D03*
Y1041207D03*
Y1034515D03*
X688999Y1037861D03*
Y1044554D03*
X696441Y1054593D03*
Y1061286D03*
X688999Y1057940D03*
Y1051247D03*
X696441Y1074672D03*
Y1067979D03*
X688999Y1077118D03*
Y1071326D03*
Y1064633D03*
X696441Y1091404D03*
Y1084711D03*
X688999Y1094751D03*
Y1088058D03*
X696441Y1111483D03*
Y1104790D03*
Y1098097D03*
X688999Y1108137D03*
Y1101444D03*
X696441Y1128215D03*
Y1121522D03*
X688999Y1124869D03*
Y1114829D03*
X696441Y1141601D03*
Y1134908D03*
X688999Y1144948D03*
Y1138255D03*
Y1131562D03*
X696441Y1158333D03*
Y1148294D03*
X688999Y1161680D03*
X689999Y1151641D03*
X696441Y1171719D03*
Y1165026D03*
X688999Y1175066D03*
Y1168373D03*
X696441Y1185105D03*
Y1178412D03*
X688999Y1188452D03*
Y1181759D03*
X696441Y1208530D03*
Y1201837D03*
Y1195144D03*
X688999Y1205184D03*
Y1198491D03*
X696441Y1221916D03*
Y1215223D03*
X688999Y1218570D03*
X689799Y1225263D03*
X688999Y1211877D03*
X696441Y1238648D03*
Y1231955D03*
X688999Y1241995D03*
Y1235302D03*
X688916Y1256964D03*
X696441Y1245341D03*
X688999Y1248688D03*
X696441Y1255381D03*
X694100Y1261562D03*
X696441Y1248688D03*
X692233Y1252480D03*
X686146Y1273364D03*
X683346D03*
X696046Y1263764D03*
X706125Y421163D03*
X702975Y414864D03*
X706125Y418013D03*
X712424Y424313D03*
X699825Y427462D03*
X699826Y414864D03*
X699825Y424313D03*
X709274Y436911D03*
X706125Y440061D03*
Y436911D03*
X699825Y440061D03*
Y436911D03*
X712424Y443210D03*
Y440061D03*
Y436911D03*
Y430612D03*
X709274Y440061D03*
Y443210D03*
X706125D03*
X699825D03*
X709274Y433761D03*
X712424D03*
X699825D03*
X706125D03*
X699825Y430612D03*
X706125Y462108D03*
X709274D03*
X712424D03*
Y455809D03*
X709274D03*
X706125D03*
Y452659D03*
X699825Y455809D03*
Y452659D03*
X712424D03*
Y449510D03*
X709274D03*
X699825D03*
X706125D03*
X709274Y452659D03*
X699825Y458959D03*
X706125D03*
X709274D03*
X712424D03*
X699825Y462108D03*
X709274Y474707D03*
Y471557D03*
Y465258D03*
Y468407D03*
X712424Y474707D03*
Y468407D03*
Y465258D03*
X709274Y477856D03*
X699825Y468407D03*
X706125Y471557D03*
Y468407D03*
X699825Y471557D03*
Y474707D03*
X706125Y477856D03*
X699825Y465258D03*
X712424Y471557D03*
X706125Y481006D03*
X709899Y766798D03*
X705141Y847113D03*
X709999Y850459D03*
X705141Y863845D03*
Y853806D03*
X709999Y867192D03*
Y857152D03*
X705141Y883924D03*
Y877231D03*
Y870538D03*
X709999Y880577D03*
Y873885D03*
X705141Y900656D03*
Y890617D03*
X709999Y893963D03*
Y887270D03*
X705141Y914042D03*
Y907349D03*
X709999Y917389D03*
Y910696D03*
Y904003D03*
X705141Y927428D03*
Y920735D03*
X709999Y930774D03*
Y924081D03*
X705141Y944160D03*
Y937467D03*
X709999Y947507D03*
Y940814D03*
X705141Y960892D03*
Y950853D03*
X709999Y964239D03*
Y954200D03*
X705141Y980971D03*
Y974278D03*
Y967585D03*
X709999Y977625D03*
Y970932D03*
X705141Y987664D03*
X709999Y991011D03*
Y984318D03*
X705141Y1027822D03*
Y1017782D03*
X709999Y1031168D03*
Y1024475D03*
Y1017782D03*
X705141Y1047900D03*
Y1041207D03*
Y1034515D03*
X709999Y1044554D03*
Y1037861D03*
X705141Y1054593D03*
Y1061286D03*
X709999Y1057940D03*
Y1051247D03*
X705141Y1074672D03*
Y1067979D03*
X709999Y1078018D03*
Y1071326D03*
Y1064633D03*
X705141Y1091404D03*
Y1084711D03*
X709999Y1094751D03*
Y1088058D03*
X705141Y1111483D03*
Y1104790D03*
Y1098097D03*
X709999Y1108137D03*
Y1101444D03*
X705141Y1128215D03*
Y1121522D03*
X709999Y1124869D03*
Y1114829D03*
X705141Y1141601D03*
Y1134908D03*
X709999Y1144948D03*
Y1138255D03*
Y1131562D03*
X705141Y1158333D03*
Y1148294D03*
X709999Y1161680D03*
Y1151641D03*
X705141Y1171719D03*
Y1165026D03*
X709999Y1175066D03*
Y1168373D03*
X705141Y1185105D03*
Y1178412D03*
X709999Y1188452D03*
Y1181759D03*
X705141Y1208530D03*
Y1201837D03*
Y1195144D03*
X709999Y1205184D03*
Y1198491D03*
X705141Y1221916D03*
Y1215223D03*
X709999Y1225263D03*
Y1218570D03*
Y1211877D03*
X705141Y1238648D03*
Y1231955D03*
X709999Y1241995D03*
Y1235302D03*
X705141Y1245341D03*
X709999Y1248688D03*
Y1258727D03*
X708090Y1262074D03*
X705037Y1252034D03*
X706493Y1256563D03*
X713046Y1273364D03*
X702146D03*
X699346D03*
X705167Y1262074D03*
X709977Y1264985D03*
X721873Y427462D03*
X725022D03*
X728172Y418013D03*
X725022Y414864D03*
X718723Y418013D03*
X715574Y427462D03*
X728172Y421163D03*
X718723Y414864D03*
X725022Y424313D03*
X721873D03*
X725022Y421163D03*
X728172Y427462D03*
X731322Y421163D03*
X725022Y418013D03*
X718723Y427462D03*
Y424313D03*
Y421163D03*
X715574Y424313D03*
Y421163D03*
Y418013D03*
X728172Y424313D03*
X718723Y436911D03*
X721873Y433761D03*
Y436911D03*
Y440061D03*
Y430612D03*
X718723Y433761D03*
Y440061D03*
X725022Y436911D03*
Y433761D03*
X728172D03*
X715574D03*
X718723Y430612D03*
X715574D03*
X725022D03*
X728172Y436911D03*
X715574D03*
Y440061D03*
Y443210D03*
X728172D03*
Y430612D03*
X725022Y440061D03*
X718723Y443210D03*
X721873D03*
X725022D03*
X728172Y440061D03*
X731322D03*
X728172Y455809D03*
Y458959D03*
X718723Y455809D03*
X721873Y458959D03*
X715574D03*
X728172Y449510D03*
X721873Y452659D03*
X725022D03*
X728172D03*
X715574Y462108D03*
X725022Y458959D03*
X721873Y455809D03*
X725022Y462108D03*
X718723Y452659D03*
X715574Y449510D03*
Y452659D03*
Y455809D03*
X728172Y462108D03*
X718723Y449510D03*
X721873D03*
X725022D03*
X718723Y458959D03*
X721873Y462108D03*
X718723D03*
X725022Y468407D03*
X721873Y465258D03*
Y477856D03*
X725022D03*
X718723Y468407D03*
X715574Y474707D03*
Y471557D03*
Y468407D03*
Y465258D03*
X718723Y474707D03*
Y471557D03*
X728172Y477856D03*
X721873Y471557D03*
X725022D03*
X718723Y465258D03*
X728172D03*
X725022Y474707D03*
X728172Y468407D03*
X721873Y474707D03*
Y468407D03*
X728172Y474707D03*
Y471557D03*
X725022Y465258D03*
X718723Y477856D03*
X725132Y481116D03*
X728272Y481006D03*
X726041Y957546D03*
Y954200D03*
Y994357D03*
X726141Y1057940D03*
Y1255381D03*
X723700Y1258727D03*
X726141Y1248688D03*
X729046Y1273364D03*
X715846D03*
X737621Y411714D03*
X734471Y418013D03*
X731322Y427462D03*
Y418013D03*
X734471Y421163D03*
X731322Y424313D03*
X734471D03*
X737621D03*
X731322Y414864D03*
Y433761D03*
Y430612D03*
X734471Y436911D03*
X731322D03*
X734471Y443210D03*
X737621D03*
X731322D03*
Y455809D03*
X737621Y458959D03*
X731322D03*
Y462108D03*
X734471Y452659D03*
X731322D03*
Y449510D03*
X734471Y458959D03*
X731322Y465258D03*
Y477856D03*
X737621Y471557D03*
X734471Y468407D03*
X731322D03*
X731321Y474707D03*
X731322Y471557D03*
X737621Y481006D03*
X734471D03*
X739699Y766798D03*
Y1061286D03*
Y1258727D03*
X734967Y1252034D03*
X737580Y1262074D03*
X745546Y1273364D03*
X742746D03*
X731372Y1273464D03*
X755841Y957546D03*
Y954200D03*
Y994357D03*
X755541Y1057940D03*
X750890Y1248500D03*
X755890Y1255381D03*
X753000Y1261352D03*
X755841Y1252034D03*
Y1248688D03*
X750040Y1254179D03*
X758746Y1273364D03*
X761546D03*
X769399Y766798D03*
Y1258727D03*
X767080Y1262074D03*
X766148Y1255882D03*
X772446Y1273364D03*
X775246D03*
X785541Y957546D03*
Y954200D03*
Y994357D03*
Y1255381D03*
X783130Y1259372D03*
X794157Y1252034D03*
X785541Y1248688D03*
X796880Y1262074D03*
X796280Y1254402D03*
X788446Y1273364D03*
X791246D03*
X797417Y767345D03*
X799099Y780184D03*
Y773491D03*
Y786877D03*
Y803609D03*
Y796916D03*
Y790223D03*
Y847113D03*
Y853806D03*
Y860499D03*
Y863845D03*
Y883924D03*
Y877231D03*
Y870538D03*
Y890617D03*
Y897310D03*
Y900656D03*
Y914042D03*
Y907349D03*
Y927428D03*
Y920735D03*
Y934121D03*
Y944160D03*
Y937467D03*
Y950853D03*
Y980971D03*
Y974278D03*
Y994357D03*
Y987664D03*
Y1027822D03*
Y1021129D03*
Y1047900D03*
Y1041207D03*
Y1034515D03*
Y1061286D03*
Y1054593D03*
Y1074672D03*
Y1067979D03*
Y1091404D03*
Y1081365D03*
Y1084711D03*
Y1098097D03*
Y1111483D03*
Y1104790D03*
Y1128215D03*
Y1118176D03*
Y1121522D03*
Y1141601D03*
Y1134908D03*
Y1148294D03*
Y1154987D03*
Y1158333D03*
Y1171719D03*
Y1165026D03*
Y1185105D03*
Y1178412D03*
Y1191798D03*
Y1208530D03*
Y1201837D03*
Y1195144D03*
Y1258727D03*
X812440D03*
X804946Y1273364D03*
X802146D03*
X815241Y770144D03*
Y776837D03*
Y786877D03*
Y783530D03*
Y800263D03*
Y793570D03*
Y850459D03*
Y843766D03*
Y867192D03*
Y860499D03*
Y857152D03*
Y873885D03*
Y880577D03*
Y887270D03*
Y897310D03*
Y893963D03*
Y917389D03*
Y910696D03*
Y904003D03*
Y924081D03*
Y934121D03*
Y930774D03*
Y947507D03*
Y940814D03*
Y957546D03*
Y954200D03*
Y977625D03*
Y970932D03*
Y991011D03*
Y984318D03*
Y994357D03*
Y1021129D03*
Y1024475D03*
Y1031168D03*
Y1044554D03*
Y1037861D03*
X814941Y1051247D03*
X815241Y1071325D03*
Y1064633D03*
Y1078018D03*
Y1094751D03*
Y1088058D03*
Y1081365D03*
Y1108136D03*
Y1101444D03*
Y1124869D03*
Y1118176D03*
Y1114829D03*
Y1144947D03*
Y1138255D03*
Y1131562D03*
Y1161680D03*
Y1154987D03*
Y1151640D03*
Y1175066D03*
Y1168373D03*
Y1181758D03*
Y1191798D03*
Y1188451D03*
Y1205184D03*
Y1198491D03*
Y1255381D03*
X826750Y1262074D03*
X823877Y1252034D03*
X815241Y1248688D03*
X826501Y1254553D03*
X820946Y1273364D03*
X818146D03*
X828699Y766798D03*
X828799Y1054593D03*
Y1258727D03*
X842630Y1256912D03*
X839246Y1273064D03*
X842046D03*
X831846Y1273364D03*
X834646D03*
X844841Y957546D03*
Y954200D03*
Y994357D03*
X844941Y1021129D03*
Y1024475D03*
Y1051247D03*
Y1258727D03*
Y1252034D03*
X844997Y1248155D03*
X1001970Y1251522D03*
X1003831Y1259077D03*
X1002070Y1256942D03*
X1003841Y1262074D03*
X1012769Y766798D03*
X1019983Y994357D03*
X1012541Y1054593D03*
X1012543Y1257198D03*
X1017900Y1247632D03*
X1019983Y1255381D03*
Y1252034D03*
Y1248688D03*
X1017111Y1273299D03*
X1014111D03*
X1033441Y766798D03*
X1028683Y957546D03*
Y954200D03*
Y1021129D03*
Y1024475D03*
Y1051247D03*
X1033541Y1258727D03*
X1030830Y1261302D03*
X1030270Y1256042D03*
X1036588Y1273344D03*
X1022888D03*
X1025688D03*
X1042241Y780184D03*
Y773491D03*
Y786877D03*
Y803609D03*
Y796916D03*
Y790223D03*
Y847113D03*
Y853806D03*
Y860499D03*
Y863845D03*
Y883924D03*
Y877231D03*
Y870538D03*
Y890617D03*
Y897310D03*
Y900656D03*
Y914042D03*
Y907349D03*
Y927428D03*
Y920735D03*
Y934121D03*
Y944160D03*
Y937467D03*
Y950853D03*
Y980971D03*
Y974278D03*
Y994357D03*
Y987664D03*
Y1027822D03*
Y1021129D03*
Y1047900D03*
Y1041207D03*
Y1034515D03*
Y1061286D03*
Y1054593D03*
Y1074672D03*
Y1067979D03*
Y1091404D03*
Y1081365D03*
Y1084711D03*
Y1098097D03*
Y1111483D03*
Y1104790D03*
Y1128215D03*
Y1118176D03*
Y1121522D03*
Y1141601D03*
Y1134908D03*
Y1148294D03*
Y1154987D03*
Y1158333D03*
Y1171719D03*
Y1165026D03*
Y1185105D03*
Y1178412D03*
Y1191798D03*
Y1208530D03*
Y1201837D03*
Y1195144D03*
X1042331Y1257488D03*
X1047010Y1259222D03*
X1049683Y1258727D03*
X1052588Y1273344D03*
X1039388D03*
X1044930Y1263492D03*
X1058383Y770144D03*
X1063141Y766798D03*
X1058383Y776837D03*
Y786877D03*
Y783530D03*
Y800263D03*
Y793570D03*
Y850459D03*
Y843766D03*
Y867192D03*
Y860499D03*
Y857152D03*
Y873885D03*
Y880577D03*
Y887270D03*
Y897310D03*
Y893963D03*
Y917389D03*
Y910696D03*
Y904003D03*
Y924081D03*
Y934121D03*
Y930774D03*
Y947507D03*
Y940814D03*
Y957546D03*
Y954200D03*
Y977625D03*
Y970932D03*
Y991011D03*
Y984318D03*
Y994357D03*
Y1021129D03*
Y1024475D03*
Y1031168D03*
Y1044554D03*
Y1037861D03*
Y1051247D03*
Y1071326D03*
Y1064633D03*
Y1078018D03*
Y1094751D03*
Y1088058D03*
Y1081365D03*
Y1108137D03*
Y1101444D03*
Y1124869D03*
Y1118176D03*
Y1114829D03*
Y1144948D03*
Y1138255D03*
Y1131562D03*
Y1161680D03*
Y1154987D03*
Y1151641D03*
Y1175066D03*
Y1168373D03*
Y1181759D03*
Y1191798D03*
Y1188452D03*
Y1205184D03*
Y1198491D03*
X1063241Y1258727D03*
X1061330Y1262074D03*
X1058383Y1248688D03*
X1059410Y1252272D03*
X1069088Y1273344D03*
X1066288D03*
X1055388D03*
X1079383Y994357D03*
X1071991Y1257262D03*
X1076520Y1259072D03*
X1079383Y1258727D03*
X1088262Y1252293D03*
X1085088Y1273344D03*
X1082288D03*
X1092709Y766775D03*
X1088083Y957546D03*
Y954200D03*
X1101641Y1061286D03*
X1101554Y1257102D03*
X1090273Y1246800D03*
X1092941Y1258727D03*
X1088083Y1248688D03*
X1091000Y1262074D03*
X1106200Y1250162D03*
X1098788Y1273344D03*
X1095988D03*
X1103530Y1263602D03*
X1117783Y957546D03*
Y954200D03*
Y994357D03*
Y1057940D03*
X1120800Y1262074D03*
X1117783Y1248688D03*
X1111988Y1273344D03*
X1114788D03*
X1106740Y1267902D03*
X1122541Y766798D03*
X1131341Y867192D03*
X1122641D03*
X1131341Y880577D03*
X1122641D03*
X1131341Y873885D03*
X1122641D03*
X1131341Y893963D03*
X1122641D03*
X1131341Y887270D03*
X1122641D03*
X1131341Y917389D03*
X1122641D03*
X1131341Y910696D03*
X1122641D03*
X1131341Y904003D03*
X1122641D03*
X1131341Y930774D03*
X1122641D03*
X1131341Y924081D03*
X1122641D03*
Y947507D03*
X1131341D03*
Y940814D03*
X1122641D03*
X1131341Y964239D03*
X1122641D03*
X1131341Y954200D03*
X1122641D03*
X1131341Y977625D03*
X1122641D03*
X1131341Y970932D03*
X1122641D03*
X1131341Y991011D03*
X1122641D03*
X1131341Y984318D03*
X1122641D03*
X1131341Y1031168D03*
X1122641D03*
X1131341Y1024475D03*
X1122641D03*
X1131341Y1017782D03*
X1122641D03*
X1131341Y1044554D03*
X1122641D03*
X1131341Y1037861D03*
X1122641D03*
X1131341Y1057940D03*
X1122641D03*
X1131341Y1051247D03*
X1122641D03*
X1131341Y1078018D03*
X1122641D03*
X1131341Y1071326D03*
X1122641D03*
X1131341Y1064633D03*
X1122641D03*
X1131341Y1094751D03*
X1122641D03*
X1131341Y1088058D03*
X1122641D03*
X1131341Y1108137D03*
X1122641D03*
X1131341Y1101444D03*
X1122641D03*
X1131341Y1124869D03*
X1122641D03*
X1131341Y1114829D03*
X1122641D03*
X1131341Y1144948D03*
X1122641D03*
X1131341Y1138255D03*
X1122641D03*
X1131341Y1131562D03*
X1122641D03*
X1131341Y1161680D03*
X1122641D03*
X1131341Y1151641D03*
X1122641D03*
X1131341Y1175066D03*
X1122641D03*
X1131341Y1168373D03*
X1122641D03*
X1131341Y1188452D03*
X1122641D03*
X1131341Y1181759D03*
X1122641D03*
X1131341Y1205184D03*
X1122641D03*
X1131341Y1198491D03*
X1122641D03*
X1131341Y1225263D03*
X1122641D03*
X1131341Y1218570D03*
X1122641D03*
X1131341Y1211877D03*
X1122641D03*
X1131341Y1241995D03*
X1122641D03*
X1131341Y1235302D03*
X1122641D03*
X1131434Y1257291D03*
X1122641Y1248688D03*
X1131341D03*
X1122641Y1258727D03*
X1133200Y1255702D03*
X1126188Y1273344D03*
X1128988D03*
X1122620Y1264622D03*
X1152241Y766798D03*
X1152341Y867192D03*
X1147483Y863845D03*
X1138783D03*
X1152341Y880577D03*
Y873885D03*
X1147483Y883924D03*
X1138783D03*
X1147483Y877231D03*
X1138783D03*
X1147483Y870538D03*
X1138783D03*
X1152341Y893963D03*
Y887270D03*
X1138783Y900656D03*
X1147483D03*
X1138783Y890617D03*
X1147483D03*
X1152341Y917389D03*
Y910696D03*
Y904003D03*
X1147483Y914042D03*
X1138783D03*
X1147483Y907349D03*
X1138783D03*
X1152341Y930774D03*
Y924081D03*
X1147483Y927428D03*
X1138783D03*
X1147483Y920735D03*
X1138783D03*
X1152341Y947507D03*
Y940814D03*
X1147483Y944160D03*
X1138783D03*
X1147483Y937467D03*
X1138783D03*
X1152341Y964239D03*
Y954200D03*
X1147483Y960892D03*
X1138783D03*
X1147483Y950853D03*
X1138783D03*
X1147483Y957546D03*
Y954200D03*
X1152341Y977625D03*
Y970932D03*
X1147483Y980971D03*
X1138783D03*
X1147483Y974278D03*
X1138783D03*
X1147483Y967585D03*
X1138783D03*
X1152341Y991011D03*
Y984318D03*
X1147483Y987664D03*
X1138783D03*
Y994357D03*
X1152341Y1031168D03*
Y1024475D03*
Y1017782D03*
X1147483Y1027822D03*
X1138783D03*
X1147483Y1017782D03*
X1138783D03*
X1152341Y1044554D03*
Y1037861D03*
X1138783Y1047900D03*
X1147483D03*
Y1041207D03*
X1138783D03*
X1147483Y1034515D03*
X1138783D03*
X1152341Y1057940D03*
Y1051247D03*
X1147483Y1061286D03*
X1138783D03*
X1147483Y1054593D03*
X1138783D03*
X1152341Y1078018D03*
Y1071326D03*
Y1064633D03*
X1147483Y1074672D03*
X1138783D03*
X1147483Y1067979D03*
X1138783D03*
X1152341Y1094751D03*
Y1088058D03*
X1147483Y1091404D03*
X1138783D03*
X1147483Y1084711D03*
X1138783D03*
X1152341Y1108137D03*
Y1101444D03*
X1147483Y1111483D03*
X1138783D03*
X1147483Y1104790D03*
X1138783D03*
X1147483Y1098097D03*
X1138783D03*
X1152341Y1124869D03*
Y1114829D03*
X1147483Y1128215D03*
X1138783D03*
X1147483Y1121522D03*
X1138783D03*
X1152341Y1144948D03*
Y1138255D03*
Y1131562D03*
X1147483Y1141601D03*
X1138783D03*
X1147483Y1134908D03*
X1138783D03*
X1152341Y1161680D03*
Y1151641D03*
X1147483Y1158333D03*
X1138783D03*
Y1148294D03*
X1147483D03*
X1152341Y1175066D03*
Y1168373D03*
X1147483Y1171719D03*
X1138783D03*
X1147483Y1165026D03*
X1138783D03*
X1152341Y1188452D03*
Y1181759D03*
X1147483Y1185105D03*
X1138783D03*
X1147483Y1178412D03*
X1138783D03*
X1152341Y1205184D03*
Y1198491D03*
X1147483Y1208530D03*
X1138783D03*
X1147483Y1201837D03*
X1138783D03*
X1147483Y1195144D03*
X1138783D03*
X1152341Y1225263D03*
Y1218570D03*
Y1211877D03*
X1147483Y1221916D03*
X1138783D03*
X1147483Y1215223D03*
X1138783D03*
X1152341Y1241995D03*
Y1235302D03*
X1147483Y1238648D03*
X1138783D03*
X1147483Y1231955D03*
X1138783D03*
X1152341Y1248688D03*
X1147483Y1245341D03*
X1138783D03*
X1152341Y1258727D03*
X1138783Y1255381D03*
Y1258727D03*
Y1252034D03*
X1147483Y1248688D03*
X1150400Y1262074D03*
X1148563Y1257097D03*
X1152381Y1269684D03*
X1147681D03*
X1138201Y1270277D03*
X1152341Y1265420D03*
X1138783Y1262027D03*
X1137980Y1264212D03*
X1167633Y863845D03*
X1161041Y867192D03*
X1168483Y883924D03*
Y877231D03*
Y870538D03*
X1161041Y880577D03*
Y873885D03*
X1168483Y900656D03*
Y890617D03*
X1161041Y893963D03*
Y887270D03*
X1168483Y914042D03*
Y907349D03*
X1161041Y917389D03*
Y910696D03*
Y904003D03*
X1167633Y927428D03*
X1168483Y920735D03*
X1161041Y930774D03*
Y924081D03*
X1168483Y937467D03*
Y944160D03*
X1161041Y947507D03*
Y940814D03*
X1168483Y960892D03*
Y950853D03*
X1161041Y964239D03*
Y954200D03*
X1168483Y974278D03*
Y980971D03*
Y967585D03*
X1161041Y977625D03*
Y970932D03*
X1168483Y987664D03*
X1161041Y991011D03*
Y984318D03*
X1168483Y1027822D03*
Y1017782D03*
X1161041Y1031168D03*
Y1024475D03*
Y1017782D03*
X1168483Y1047900D03*
Y1041207D03*
Y1034515D03*
X1161041Y1044554D03*
Y1037861D03*
X1168483Y1054593D03*
Y1061286D03*
X1161041Y1057940D03*
Y1051247D03*
Y1061286D03*
X1168483Y1074672D03*
Y1067979D03*
X1161041Y1078018D03*
Y1071326D03*
Y1064633D03*
X1168483Y1091404D03*
X1167633Y1084711D03*
X1161041Y1094751D03*
Y1088058D03*
X1168483Y1111483D03*
Y1104790D03*
Y1098097D03*
X1161041Y1108137D03*
Y1101444D03*
X1168483Y1128215D03*
Y1121522D03*
X1161041Y1124869D03*
Y1114829D03*
X1168483Y1141601D03*
Y1134908D03*
X1161041Y1144948D03*
Y1138255D03*
Y1131562D03*
X1167633Y1158333D03*
X1168483Y1148294D03*
X1161041Y1161680D03*
Y1151641D03*
X1168483Y1171719D03*
Y1165026D03*
X1161041Y1175066D03*
Y1168373D03*
X1168483Y1185105D03*
Y1178412D03*
X1161041Y1188452D03*
Y1181759D03*
X1168483Y1208530D03*
Y1201837D03*
Y1195144D03*
X1161041Y1205184D03*
Y1198491D03*
X1168483Y1221916D03*
Y1215223D03*
X1161041Y1225263D03*
Y1218570D03*
Y1211877D03*
X1168483Y1238648D03*
X1167633Y1231955D03*
X1161041Y1241995D03*
Y1235302D03*
X1161065Y1258871D03*
X1168483Y1245341D03*
X1161041Y1248688D03*
X1168483Y1255381D03*
Y1258727D03*
Y1252034D03*
X1161781Y1269684D03*
X1168483Y1265420D03*
Y1262074D03*
X1181191Y867192D03*
X1177183Y863845D03*
X1182041Y873885D03*
Y880577D03*
X1177183Y883924D03*
Y877231D03*
Y870538D03*
X1182041Y893963D03*
Y887270D03*
X1177183Y900656D03*
Y890617D03*
X1182041Y917389D03*
Y910696D03*
Y904003D03*
X1177183Y914042D03*
Y907349D03*
X1181191Y930774D03*
Y924081D03*
X1177183Y927428D03*
Y920735D03*
X1182041Y940814D03*
Y947507D03*
X1177183Y937467D03*
Y944160D03*
X1182041Y964239D03*
Y954200D03*
X1177183Y960892D03*
Y950853D03*
Y957546D03*
Y954200D03*
X1182041Y970932D03*
Y977625D03*
X1177183Y974278D03*
Y980971D03*
Y967585D03*
X1182041Y991011D03*
Y984318D03*
X1177183Y987664D03*
Y994357D03*
X1182041Y1031168D03*
Y1017782D03*
Y1024475D03*
X1177183Y1027822D03*
Y1017782D03*
X1182041Y1044554D03*
Y1037861D03*
X1177183Y1047900D03*
Y1041207D03*
Y1034515D03*
X1182041Y1057940D03*
Y1051247D03*
X1177183Y1054593D03*
Y1061286D03*
X1181191Y1078018D03*
X1182041Y1071326D03*
Y1064633D03*
X1177183Y1074672D03*
Y1067979D03*
X1182041Y1094751D03*
X1181191Y1088058D03*
X1177183Y1091404D03*
Y1084711D03*
X1182041Y1101444D03*
Y1108137D03*
X1177183Y1111483D03*
Y1104790D03*
Y1098097D03*
X1182041Y1114829D03*
Y1124869D03*
X1177183Y1128215D03*
Y1121522D03*
X1182041Y1144948D03*
Y1138255D03*
Y1131562D03*
X1177183Y1141601D03*
Y1134908D03*
X1181191Y1161680D03*
Y1151641D03*
X1177183Y1158333D03*
Y1148294D03*
X1182041Y1168373D03*
Y1175066D03*
X1177183Y1171719D03*
Y1165026D03*
X1182041Y1188452D03*
Y1181759D03*
X1177183Y1185105D03*
Y1178412D03*
X1182041Y1205184D03*
Y1198491D03*
X1177183Y1208530D03*
Y1201837D03*
Y1195144D03*
X1181191Y1225263D03*
X1182041Y1211877D03*
Y1218570D03*
X1177183Y1221916D03*
Y1215223D03*
X1182041Y1241995D03*
X1181191Y1235302D03*
X1177183Y1238648D03*
Y1231955D03*
X1182041Y1248688D03*
X1177183Y1245341D03*
X1177120Y1248688D03*
X1177222Y1255567D03*
X1176867Y1270029D03*
X1182041Y1265420D03*
X1181850Y1260192D03*
X1179180Y1265872D03*
X1197333Y863845D03*
X1191591Y867192D03*
X1198183Y877231D03*
X1197333Y870538D03*
X1198183Y883924D03*
X1190741Y873885D03*
Y880577D03*
X1198183Y900656D03*
Y890617D03*
X1190741Y893963D03*
Y887270D03*
X1198183Y914042D03*
Y907349D03*
X1190741Y917389D03*
Y910696D03*
Y904003D03*
X1197383Y927428D03*
X1198183Y920735D03*
X1191591Y930774D03*
Y924081D03*
X1198183Y944160D03*
X1197333Y937467D03*
X1190741Y940814D03*
Y947507D03*
X1198183Y960892D03*
Y950853D03*
X1190741Y964239D03*
Y954200D03*
X1198183Y957546D03*
Y954200D03*
Y980971D03*
Y974278D03*
Y967585D03*
X1190741Y970932D03*
Y977625D03*
X1198183Y987664D03*
X1190741Y991011D03*
Y984318D03*
X1198183Y994357D03*
Y1027822D03*
Y1017782D03*
X1190741Y1031168D03*
Y1017782D03*
Y1024475D03*
X1198183Y1047900D03*
Y1041207D03*
Y1034515D03*
X1190741Y1044554D03*
Y1037861D03*
X1198183Y1054593D03*
Y1061286D03*
X1190741Y1057940D03*
Y1051247D03*
X1197333Y1074672D03*
X1198183Y1067979D03*
X1191591Y1078018D03*
X1190741Y1071326D03*
Y1064633D03*
X1198183Y1091404D03*
X1197333Y1084711D03*
X1190741Y1094751D03*
X1191591Y1088058D03*
X1198183Y1111483D03*
Y1098097D03*
Y1104790D03*
X1190741Y1101444D03*
Y1108137D03*
X1198183Y1128215D03*
Y1121522D03*
X1190741Y1114829D03*
Y1124869D03*
X1198183Y1141601D03*
X1197333Y1134908D03*
X1190741Y1144948D03*
Y1138255D03*
Y1131562D03*
X1198183Y1158333D03*
X1197333Y1148294D03*
X1191591Y1161680D03*
Y1151641D03*
X1198183Y1165026D03*
Y1171719D03*
X1190741Y1168373D03*
Y1175066D03*
X1198183Y1185105D03*
Y1178412D03*
X1190741Y1188452D03*
Y1181759D03*
X1198183Y1208530D03*
Y1201837D03*
Y1195144D03*
X1190741Y1205184D03*
Y1198491D03*
X1198183Y1221916D03*
Y1215223D03*
X1191591Y1225263D03*
X1190741Y1211877D03*
Y1218570D03*
X1197333Y1238648D03*
Y1231955D03*
X1190741Y1241995D03*
X1191591Y1235302D03*
X1198183Y1245341D03*
X1190966Y1258711D03*
X1190741Y1248688D03*
X1198183Y1252034D03*
X1191538Y1270004D03*
X1198180Y1262112D03*
X1196470Y1265382D03*
X1193590Y1267912D03*
X1195470Y1262802D03*
X1195994Y1580678D03*
Y1575686D03*
X1200950Y1580678D03*
Y1575686D03*
X1201294Y1599884D03*
X1195994Y1592590D03*
Y1587598D03*
X1200950Y1592590D03*
Y1587598D03*
X1201294Y1604876D03*
Y1611796D03*
Y1616788D03*
X1211641Y766798D03*
X1210891Y867492D03*
X1207733Y863845D03*
X1211741Y874185D03*
Y880577D03*
X1206883Y877231D03*
X1207201Y871084D03*
X1206883Y883924D03*
X1211741Y893963D03*
Y887270D03*
X1206883Y900656D03*
Y890617D03*
X1211741Y917389D03*
Y910696D03*
Y904003D03*
X1206883Y914042D03*
Y907349D03*
X1211741Y930774D03*
Y924081D03*
X1207683Y927428D03*
X1206883Y920735D03*
X1211741Y947507D03*
X1211001Y940814D03*
X1206883Y944660D03*
X1207733Y937467D03*
X1211741Y964239D03*
Y954200D03*
X1206883Y960892D03*
Y950853D03*
X1211741Y977625D03*
Y970932D03*
X1206883Y980971D03*
Y974278D03*
Y967585D03*
X1211741Y991011D03*
X1206883Y987664D03*
X1211741Y984318D03*
Y1031168D03*
X1206883Y1027822D03*
Y1017782D03*
X1211741D03*
Y1024475D03*
Y1044554D03*
Y1037861D03*
X1206883Y1047900D03*
Y1041207D03*
Y1034515D03*
X1211741Y1051247D03*
Y1057940D03*
X1206883Y1054593D03*
Y1061286D03*
X1210891Y1078018D03*
X1211741Y1064633D03*
Y1071326D03*
X1207733Y1074672D03*
X1206883Y1067979D03*
X1211741Y1094751D03*
X1210891Y1088058D03*
X1206883Y1091404D03*
Y1084711D03*
X1211741Y1108137D03*
Y1101444D03*
X1206883Y1111483D03*
Y1098097D03*
Y1104790D03*
X1210891Y1124869D03*
X1211741Y1114829D03*
X1206883Y1128215D03*
Y1121522D03*
X1211741Y1144948D03*
Y1138255D03*
X1210891Y1131562D03*
X1206883Y1141601D03*
X1207733Y1134908D03*
X1211741Y1151641D03*
Y1161680D03*
X1206883Y1158333D03*
X1207733Y1148294D03*
X1211741Y1175066D03*
Y1168373D03*
X1206883Y1165026D03*
Y1171719D03*
X1211741Y1188452D03*
Y1181759D03*
X1206883Y1185105D03*
Y1178412D03*
X1211741Y1205184D03*
Y1198491D03*
X1206883Y1208530D03*
Y1201837D03*
Y1195144D03*
X1210891Y1225263D03*
X1211741Y1218570D03*
Y1211877D03*
X1206883Y1221916D03*
Y1215223D03*
X1211741Y1241995D03*
X1211328Y1234977D03*
X1207733Y1238648D03*
Y1231955D03*
X1206883Y1245341D03*
X1211741Y1248688D03*
X1208830Y1256692D03*
X1206883Y1248688D03*
X1207048Y1255174D03*
X1204608Y1273119D03*
X1202043Y1273123D03*
X1211240Y1265502D03*
X1208750Y1266546D03*
X1213010Y1575686D03*
X1208054D03*
X1213010Y1580678D03*
X1208054D03*
X1206250Y1599884D03*
X1213354D03*
X1213010Y1587598D03*
X1208054D03*
X1213010Y1592590D03*
X1208054D03*
X1206250Y1604876D03*
Y1611796D03*
Y1616788D03*
X1213354D03*
Y1604876D03*
Y1611796D03*
X1214132Y1614292D03*
X1202072D03*
X1217532D03*
X1205472D03*
X1214132Y1602380D03*
X1202072D03*
X1217532D03*
X1205472D03*
X1227033Y863845D03*
X1221291Y867192D03*
X1227883Y870538D03*
Y883924D03*
Y877231D03*
X1220441Y873885D03*
Y880577D03*
X1227033Y900656D03*
X1227883Y890617D03*
X1220441Y893963D03*
Y887270D03*
X1227883Y914042D03*
Y907349D03*
X1220441Y917389D03*
Y910696D03*
Y904003D03*
X1227033Y927428D03*
X1227883Y920735D03*
X1221291Y930774D03*
X1220441Y924081D03*
X1227883Y944160D03*
X1227033Y937467D03*
X1220441Y947507D03*
X1221291Y940814D03*
X1227883Y960892D03*
Y950853D03*
X1220441Y964239D03*
Y954200D03*
X1227883Y957546D03*
Y954200D03*
Y974278D03*
Y967585D03*
X1220441Y977625D03*
Y970932D03*
X1227883Y980971D03*
Y987664D03*
X1220441Y991011D03*
Y984318D03*
X1227883Y994357D03*
Y1027822D03*
X1220441Y1031168D03*
X1227883Y1017782D03*
X1220441D03*
Y1024475D03*
X1227883Y1047900D03*
Y1041207D03*
Y1034515D03*
X1220441Y1044554D03*
Y1037861D03*
X1227883Y1061286D03*
Y1054593D03*
X1220441Y1051247D03*
Y1057940D03*
Y1061286D03*
X1227033Y1074672D03*
Y1067979D03*
X1221291Y1078018D03*
X1220441Y1064633D03*
Y1071326D03*
X1227883Y1091404D03*
Y1084711D03*
X1220441Y1094751D03*
X1221291Y1088058D03*
X1227883Y1104790D03*
X1227033Y1111483D03*
X1227883Y1098097D03*
X1220441Y1108137D03*
Y1101444D03*
X1227883Y1128215D03*
X1227033Y1121522D03*
X1221291Y1124869D03*
X1220441Y1114829D03*
X1227883Y1134908D03*
Y1141601D03*
X1220441Y1144948D03*
Y1138255D03*
X1221291Y1131562D03*
X1227883Y1158333D03*
Y1148294D03*
X1220441Y1151641D03*
Y1161680D03*
X1227883Y1171719D03*
Y1165026D03*
X1220441Y1175066D03*
Y1168373D03*
X1227883Y1185105D03*
Y1178412D03*
X1220441Y1188452D03*
Y1181759D03*
X1227883Y1208530D03*
Y1201837D03*
X1227033Y1195144D03*
X1220441Y1205184D03*
Y1198491D03*
X1227033Y1221916D03*
X1227883Y1215223D03*
X1221291Y1225263D03*
X1220441Y1218570D03*
Y1211877D03*
X1227883Y1238648D03*
X1227033Y1231955D03*
X1220441Y1241995D03*
X1221291Y1235302D03*
X1220441Y1248688D03*
X1227883Y1245341D03*
X1224189Y1259155D03*
X1226899Y1257968D03*
X1227847Y1251715D03*
X1220601Y1269684D03*
X1220931Y1260093D03*
X1233327Y1274515D03*
X1231377Y1275855D03*
X1227670Y1265162D03*
X1225540Y1266402D03*
X1225070Y1580678D03*
Y1575686D03*
X1220114D03*
Y1580678D03*
X1232174D03*
Y1575686D03*
X1218310Y1599884D03*
X1225414D03*
X1230370D03*
X1225070Y1592590D03*
X1220114D03*
X1225070Y1587598D03*
X1220114D03*
X1232174D03*
Y1592590D03*
X1218310Y1616788D03*
Y1604876D03*
Y1611796D03*
X1225414D03*
Y1604876D03*
X1230370Y1611796D03*
Y1604876D03*
X1225414Y1616788D03*
X1230370D03*
X1226192Y1614292D03*
X1229592D03*
X1226192Y1602380D03*
X1229592D03*
X1237433Y863845D03*
X1236583Y870538D03*
Y883924D03*
Y877231D03*
Y900656D03*
Y890617D03*
Y914042D03*
Y907349D03*
X1237433Y927428D03*
X1236583Y920735D03*
Y944160D03*
X1237433Y937467D03*
X1236583Y960892D03*
Y950853D03*
Y974278D03*
Y967585D03*
Y980971D03*
Y987664D03*
Y1027822D03*
Y1017782D03*
Y1047900D03*
Y1041207D03*
Y1034515D03*
Y1061286D03*
Y1054593D03*
Y1057940D03*
X1237433Y1074672D03*
Y1067979D03*
X1236583Y1091404D03*
Y1084711D03*
Y1104790D03*
X1237433Y1111483D03*
X1236583Y1098097D03*
Y1128215D03*
X1237433Y1121522D03*
X1236583Y1134908D03*
Y1141601D03*
Y1158333D03*
Y1148294D03*
Y1171719D03*
Y1165026D03*
Y1185105D03*
Y1178412D03*
Y1208530D03*
Y1201837D03*
Y1195144D03*
X1237433Y1221916D03*
X1236583Y1215223D03*
Y1238648D03*
X1237433Y1231955D03*
X1236583Y1245341D03*
Y1248688D03*
X1237130Y1575686D03*
Y1580678D03*
X1244234D03*
X1249190D03*
X1244234Y1575686D03*
X1249190D03*
X1242430Y1599884D03*
X1237474D03*
X1249534D03*
X1237130Y1587598D03*
Y1592590D03*
X1249190D03*
X1244234D03*
Y1587598D03*
X1249190D03*
X1242430Y1616788D03*
X1237474D03*
X1242430Y1611796D03*
Y1604876D03*
X1237474Y1611796D03*
Y1604876D03*
X1249534Y1611796D03*
Y1604876D03*
Y1616788D03*
X1238252Y1614292D03*
X1241652D03*
X1238252Y1602380D03*
X1241652D03*
X1241142Y1675383D03*
Y1679920D03*
X1249016Y1679320D03*
X1241142Y1684454D03*
Y1689556D03*
Y1694093D03*
Y1698627D03*
X1249016Y1688391D03*
Y1693493D03*
Y1698030D03*
Y1683857D03*
X1241142Y1703729D03*
Y1708266D03*
Y1712800D03*
X1249016Y1707666D03*
Y1712203D03*
Y1702564D03*
X1241142Y1726974D03*
Y1722440D03*
Y1717903D03*
X1249016Y1730911D03*
Y1726377D03*
Y1721840D03*
Y1716737D03*
X1261250Y1575686D03*
X1256294D03*
X1261250Y1580678D03*
X1256294D03*
X1254490Y1599884D03*
X1261594D03*
X1261250Y1587598D03*
X1256294D03*
X1261250Y1592590D03*
X1256294D03*
X1254490Y1611796D03*
Y1604876D03*
Y1616788D03*
X1261594D03*
Y1611796D03*
Y1604876D03*
X1262372Y1614292D03*
X1250312D03*
X1265772D03*
X1253712D03*
X1262372Y1602380D03*
X1250312D03*
X1265772D03*
X1253712D03*
X1256890Y1675383D03*
Y1679920D03*
X1264764Y1679320D03*
X1256890Y1684454D03*
Y1689556D03*
Y1694093D03*
Y1698627D03*
X1264764Y1688391D03*
Y1693493D03*
Y1698030D03*
Y1683857D03*
X1256890Y1703729D03*
Y1708266D03*
Y1712800D03*
X1264764Y1707666D03*
Y1712203D03*
Y1702564D03*
X1256890Y1726974D03*
Y1722440D03*
Y1717903D03*
X1264764Y1730911D03*
Y1726377D03*
Y1721840D03*
Y1716737D03*
X1273310Y1580678D03*
Y1575592D03*
X1268354D03*
Y1580678D03*
X1280414Y1575686D03*
Y1580678D03*
X1266550Y1599884D03*
X1273654Y1599790D03*
X1278610D03*
X1273310Y1592590D03*
X1268354D03*
X1273310Y1587598D03*
X1268354D03*
X1280414D03*
Y1592590D03*
X1266550Y1616788D03*
Y1611796D03*
Y1604876D03*
X1273654Y1611796D03*
Y1604876D03*
X1278610Y1611796D03*
Y1604876D03*
X1273654Y1616788D03*
X1278610D03*
X1274432Y1614292D03*
X1277832D03*
X1274432Y1602380D03*
X1277832D03*
X1272638Y1675383D03*
Y1679920D03*
X1280512Y1679320D03*
X1272638Y1684454D03*
Y1689556D03*
Y1694093D03*
Y1698627D03*
X1280512Y1688391D03*
Y1693493D03*
Y1698030D03*
Y1683857D03*
X1272638Y1703729D03*
Y1708266D03*
Y1712800D03*
X1280512Y1707666D03*
Y1712203D03*
Y1702564D03*
X1272638Y1726974D03*
Y1722440D03*
Y1717903D03*
X1280512Y1730911D03*
Y1726377D03*
Y1721840D03*
Y1716737D03*
X1285370Y1575686D03*
Y1580678D03*
X1297430D03*
X1292474D03*
Y1575686D03*
X1297430D03*
X1285714Y1599884D03*
X1290670D03*
X1297774D03*
X1285370Y1587598D03*
Y1592590D03*
X1297430D03*
X1292474D03*
X1297430Y1587598D03*
X1292474D03*
X1290670Y1616788D03*
X1285714D03*
Y1611796D03*
X1290670D03*
X1285714Y1604876D03*
X1290670D03*
X1297774Y1611796D03*
Y1604876D03*
Y1616788D03*
X1298552Y1614292D03*
X1286492D03*
X1289892D03*
X1298552Y1602380D03*
X1286492D03*
X1289892D03*
X1296260Y1679320D03*
X1288386Y1675383D03*
Y1679920D03*
X1296260Y1688391D03*
Y1693493D03*
Y1698030D03*
Y1683857D03*
X1288386Y1684454D03*
Y1689556D03*
Y1694093D03*
Y1698627D03*
X1296260Y1707666D03*
Y1712203D03*
Y1702564D03*
X1288386Y1703729D03*
Y1708266D03*
Y1712800D03*
X1296260Y1730911D03*
Y1726377D03*
Y1721840D03*
Y1716737D03*
X1288386Y1726974D03*
Y1722440D03*
Y1717903D03*
X1309490Y1575686D03*
X1304534D03*
X1309490Y1580678D03*
X1304534D03*
X1302730Y1599884D03*
X1309834D03*
X1314790D03*
X1309490Y1587598D03*
X1304534D03*
X1309490Y1592590D03*
X1304534D03*
X1302730Y1611796D03*
Y1604876D03*
Y1616788D03*
X1309834D03*
Y1611796D03*
Y1604876D03*
X1314790Y1616788D03*
Y1611796D03*
Y1604876D03*
X1310612Y1614292D03*
X1314012D03*
X1301952D03*
X1310612Y1602380D03*
X1314012D03*
X1301952D03*
X1308071Y1675383D03*
Y1679920D03*
Y1684454D03*
Y1689556D03*
Y1694093D03*
Y1698627D03*
Y1703729D03*
Y1708266D03*
Y1712800D03*
Y1726974D03*
Y1722440D03*
Y1717903D03*
X1321550Y1580678D03*
X1316594D03*
X1321550Y1575686D03*
X1316594D03*
X1328654D03*
Y1580678D03*
X1321894Y1599884D03*
X1326850D03*
X1321550Y1592590D03*
X1316594D03*
X1321550Y1587598D03*
X1316594D03*
X1328654D03*
Y1592590D03*
X1321894Y1611796D03*
Y1604876D03*
X1326850Y1611796D03*
Y1604876D03*
X1321894Y1616788D03*
X1326850D03*
X1322672Y1614292D03*
X1326072D03*
X1322672Y1602380D03*
X1326072D03*
X1323819Y1675383D03*
Y1679920D03*
X1315945Y1679320D03*
X1323819Y1684454D03*
Y1689556D03*
Y1694093D03*
Y1698627D03*
X1315945Y1688391D03*
Y1693493D03*
Y1698030D03*
Y1683857D03*
X1323819Y1703729D03*
Y1708266D03*
Y1712800D03*
X1315945Y1707666D03*
Y1712203D03*
Y1702564D03*
X1323819Y1726974D03*
Y1722440D03*
Y1717903D03*
X1315945Y1730911D03*
Y1726377D03*
Y1721840D03*
Y1716737D03*
X1333610Y1575686D03*
Y1580678D03*
X1345670D03*
X1340714D03*
X1345670Y1575686D03*
X1340714D03*
X1338910Y1599884D03*
X1333954D03*
X1346014D03*
X1333610Y1587598D03*
Y1592590D03*
X1345670D03*
X1340714D03*
X1345670Y1587598D03*
X1340714D03*
X1338910Y1616788D03*
Y1611796D03*
Y1604876D03*
X1333954Y1616788D03*
Y1611796D03*
Y1604876D03*
X1346014Y1611796D03*
Y1604876D03*
Y1616788D03*
X1346792Y1614292D03*
X1334732D03*
X1338132D03*
X1346792Y1602380D03*
X1334732D03*
X1338132D03*
X1339567Y1675383D03*
Y1679920D03*
X1331693Y1679320D03*
X1347441D03*
X1339567Y1684454D03*
Y1689556D03*
Y1694093D03*
Y1698627D03*
X1331693Y1688391D03*
Y1693493D03*
Y1698030D03*
Y1683857D03*
X1347441Y1688391D03*
Y1693493D03*
Y1698030D03*
Y1683857D03*
X1339567Y1703729D03*
Y1708266D03*
Y1712800D03*
X1331693Y1707666D03*
Y1712203D03*
Y1702564D03*
X1347441Y1707666D03*
Y1712203D03*
Y1702564D03*
X1339567Y1726974D03*
Y1722440D03*
Y1717903D03*
X1331693Y1730911D03*
Y1726377D03*
Y1721840D03*
Y1716737D03*
X1347441Y1730911D03*
Y1726377D03*
Y1721840D03*
Y1716737D03*
X1357730Y1575686D03*
X1352774D03*
X1357730Y1580678D03*
X1352774D03*
X1350970Y1599884D03*
X1363030D03*
X1358074D03*
X1357730Y1587598D03*
X1352774D03*
X1357730Y1592590D03*
X1352774D03*
X1350970Y1611796D03*
Y1604876D03*
Y1616788D03*
X1363030D03*
Y1611796D03*
Y1604876D03*
X1358074Y1616788D03*
Y1611796D03*
Y1604876D03*
X1358852Y1614292D03*
X1362252D03*
X1350192D03*
X1358852Y1602380D03*
X1362252D03*
X1350192D03*
X1363189Y1679320D03*
X1355315Y1675383D03*
Y1679920D03*
X1363189Y1688391D03*
Y1693493D03*
Y1698030D03*
Y1683857D03*
X1355315Y1684454D03*
Y1689556D03*
Y1694093D03*
Y1698627D03*
X1363189Y1707666D03*
Y1712203D03*
Y1702564D03*
X1355315Y1703729D03*
Y1708266D03*
Y1712800D03*
X1363189Y1730911D03*
Y1726377D03*
Y1721840D03*
Y1716737D03*
X1355315Y1726974D03*
Y1722440D03*
Y1717903D03*
X1369790Y1580678D03*
X1364834D03*
X1369790Y1575592D03*
X1364834D03*
X1376894Y1575686D03*
Y1580678D03*
X1375090Y1599790D03*
X1370134D03*
X1369790Y1592590D03*
X1364834D03*
X1369790Y1587598D03*
X1364834D03*
X1376894D03*
Y1592590D03*
X1375090Y1611796D03*
Y1604876D03*
Y1616788D03*
X1370134Y1611796D03*
Y1604876D03*
Y1616788D03*
X1370912Y1614292D03*
X1374312D03*
X1370912Y1602380D03*
X1374312D03*
X1381850Y1575686D03*
Y1580678D03*
X1387150Y1599884D03*
X1382194D03*
X1381850Y1587598D03*
Y1592590D03*
X1387150Y1616788D03*
X1382194D03*
X1387150Y1611796D03*
Y1604876D03*
X1382194Y1611796D03*
Y1604876D03*
X1382972Y1614292D03*
X1386372D03*
X1382972Y1602380D03*
X1386372D03*
X1461517Y1575686D03*
Y1580678D03*
Y1587598D03*
Y1592590D03*
X1473577Y1580678D03*
Y1575686D03*
X1466473D03*
Y1580678D03*
X1477755Y1578182D03*
X1462295D03*
X1474355D03*
X1465695D03*
X1471773Y1599884D03*
X1466817D03*
X1473577Y1592590D03*
Y1587598D03*
X1466473D03*
Y1592590D03*
X1477755Y1590094D03*
X1462295D03*
X1474355D03*
X1465695D03*
X1466817Y1611796D03*
X1471773D03*
X1466817Y1604876D03*
X1471773D03*
Y1616788D03*
X1466817D03*
X1490593Y1580678D03*
Y1575686D03*
X1485637D03*
Y1580678D03*
X1478533D03*
Y1575686D03*
X1489815Y1578182D03*
X1486415D03*
X1490937Y1599884D03*
X1478877D03*
X1483833D03*
X1490593Y1587598D03*
X1485637D03*
Y1592590D03*
X1490593D03*
X1478533D03*
Y1587598D03*
X1489815Y1590094D03*
X1486415D03*
X1490937Y1604876D03*
Y1611796D03*
Y1616788D03*
X1483833D03*
X1478877D03*
Y1611796D03*
X1483833D03*
X1478877Y1604876D03*
X1483833D03*
X1509757Y1575686D03*
Y1580678D03*
X1502653D03*
X1497697D03*
X1502653Y1575686D03*
X1497697D03*
X1501875Y1578182D03*
X1498475D03*
X1502997Y1599884D03*
X1507953D03*
X1495893D03*
X1509757Y1587598D03*
Y1592590D03*
X1502653D03*
X1497697D03*
X1502653Y1587598D03*
X1497697D03*
X1501875Y1590094D03*
X1498475D03*
X1502997Y1616788D03*
X1507953D03*
X1502997Y1604876D03*
Y1611796D03*
X1507953Y1604876D03*
Y1611796D03*
X1495893Y1604876D03*
Y1611796D03*
Y1616788D03*
X1505315Y1675383D03*
Y1679920D03*
Y1684454D03*
Y1689556D03*
Y1694093D03*
Y1698627D03*
Y1703729D03*
Y1708266D03*
Y1712800D03*
Y1726974D03*
Y1722440D03*
Y1717903D03*
X1521817Y1580678D03*
Y1575686D03*
X1514713D03*
Y1580678D03*
X1525995Y1578182D03*
X1513935D03*
X1522595D03*
X1510535D03*
X1520013Y1599884D03*
X1515057D03*
X1521817Y1592590D03*
Y1587598D03*
X1514713D03*
Y1592590D03*
X1525995Y1590094D03*
X1513935D03*
X1522595D03*
X1510535D03*
X1520013Y1604876D03*
X1515057D03*
X1520013Y1611796D03*
X1515057D03*
Y1616788D03*
X1520013D03*
X1521063Y1675383D03*
Y1679920D03*
X1513189Y1679320D03*
X1521063Y1684454D03*
Y1689556D03*
Y1694093D03*
Y1698627D03*
X1513189Y1688391D03*
Y1693493D03*
Y1698030D03*
Y1683857D03*
X1521063Y1703729D03*
Y1708266D03*
Y1712800D03*
X1513189Y1707666D03*
Y1712203D03*
Y1702564D03*
X1521063Y1726974D03*
Y1722440D03*
Y1717903D03*
X1513189Y1730911D03*
Y1726377D03*
Y1721840D03*
Y1716737D03*
X1533877Y1575592D03*
X1538833D03*
X1533877Y1580678D03*
X1538833D03*
X1526773D03*
Y1575686D03*
X1538055Y1578182D03*
X1534655D03*
X1539177Y1599790D03*
X1527117Y1599884D03*
X1532073D03*
X1533877Y1587598D03*
X1538833D03*
X1533877Y1592590D03*
X1538833D03*
X1526773D03*
Y1587598D03*
X1538055Y1590094D03*
X1534655D03*
X1539177Y1611796D03*
Y1604876D03*
Y1616788D03*
X1527117D03*
Y1604876D03*
Y1611796D03*
X1532073Y1616788D03*
Y1604876D03*
Y1611796D03*
X1536811Y1675383D03*
Y1679920D03*
X1528937Y1679320D03*
X1536811Y1684454D03*
Y1689556D03*
Y1694093D03*
Y1698627D03*
X1528937Y1688391D03*
Y1693493D03*
Y1698030D03*
Y1683857D03*
X1536811Y1703729D03*
Y1708266D03*
Y1712800D03*
X1528937Y1707666D03*
Y1712203D03*
Y1702564D03*
X1536811Y1726974D03*
Y1722440D03*
Y1717903D03*
X1528937Y1730911D03*
Y1726377D03*
Y1721840D03*
Y1716737D03*
X1557997Y1575686D03*
Y1580678D03*
X1550893D03*
X1545937D03*
X1550893Y1575686D03*
X1545937D03*
X1550115Y1578182D03*
X1558775D03*
X1546715D03*
X1556193Y1599884D03*
X1551237D03*
X1544133Y1599790D03*
X1557997Y1587598D03*
Y1592590D03*
X1545937D03*
X1550893D03*
Y1587598D03*
X1545937D03*
X1550115Y1590094D03*
X1558775D03*
X1546715D03*
X1551237Y1616788D03*
X1556193D03*
Y1604876D03*
X1551237D03*
X1556193Y1611796D03*
X1551237D03*
X1544133Y1604876D03*
Y1611796D03*
Y1616788D03*
X1552559Y1675383D03*
Y1679920D03*
X1544685Y1679320D03*
X1552559Y1684454D03*
Y1689556D03*
Y1694093D03*
Y1698627D03*
X1544685Y1688391D03*
Y1693493D03*
Y1698030D03*
Y1683857D03*
X1552559Y1703729D03*
Y1708266D03*
Y1712800D03*
X1544685Y1707666D03*
Y1712203D03*
Y1702564D03*
X1552559Y1726974D03*
Y1722440D03*
Y1717903D03*
X1544685Y1730911D03*
Y1726377D03*
Y1721840D03*
Y1716737D03*
X1570057Y1580678D03*
X1575013D03*
X1570057Y1575686D03*
X1575013D03*
X1562953D03*
Y1580678D03*
X1574235Y1578182D03*
X1562175D03*
X1570835D03*
X1575357Y1599884D03*
X1563297D03*
X1568253D03*
X1570057Y1592590D03*
X1575013D03*
X1570057Y1587598D03*
X1575013D03*
X1562953D03*
Y1592590D03*
X1574235Y1590094D03*
X1562175D03*
X1570835D03*
X1575357Y1616788D03*
Y1604876D03*
Y1611796D03*
X1563297Y1604876D03*
Y1611796D03*
X1568253Y1604876D03*
Y1611796D03*
X1563297Y1616788D03*
X1568253D03*
X1560433Y1679320D03*
X1572244Y1675383D03*
Y1679920D03*
X1560433Y1688391D03*
Y1693493D03*
Y1698030D03*
Y1683857D03*
X1572244Y1684454D03*
Y1689556D03*
Y1694093D03*
Y1698627D03*
X1560433Y1707666D03*
Y1712203D03*
Y1702564D03*
X1572244Y1703729D03*
Y1708266D03*
Y1712800D03*
X1560433Y1730911D03*
Y1726377D03*
Y1721840D03*
Y1716737D03*
X1572244Y1726974D03*
Y1722440D03*
Y1717903D03*
X1582117Y1575686D03*
X1587073D03*
X1582117Y1580678D03*
X1587073D03*
X1586295Y1578182D03*
X1582895D03*
X1587417Y1599884D03*
X1580313D03*
X1582117Y1587598D03*
X1587073D03*
X1582117Y1592590D03*
X1587073D03*
X1586295Y1590094D03*
X1582895D03*
X1587417Y1604876D03*
Y1611796D03*
Y1616788D03*
X1580313D03*
Y1604876D03*
Y1611796D03*
X1587992Y1675383D03*
Y1679920D03*
X1580118Y1679320D03*
X1587992Y1684454D03*
Y1689556D03*
Y1694093D03*
Y1698627D03*
X1580118Y1688391D03*
Y1693493D03*
Y1698030D03*
Y1683857D03*
X1587992Y1703729D03*
Y1708266D03*
Y1712800D03*
X1580118Y1707666D03*
Y1712203D03*
Y1702564D03*
X1587992Y1726974D03*
Y1722440D03*
Y1717903D03*
X1580118Y1730911D03*
Y1726377D03*
Y1721840D03*
Y1716737D03*
X1597041Y770144D03*
X1605741D03*
X1605800Y766478D03*
X1605741Y776837D03*
X1597041D03*
X1605741Y783530D03*
X1597041D03*
X1605741Y793570D03*
X1597041D03*
X1596988Y800263D03*
X1605741D03*
X1595774Y806955D03*
X1606934D03*
X1596218Y813648D03*
X1606735D03*
X1597041Y820341D03*
X1605741D03*
X1597041Y830381D03*
X1605741D03*
Y837074D03*
X1597041D03*
Y843766D03*
X1605741D03*
X1596147Y850459D03*
X1606896D03*
X1596200Y857152D03*
X1606623D03*
X1597041Y867192D03*
X1605741D03*
X1597041Y873885D03*
X1605741D03*
X1597041Y880577D03*
X1605741D03*
X1597041Y887270D03*
X1605741D03*
X1606898Y893963D03*
X1597041D03*
X1605741Y904003D03*
X1597041D03*
Y917389D03*
X1605741D03*
X1597041Y910696D03*
X1605741D03*
X1597041Y924081D03*
X1605741D03*
X1606541Y930697D03*
X1596047Y930774D03*
X1596106Y940814D03*
X1606919D03*
X1605741Y947507D03*
X1597041D03*
X1605741Y954200D03*
X1597041D03*
Y964239D03*
X1605741D03*
X1597041Y977625D03*
X1605741D03*
Y970932D03*
X1597041D03*
Y984318D03*
X1605741D03*
X1597041Y991011D03*
X1605741D03*
X1597041Y1024475D03*
X1605741D03*
X1597041Y1017782D03*
X1605741D03*
X1597041Y1031168D03*
X1605741D03*
X1597041Y1037861D03*
X1605741D03*
X1597041Y1044554D03*
X1605741D03*
Y1051247D03*
X1597041D03*
Y1057940D03*
X1605741D03*
X1597041Y1061286D03*
Y1064633D03*
X1605741D03*
X1606541Y1071326D03*
X1596141D03*
X1597041Y1078018D03*
X1605741D03*
Y1094751D03*
X1597041D03*
Y1088058D03*
X1605741D03*
Y1101444D03*
X1597041D03*
Y1108137D03*
X1605741D03*
X1606541Y1114829D03*
X1596241D03*
X1596511Y1124969D03*
X1606505Y1124674D03*
X1605741Y1138255D03*
X1597041D03*
X1605741Y1144948D03*
X1597041D03*
Y1131562D03*
X1605741D03*
Y1151641D03*
X1597041D03*
X1596653Y1161680D03*
X1605975Y1161581D03*
X1605741Y1168373D03*
X1597041D03*
X1605741Y1175066D03*
X1597041D03*
X1605741Y1181759D03*
X1597041D03*
X1606765Y1188452D03*
X1597041D03*
Y1198491D03*
X1605741D03*
Y1205184D03*
X1597041D03*
Y1211877D03*
X1605741D03*
X1597041Y1218570D03*
X1605741D03*
X1597041Y1225263D03*
X1605741D03*
X1607064Y1235302D03*
X1596178D03*
X1605741Y1241995D03*
X1597041D03*
Y1248688D03*
X1605741D03*
X1606481Y1258649D03*
X1608000Y1261662D03*
X1603788Y1273144D03*
X1601388D03*
X1607897Y1264445D03*
X1606237Y1575686D03*
Y1580678D03*
X1594177D03*
X1599133D03*
X1594177Y1575686D03*
X1599133D03*
X1598355Y1578182D03*
X1607015D03*
X1594955D03*
X1599477Y1599884D03*
X1604433D03*
X1592373D03*
X1606237Y1587598D03*
Y1592590D03*
X1594177D03*
X1599133D03*
X1594177Y1587598D03*
X1599133D03*
X1598355Y1590094D03*
X1607015D03*
X1594955D03*
X1599477Y1616788D03*
X1604433D03*
X1599477Y1604876D03*
Y1611796D03*
X1604433Y1604876D03*
Y1611796D03*
X1592373Y1604876D03*
Y1611796D03*
Y1616788D03*
X1603740Y1675383D03*
Y1679920D03*
X1595866Y1679320D03*
X1603740Y1684454D03*
Y1689556D03*
Y1694093D03*
Y1698627D03*
X1595866Y1688391D03*
Y1693493D03*
Y1698030D03*
Y1683857D03*
X1603740Y1703729D03*
Y1708266D03*
Y1712800D03*
X1595866Y1707666D03*
Y1712203D03*
Y1702564D03*
X1603740Y1726974D03*
Y1722440D03*
Y1717903D03*
X1595866Y1730911D03*
Y1726377D03*
Y1721840D03*
Y1716737D03*
X1613183Y766798D03*
Y773491D03*
Y780184D03*
Y790223D03*
Y796916D03*
Y803609D03*
Y816995D03*
X1612363Y810302D03*
X1613183Y827034D03*
Y833727D03*
Y840420D03*
Y847113D03*
X1621943D03*
X1622060Y863845D03*
X1612408D03*
X1612474Y853955D03*
X1622961Y853806D03*
X1621883Y883924D03*
X1613183D03*
Y870538D03*
X1621883D03*
X1613183Y877231D03*
X1621883D03*
X1613183Y890617D03*
X1621883D03*
X1613183Y900656D03*
X1621883D03*
Y907349D03*
X1613183D03*
Y914042D03*
X1621883D03*
Y920735D03*
X1613183D03*
X1622535Y927526D03*
X1612168Y927428D03*
X1622845Y937467D03*
X1612312D03*
X1621883Y944160D03*
X1613183D03*
X1621883Y950853D03*
X1613183D03*
X1621883Y960892D03*
X1613183D03*
X1613083Y957546D03*
Y954200D03*
X1613183Y974278D03*
X1621883D03*
X1613183Y980971D03*
X1621883D03*
X1613183Y967585D03*
X1621883D03*
X1613183Y987664D03*
X1621883D03*
X1620399Y1000325D03*
X1621883Y1017782D03*
X1613183D03*
Y1027822D03*
X1621883D03*
X1613183Y1034515D03*
X1621883D03*
X1613183Y1041207D03*
X1621883D03*
X1613183Y1047900D03*
X1621883D03*
Y1054593D03*
X1613183D03*
Y1061286D03*
X1621883D03*
Y1067979D03*
X1612983D03*
X1612283Y1074672D03*
X1622683D03*
X1621883Y1084711D03*
X1612383D03*
X1613183Y1091404D03*
X1621883D03*
Y1104790D03*
X1613183D03*
X1621883Y1098097D03*
X1613183D03*
X1621883Y1111483D03*
X1613183D03*
Y1128915D03*
X1621883Y1128215D03*
X1613183Y1121522D03*
X1621883D03*
Y1141601D03*
X1613183D03*
X1622726Y1135108D03*
X1611886Y1134908D03*
X1621883Y1158333D03*
X1613183D03*
X1621883Y1148294D03*
X1613183D03*
X1621883Y1165026D03*
X1613183D03*
Y1171719D03*
X1621883D03*
Y1178412D03*
X1613183D03*
X1621883Y1185105D03*
X1613183D03*
Y1195144D03*
X1621883D03*
Y1201837D03*
X1613183D03*
X1621883Y1208530D03*
X1613183D03*
X1621883Y1215223D03*
X1613183D03*
X1612147Y1221916D03*
X1622712D03*
X1612137Y1231862D03*
X1622681Y1231955D03*
X1621883Y1238648D03*
X1613183D03*
X1610150Y1257172D03*
X1621883Y1245341D03*
X1613183D03*
X1621983Y1258727D03*
X1624600Y1262074D03*
X1613183Y1252034D03*
X1613027Y1248805D03*
X1609056Y1250602D03*
X1623930Y1252242D03*
X1618888Y1273344D03*
X1616088D03*
X1613019Y1261235D03*
X1618297Y1580678D03*
X1623253D03*
X1618297Y1575686D03*
X1623253D03*
X1611193D03*
Y1580678D03*
X1622475Y1578182D03*
X1610415D03*
X1619075D03*
X1623597Y1599884D03*
X1611537D03*
X1616493D03*
X1618297Y1592590D03*
X1623253D03*
X1618297Y1587598D03*
X1623253D03*
X1611193D03*
Y1592590D03*
X1622475Y1590094D03*
X1610415D03*
X1619075D03*
X1623597Y1616788D03*
Y1604876D03*
Y1611796D03*
X1611537Y1604876D03*
Y1611796D03*
X1616493Y1604876D03*
Y1611796D03*
X1611537Y1616788D03*
X1616493D03*
X1619488Y1675383D03*
Y1679920D03*
X1611614Y1679320D03*
X1619488Y1684454D03*
Y1689556D03*
Y1694093D03*
Y1698627D03*
X1611614Y1688391D03*
Y1693493D03*
Y1698030D03*
Y1683857D03*
X1619488Y1703729D03*
Y1708266D03*
Y1712800D03*
X1611614Y1707666D03*
Y1712203D03*
Y1702564D03*
X1619488Y1726974D03*
Y1722440D03*
Y1717903D03*
X1611614Y1730911D03*
Y1726377D03*
Y1721840D03*
Y1716737D03*
X1626741Y766798D03*
X1635441Y850459D03*
X1626741D03*
X1625705Y867192D03*
X1636441D03*
X1635441Y857152D03*
X1626741D03*
Y880577D03*
X1635441D03*
Y873885D03*
X1626741D03*
Y887270D03*
X1635441D03*
X1626741Y893963D03*
X1635441D03*
X1626741Y904003D03*
X1635441D03*
Y910696D03*
X1626741D03*
X1635441Y917389D03*
X1626741D03*
X1636316Y930774D03*
X1625803D03*
X1636646Y924081D03*
X1626741D03*
X1635441Y940814D03*
X1626741D03*
X1635441Y947507D03*
X1626741D03*
X1635441Y954200D03*
X1626741D03*
Y964239D03*
X1635441D03*
Y977625D03*
X1626741D03*
X1635441Y970932D03*
X1626741D03*
X1635441Y984318D03*
X1626741D03*
Y991011D03*
X1635441D03*
Y1024475D03*
X1626741D03*
X1635441Y1017782D03*
X1626741D03*
X1635441Y1031168D03*
X1626741D03*
X1635441Y1037861D03*
X1626741D03*
X1635441Y1044554D03*
X1626741D03*
Y1057940D03*
X1635441D03*
Y1051247D03*
X1626741D03*
X1635441Y1064633D03*
X1626741D03*
X1635441Y1071326D03*
X1626741D03*
X1636241Y1078018D03*
X1625941D03*
Y1088058D03*
X1636241D03*
X1635441Y1094751D03*
X1626741D03*
Y1101444D03*
X1635441D03*
X1626741Y1108137D03*
X1635441D03*
X1626074Y1124640D03*
X1636341Y1124869D03*
X1635441Y1114829D03*
X1626741D03*
X1635441Y1144948D03*
X1626741D03*
X1635441Y1138255D03*
X1626741D03*
X1635441Y1130762D03*
X1626741D03*
Y1161680D03*
X1635441D03*
Y1151641D03*
X1626741D03*
Y1168373D03*
X1635441D03*
X1626741Y1175066D03*
X1635441D03*
X1626741Y1181759D03*
X1635441D03*
X1626741Y1188452D03*
X1635441D03*
X1626741Y1198491D03*
X1635441D03*
X1626741Y1205184D03*
X1635441D03*
Y1211877D03*
X1626741D03*
X1635441Y1218570D03*
X1626741D03*
X1636212Y1225263D03*
X1626055D03*
X1636376Y1235302D03*
X1625843D03*
X1635441Y1241995D03*
X1626741D03*
X1635688Y1257664D03*
X1626741Y1248688D03*
X1635441D03*
X1626741Y1258727D03*
X1629788Y1273344D03*
X1632588D03*
X1625729Y1266766D03*
X1630357Y1575592D03*
X1635313D03*
X1630357Y1580678D03*
X1635313D03*
X1634535Y1578182D03*
X1631135D03*
X1640613Y1599790D03*
X1635657D03*
X1628553Y1599884D03*
X1630357Y1587598D03*
X1635313D03*
X1630357Y1592590D03*
X1635313D03*
X1634535Y1590094D03*
X1631135D03*
X1640613Y1604876D03*
Y1611796D03*
X1635657Y1604876D03*
Y1611796D03*
X1640613Y1616788D03*
X1635657D03*
X1628553D03*
Y1604876D03*
Y1611796D03*
X1627362Y1679320D03*
Y1688391D03*
Y1693493D03*
Y1698030D03*
Y1683857D03*
Y1707666D03*
Y1712203D03*
Y1702564D03*
Y1730911D03*
Y1726377D03*
Y1721840D03*
Y1716737D03*
X1656441Y766798D03*
Y850459D03*
X1651583Y847113D03*
X1642883D03*
X1642058Y863845D03*
X1652742D03*
X1656441Y857152D03*
Y867192D03*
X1652559Y853806D03*
X1642032D03*
X1656441Y873885D03*
Y880577D03*
X1642883Y883924D03*
X1651583D03*
Y870538D03*
X1642883D03*
X1651583Y877231D03*
X1642883D03*
X1656441Y887270D03*
Y893963D03*
X1642883Y890617D03*
X1651583D03*
X1642883Y900656D03*
X1651583D03*
X1656441Y904003D03*
Y910696D03*
X1642883Y907349D03*
X1651583D03*
X1656441Y917389D03*
X1651583Y914042D03*
X1642883D03*
X1656441Y924081D03*
Y930774D03*
X1652630Y927428D03*
X1642038D03*
X1651583Y920735D03*
X1642883D03*
X1656441Y940814D03*
Y947507D03*
X1652501Y937467D03*
X1642065D03*
X1651583Y944160D03*
X1642883D03*
X1656441Y954200D03*
X1642883Y950853D03*
X1651583D03*
Y960892D03*
X1642883D03*
X1656441Y964239D03*
X1642783Y957546D03*
Y954200D03*
X1656441Y977625D03*
Y970932D03*
X1651583Y967585D03*
X1642883D03*
X1651583Y974278D03*
X1642883D03*
X1651583Y980971D03*
X1642883D03*
X1656441Y984318D03*
Y991011D03*
X1651583Y987664D03*
X1642883D03*
X1648205Y998632D03*
X1651583Y1017782D03*
X1642883D03*
X1656441D03*
Y1024475D03*
X1651583Y1027822D03*
X1642883D03*
X1656441Y1031168D03*
Y1044554D03*
Y1037861D03*
X1651583Y1034515D03*
X1642883D03*
X1651583Y1041207D03*
X1642883D03*
X1651583Y1047900D03*
X1642883D03*
Y1061286D03*
X1651583D03*
X1656441Y1051247D03*
Y1057940D03*
X1651583Y1054593D03*
X1642883D03*
X1656441Y1061286D03*
Y1064633D03*
Y1071326D03*
Y1078018D03*
X1652483Y1074672D03*
X1641983D03*
X1651583Y1067979D03*
X1642883D03*
X1656441Y1088058D03*
Y1094751D03*
X1652383Y1084711D03*
X1642083D03*
X1651583Y1091404D03*
X1642883D03*
X1656441Y1101444D03*
Y1108137D03*
X1642883Y1098097D03*
X1651583D03*
X1642883Y1104790D03*
X1651583D03*
X1642883Y1111483D03*
X1651583D03*
X1656441Y1114829D03*
Y1124869D03*
X1642883Y1121522D03*
X1651583D03*
X1642883Y1128215D03*
X1651583D03*
X1656441Y1131562D03*
Y1138255D03*
X1642883Y1134908D03*
X1651583D03*
X1642883Y1141601D03*
X1651583D03*
X1656441Y1144948D03*
Y1151641D03*
Y1161680D03*
X1652383Y1158333D03*
X1642083D03*
X1652794Y1148294D03*
X1641744D03*
X1656441Y1168373D03*
Y1175066D03*
X1642883Y1171719D03*
X1651583D03*
Y1165026D03*
X1642883D03*
X1656441Y1181759D03*
Y1188452D03*
X1651583Y1178412D03*
X1642883D03*
X1651583Y1185105D03*
X1642883D03*
X1656441Y1198491D03*
Y1205184D03*
X1642883Y1195144D03*
X1651583D03*
X1642883Y1201837D03*
X1651583D03*
X1642883Y1208530D03*
X1651583D03*
X1656441Y1211877D03*
X1652590Y1221916D03*
X1641793D03*
X1656441Y1225263D03*
Y1218570D03*
X1651583Y1215223D03*
X1642883D03*
X1656441Y1235302D03*
Y1241995D03*
X1652604Y1231955D03*
X1642054D03*
X1651583Y1238648D03*
X1642883D03*
X1656441Y1248688D03*
X1651583Y1245341D03*
X1642883D03*
Y1255381D03*
Y1258727D03*
Y1252034D03*
X1651679Y1248885D03*
X1653140Y1257862D03*
X1648588Y1273344D03*
X1645788D03*
X1656188Y1264964D03*
X1642788Y1264464D03*
X1642883Y1262074D03*
X1656170Y1260352D03*
X1654600Y1262742D03*
X1647373Y1580678D03*
X1642417D03*
X1647373Y1575686D03*
X1642417D03*
X1646595Y1578182D03*
X1643195D03*
X1647717Y1599884D03*
X1652673D03*
X1647373Y1592590D03*
X1642417D03*
X1647373Y1587598D03*
X1642417D03*
X1646595Y1590094D03*
X1643195D03*
X1647717Y1616788D03*
X1652673D03*
X1647717Y1604876D03*
Y1611796D03*
X1652673Y1604876D03*
Y1611796D03*
X1665141Y850459D03*
X1672583Y847113D03*
X1666038Y857152D03*
X1665141Y867192D03*
X1672583Y853806D03*
Y863845D03*
X1665141Y873885D03*
Y880577D03*
X1672583Y870538D03*
Y877231D03*
Y883924D03*
X1665141Y887270D03*
Y893963D03*
X1672583Y890617D03*
Y900656D03*
X1665141Y904003D03*
Y910696D03*
Y917389D03*
X1672583Y907349D03*
Y914042D03*
X1665141Y924081D03*
X1666246Y930774D03*
X1672583Y920735D03*
Y927428D03*
X1665141Y940814D03*
Y947507D03*
X1672583Y937467D03*
Y944160D03*
X1665141Y954200D03*
Y964239D03*
X1672583Y950853D03*
Y960892D03*
Y957546D03*
Y954200D03*
X1665141Y977625D03*
Y970932D03*
X1672583Y967585D03*
Y974278D03*
Y980971D03*
X1665141Y984318D03*
Y991011D03*
X1672583Y987664D03*
Y994357D03*
X1665141Y1017782D03*
Y1024475D03*
Y1031168D03*
X1672583Y1017782D03*
Y1027822D03*
X1665141Y1044554D03*
Y1037861D03*
X1672583Y1034515D03*
Y1041207D03*
Y1047900D03*
X1665141Y1051247D03*
Y1057940D03*
X1672583Y1061286D03*
Y1054593D03*
X1665141Y1064633D03*
Y1071326D03*
Y1077118D03*
X1672583Y1067979D03*
Y1074672D03*
X1665141Y1088058D03*
Y1094751D03*
X1672583Y1084711D03*
Y1091404D03*
X1665141Y1101444D03*
Y1108137D03*
X1672583Y1098097D03*
Y1104790D03*
Y1111483D03*
X1665141Y1114829D03*
Y1124869D03*
X1672583Y1121522D03*
Y1128215D03*
X1665141Y1131562D03*
Y1138255D03*
Y1144948D03*
X1672583Y1134908D03*
Y1141601D03*
X1666141Y1151641D03*
X1665141Y1161680D03*
X1672583Y1148294D03*
Y1158333D03*
X1665141Y1168373D03*
Y1175066D03*
X1672583Y1165026D03*
Y1171719D03*
X1665141Y1181759D03*
Y1188452D03*
X1672583Y1178412D03*
Y1185105D03*
X1665141Y1198491D03*
Y1205184D03*
X1672583Y1195144D03*
Y1201837D03*
Y1208530D03*
X1665141Y1211877D03*
X1665941Y1225263D03*
X1665141Y1218570D03*
X1672583Y1215223D03*
Y1221916D03*
X1665141Y1235302D03*
Y1241995D03*
X1672583Y1231955D03*
Y1238648D03*
X1665141Y1248688D03*
X1672583Y1245341D03*
X1665688Y1257964D03*
X1672583Y1255381D03*
Y1258727D03*
Y1248688D03*
X1659488Y1273344D03*
X1662288D03*
X1672188Y1263764D03*
X1686041Y766798D03*
X1686141Y850459D03*
X1681283Y847113D03*
X1686141Y857152D03*
Y867192D03*
X1681283Y853806D03*
Y863845D03*
X1686141Y873885D03*
Y880577D03*
X1681283Y870538D03*
Y877231D03*
Y883924D03*
X1686141Y887270D03*
Y893963D03*
X1681283Y890617D03*
Y900656D03*
X1686141Y904003D03*
Y910696D03*
Y917389D03*
X1681283Y907349D03*
Y914042D03*
X1686141Y924081D03*
Y930774D03*
X1681283Y920735D03*
Y927428D03*
X1686141Y940814D03*
Y947507D03*
X1681283Y937467D03*
Y944160D03*
X1686141Y954200D03*
Y964239D03*
X1681283Y950853D03*
Y960892D03*
X1686141Y970932D03*
Y977625D03*
X1681283Y967585D03*
Y974278D03*
Y980971D03*
X1686141Y984318D03*
Y991011D03*
X1681283Y987664D03*
X1686141Y1017782D03*
Y1024475D03*
Y1031168D03*
X1681283Y1017782D03*
Y1027822D03*
X1686141Y1037861D03*
Y1044554D03*
X1681283Y1034515D03*
Y1041207D03*
Y1047900D03*
X1686141Y1051247D03*
Y1057940D03*
X1681283Y1061286D03*
Y1054593D03*
X1686141Y1064633D03*
Y1071326D03*
Y1078018D03*
X1681283Y1067979D03*
Y1074672D03*
X1686141Y1088058D03*
Y1094751D03*
X1681283Y1084711D03*
Y1091404D03*
X1686141Y1101444D03*
Y1108137D03*
X1681283Y1098097D03*
Y1104790D03*
Y1111483D03*
X1686141Y1114829D03*
Y1124869D03*
X1681283Y1121522D03*
Y1128215D03*
X1686141Y1131562D03*
Y1138255D03*
Y1144948D03*
X1681283Y1134908D03*
Y1141601D03*
X1686141Y1151641D03*
Y1161680D03*
X1681283Y1148294D03*
Y1158333D03*
X1686141Y1168373D03*
Y1175066D03*
X1681283Y1165026D03*
Y1171719D03*
X1686141Y1181759D03*
Y1188452D03*
X1681283Y1178412D03*
Y1185105D03*
X1686141Y1198491D03*
Y1205184D03*
X1681283Y1195144D03*
Y1201837D03*
Y1208530D03*
X1686141Y1211877D03*
Y1218570D03*
Y1225263D03*
X1681283Y1215223D03*
Y1221916D03*
Y1231955D03*
Y1238648D03*
X1686141Y1235302D03*
Y1241995D03*
X1681283Y1245341D03*
X1686141Y1248688D03*
Y1258727D03*
X1681179Y1252034D03*
X1683578Y1253780D03*
X1675488Y1273344D03*
X1678288D03*
X1689188D03*
X1686119Y1264985D03*
X1681309Y1262074D03*
X1683500Y1264312D03*
X1702183Y957546D03*
Y954200D03*
Y994357D03*
X1702283Y1057940D03*
X1694841Y1235302D03*
Y1241995D03*
X1702283Y1231955D03*
Y1238648D03*
X1694841Y1248688D03*
X1695188Y1257064D03*
X1702283Y1245341D03*
X1699852Y1245418D03*
X1699089Y1258842D03*
X1702283Y1248688D03*
X1691988Y1273344D03*
X1705188D03*
X1702249Y1265420D03*
X1702283Y1262074D03*
X1699030Y1263912D03*
X1715841Y766798D03*
Y1061286D03*
X1710983Y1231955D03*
Y1238648D03*
X1715841Y1235302D03*
Y1241995D03*
X1710983Y1245341D03*
X1715841Y1248688D03*
X1713620Y1258512D03*
X1711109Y1252034D03*
X1713930Y1262074D03*
X1707514Y1273444D03*
X1718888Y1273344D03*
X1721688D03*
X1715839Y1265420D03*
X1731983Y957546D03*
Y954200D03*
Y994357D03*
X1731683Y1057940D03*
X1724541Y1235302D03*
Y1241995D03*
X1731983Y1231955D03*
Y1238648D03*
X1724541Y1248688D03*
X1724588Y1257164D03*
X1731983Y1245341D03*
X1727041Y1248688D03*
X1731983Y1255381D03*
Y1258727D03*
Y1252034D03*
Y1248688D03*
X1734888Y1273344D03*
X1737688D03*
X1731939Y1265420D03*
X1731983Y1262074D03*
X1745541Y770144D03*
X1754241D03*
X1745541Y766798D03*
Y776837D03*
X1754241D03*
X1745541Y783530D03*
X1754241D03*
X1745541Y793570D03*
X1754241D03*
X1745541Y800263D03*
X1754241D03*
X1745541Y806955D03*
X1754241D03*
X1745541Y813648D03*
X1754241D03*
X1745541Y820341D03*
X1754241D03*
X1745541Y830381D03*
X1754241D03*
Y843766D03*
X1745541D03*
Y837074D03*
X1754241D03*
X1745541Y850459D03*
X1754241D03*
X1745541Y857152D03*
X1754241D03*
Y867192D03*
X1745541D03*
Y873885D03*
X1754241D03*
X1745541Y880577D03*
X1754241D03*
Y893963D03*
X1745541D03*
Y887270D03*
X1754241D03*
Y904003D03*
X1745541D03*
X1754241Y910696D03*
X1745541D03*
X1754241Y917389D03*
X1745541D03*
X1754241Y924081D03*
X1745541D03*
X1754241Y930774D03*
X1745541D03*
X1754241Y940814D03*
X1745541D03*
X1754241Y947507D03*
X1745541D03*
X1754241Y954200D03*
X1745541D03*
X1754241Y964239D03*
X1745541D03*
X1754241Y970932D03*
X1745541D03*
X1754241Y977625D03*
X1745541D03*
X1754241Y984318D03*
X1745541D03*
X1754241Y991011D03*
X1745541D03*
X1754241Y1017782D03*
X1745541D03*
Y1024475D03*
X1754241D03*
X1745541Y1031168D03*
X1754241D03*
Y1044554D03*
X1745541D03*
Y1037861D03*
X1754241D03*
X1745541Y1051247D03*
X1754241D03*
X1745541Y1057940D03*
X1754241D03*
Y1071326D03*
X1745541D03*
Y1064633D03*
X1754241D03*
Y1078018D03*
X1745541D03*
X1754241Y1088058D03*
X1745541D03*
X1754241Y1094751D03*
X1745541D03*
X1754241Y1101444D03*
X1745541D03*
X1754241Y1108137D03*
X1745541D03*
X1754241Y1114829D03*
X1745541D03*
X1754241Y1124869D03*
X1745541D03*
X1754241Y1131562D03*
X1745541D03*
X1754241Y1138255D03*
X1745541D03*
X1754241Y1144948D03*
X1745541D03*
X1754241Y1151641D03*
X1745541D03*
X1754241Y1161680D03*
X1745541D03*
Y1175066D03*
X1754241D03*
Y1168373D03*
X1745541D03*
Y1181759D03*
X1754241D03*
Y1188452D03*
X1745541D03*
X1754241Y1198491D03*
X1745541D03*
X1754241Y1205184D03*
X1745541D03*
X1754241Y1211877D03*
X1745541D03*
X1754241Y1218570D03*
X1745541D03*
X1754241Y1225263D03*
X1745541D03*
X1740683Y1231955D03*
Y1238648D03*
X1754241Y1235302D03*
X1745541D03*
X1754241Y1241995D03*
X1745541D03*
X1740683Y1245341D03*
X1754241Y1248688D03*
X1745541D03*
X1754488Y1257264D03*
X1745541Y1258727D03*
X1743710Y1262074D03*
X1742337Y1252300D03*
X1751388Y1273344D03*
X1748588D03*
X1745541Y1265420D03*
X1749088Y1310474D03*
X1746288D03*
X1770383Y766798D03*
X1761683D03*
X1770383Y773491D03*
X1761683D03*
Y780184D03*
X1770383D03*
X1761683Y790223D03*
X1770383D03*
X1761683Y796916D03*
X1770383D03*
X1761683Y803609D03*
X1770383D03*
X1761683Y810302D03*
X1770383D03*
X1761683Y816995D03*
X1770383D03*
X1761683Y827034D03*
X1770383D03*
X1761683Y833727D03*
X1770383D03*
X1761683Y840420D03*
X1770383D03*
X1761683Y847113D03*
X1770383D03*
X1761683Y853806D03*
X1770383D03*
X1761683Y863845D03*
X1770383D03*
X1761683Y870538D03*
X1770383D03*
X1761683Y877231D03*
X1770383D03*
X1761683Y883924D03*
X1770383D03*
X1761683Y890617D03*
X1770383D03*
X1761683Y900656D03*
X1770383D03*
X1761683Y907349D03*
X1770383D03*
X1761683Y914042D03*
X1770383D03*
Y927428D03*
X1761683D03*
Y920735D03*
X1770383D03*
X1761683Y937467D03*
X1770383D03*
X1761683Y944160D03*
X1770383D03*
X1761683Y950853D03*
X1770383D03*
X1761683Y960892D03*
X1770383D03*
X1761683Y957546D03*
Y954200D03*
Y967585D03*
X1770383D03*
X1761683Y974278D03*
X1770383D03*
X1761683Y980971D03*
X1770383D03*
X1761683Y987664D03*
X1770383D03*
X1761683Y994357D03*
Y1017782D03*
X1770383D03*
X1761683Y1027822D03*
X1770383D03*
X1761683Y1034515D03*
X1770383D03*
X1761683Y1041207D03*
X1770383D03*
X1761683Y1047900D03*
X1770383D03*
X1761683Y1054593D03*
X1770383D03*
X1761683Y1061286D03*
X1770383D03*
X1761683Y1067979D03*
X1770383D03*
X1761683Y1074672D03*
X1770383D03*
X1761683Y1084711D03*
X1770383D03*
X1761683Y1091404D03*
X1770383D03*
Y1098097D03*
X1761683D03*
Y1104790D03*
X1770383D03*
X1761683Y1111483D03*
X1770383D03*
X1761683Y1121522D03*
X1770383D03*
X1761683Y1128215D03*
X1770383D03*
X1761683Y1134908D03*
X1770383D03*
X1761683Y1141601D03*
X1770383D03*
X1761683Y1148294D03*
X1770383D03*
X1761683Y1158333D03*
X1770383D03*
X1761683Y1165026D03*
X1770383D03*
X1761683Y1171719D03*
X1770383D03*
X1761683Y1178412D03*
X1770383D03*
X1761683Y1185105D03*
X1770383D03*
X1761683Y1195144D03*
X1770383D03*
X1761683Y1201837D03*
X1770383D03*
X1761683Y1208530D03*
X1770383D03*
X1761683Y1215223D03*
X1770383D03*
X1761683Y1221916D03*
X1770383D03*
X1761683Y1231955D03*
X1770383D03*
X1761683Y1238648D03*
X1770383D03*
X1761683Y1245341D03*
X1770383D03*
X1756922Y1247632D03*
X1761683Y1255381D03*
Y1258727D03*
X1770299Y1252034D03*
X1761683Y1248688D03*
X1767388Y1273344D03*
X1764588D03*
X1761683Y1262074D03*
Y1265420D03*
X1775241Y770144D03*
X1783941D03*
X1773559Y767345D03*
X1775241Y776837D03*
X1783941D03*
X1775241Y783530D03*
X1783941D03*
X1775241Y780184D03*
Y773491D03*
Y786877D03*
Y793570D03*
X1783941D03*
X1775241Y800263D03*
X1783941D03*
X1775241Y803609D03*
Y796916D03*
Y790223D03*
Y806955D03*
X1783941D03*
X1775241Y813648D03*
X1783941D03*
X1775241Y820341D03*
X1783941D03*
Y830381D03*
X1775241D03*
Y837074D03*
X1783941D03*
X1775241Y843766D03*
X1783941D03*
X1775241Y850459D03*
X1783941D03*
X1775241Y847113D03*
Y857152D03*
X1783941D03*
X1775241Y867192D03*
X1783941D03*
X1775241Y853806D03*
Y860499D03*
Y863845D03*
Y873885D03*
X1783941D03*
X1775241Y880577D03*
X1783941D03*
X1775241Y883924D03*
Y877231D03*
Y870538D03*
Y887270D03*
X1783941D03*
X1775241Y893963D03*
X1783941D03*
X1775241Y890617D03*
Y897310D03*
Y900656D03*
Y904003D03*
X1783941D03*
X1775241Y910696D03*
X1783941D03*
X1775241Y917389D03*
X1783941D03*
X1775241Y914042D03*
Y907349D03*
Y924081D03*
X1783941D03*
X1775241Y930774D03*
X1783941D03*
X1775241Y927428D03*
Y920735D03*
Y934121D03*
Y940814D03*
X1783941D03*
X1775241Y947507D03*
X1783941D03*
X1775241Y944160D03*
Y937467D03*
Y954200D03*
X1783941D03*
X1775241Y964239D03*
X1783941D03*
X1775241Y950853D03*
Y970932D03*
X1783941D03*
X1775241Y977625D03*
X1783941D03*
X1775241Y980971D03*
Y974278D03*
Y984318D03*
X1783941D03*
X1775241Y991011D03*
X1783941D03*
X1775241Y994357D03*
Y987664D03*
Y1017782D03*
X1783941D03*
X1775241Y1024475D03*
X1783941D03*
X1775241Y1031168D03*
X1783941D03*
X1775241Y1027822D03*
Y1021129D03*
Y1037861D03*
X1783941D03*
X1775241Y1044554D03*
X1783941D03*
X1775241Y1047900D03*
Y1041207D03*
Y1034515D03*
Y1051247D03*
X1783941D03*
X1775241Y1057940D03*
X1783941D03*
X1775241Y1061286D03*
Y1054593D03*
Y1064633D03*
X1783941D03*
X1775241Y1071326D03*
X1783941D03*
X1775241Y1078018D03*
X1783941D03*
X1775241Y1074672D03*
Y1067979D03*
Y1088058D03*
X1783941D03*
X1775241Y1094751D03*
X1783941D03*
X1775241Y1091404D03*
Y1081365D03*
Y1084711D03*
Y1101444D03*
X1783941D03*
X1775241Y1108137D03*
X1783941D03*
X1775241Y1098097D03*
Y1111483D03*
Y1104790D03*
Y1114829D03*
X1783941D03*
X1775241Y1124869D03*
X1783941D03*
X1775241Y1128215D03*
Y1118176D03*
Y1121522D03*
Y1131562D03*
X1783941D03*
X1775241Y1138255D03*
X1783941D03*
X1775241Y1144948D03*
X1783941D03*
X1775241Y1141601D03*
Y1134908D03*
X1783941Y1151641D03*
X1775241D03*
Y1161680D03*
X1783941D03*
X1775241Y1148294D03*
Y1154987D03*
Y1158333D03*
Y1168373D03*
X1783941D03*
X1775241Y1175066D03*
X1783941D03*
X1775241Y1171719D03*
Y1165026D03*
Y1181759D03*
X1783941D03*
X1775241Y1188452D03*
X1783941D03*
X1775241Y1185105D03*
Y1178412D03*
Y1191798D03*
Y1198491D03*
X1783941D03*
X1775241Y1205184D03*
X1783941D03*
X1775241Y1208530D03*
Y1201837D03*
Y1195144D03*
Y1211877D03*
X1783941D03*
X1775241Y1218570D03*
X1783941D03*
X1775241Y1225263D03*
X1783941D03*
X1775241Y1235302D03*
X1783941D03*
X1775241Y1241995D03*
X1783941D03*
X1784188Y1257664D03*
X1775241Y1248688D03*
X1783941D03*
X1775241Y1258727D03*
X1788219Y1259312D03*
X1773390Y1262074D03*
X1773480Y1253692D03*
X1781088Y1273344D03*
X1778288D03*
X1775241Y1265420D03*
X1788360Y1264522D03*
X1791383Y766798D03*
X1800083D03*
X1791383Y770144D03*
Y773491D03*
X1800083D03*
X1791383Y780184D03*
X1800083D03*
X1791383Y776837D03*
Y786877D03*
Y783530D03*
Y790223D03*
X1800083D03*
X1791383Y796916D03*
X1800083D03*
X1791383Y803609D03*
X1800083D03*
X1791383Y800263D03*
Y793570D03*
Y810302D03*
X1800083D03*
X1791383Y816995D03*
X1800083D03*
X1791383Y827034D03*
X1800083D03*
Y833727D03*
X1791383D03*
Y840420D03*
X1800083D03*
X1791383Y847113D03*
X1800083D03*
X1791383Y850459D03*
Y843766D03*
Y853806D03*
X1800083D03*
X1791383Y863845D03*
X1800083D03*
X1791383Y867192D03*
Y860499D03*
Y857152D03*
Y870538D03*
X1800083D03*
X1791383Y877231D03*
X1800083D03*
X1791383Y883924D03*
X1800083D03*
X1791383Y873885D03*
Y880577D03*
Y890617D03*
X1800083D03*
X1791383Y900656D03*
X1800083D03*
X1791383Y887270D03*
Y897310D03*
Y893963D03*
Y907349D03*
X1800083D03*
X1791383Y914042D03*
X1800083D03*
X1791383Y917389D03*
Y910696D03*
Y904003D03*
Y920735D03*
X1800083D03*
X1791383Y927428D03*
X1800083D03*
X1791383Y924081D03*
Y934121D03*
Y930774D03*
Y937467D03*
X1800083D03*
X1791383Y944160D03*
X1800083D03*
X1791383Y947507D03*
Y940814D03*
X1800083Y950853D03*
X1791383D03*
Y960892D03*
X1800083D03*
X1791383Y957546D03*
Y954200D03*
Y967585D03*
X1800083D03*
X1791383Y974278D03*
X1800083D03*
X1791383Y980971D03*
X1800083D03*
X1791383Y977625D03*
Y970932D03*
Y987664D03*
X1800083D03*
X1791383Y991011D03*
Y984318D03*
Y994357D03*
Y1017782D03*
X1800083D03*
X1791383Y1027822D03*
X1800083D03*
X1791383Y1021129D03*
Y1024475D03*
Y1031168D03*
Y1034515D03*
X1800083D03*
X1791383Y1041207D03*
X1800083D03*
X1791383Y1047900D03*
X1800083D03*
X1791383Y1044554D03*
Y1037861D03*
Y1054593D03*
X1800083D03*
X1791383Y1061286D03*
X1800083D03*
X1791083Y1051247D03*
X1791383Y1067979D03*
X1800083D03*
X1791383Y1074672D03*
X1800083D03*
X1791383Y1071325D03*
Y1064633D03*
Y1078018D03*
Y1084711D03*
X1800083D03*
X1791383Y1091404D03*
X1800083D03*
X1791383Y1094751D03*
Y1088058D03*
Y1081365D03*
Y1098097D03*
X1800083D03*
X1791383Y1104790D03*
X1800083D03*
X1791383Y1111483D03*
X1800083D03*
X1791383Y1108136D03*
Y1101444D03*
Y1121522D03*
X1800083D03*
X1791383Y1128215D03*
X1800083D03*
X1791383Y1124869D03*
Y1118176D03*
Y1114829D03*
X1800083Y1134908D03*
X1791383D03*
Y1141601D03*
X1800083D03*
X1791383Y1144947D03*
Y1138255D03*
Y1131562D03*
Y1148294D03*
X1800083D03*
X1791383Y1158333D03*
X1800083D03*
X1791383Y1161680D03*
Y1154987D03*
Y1151640D03*
Y1165026D03*
X1800083D03*
X1791383Y1171719D03*
X1800083D03*
X1791383Y1175066D03*
Y1168373D03*
Y1178412D03*
X1800083D03*
X1791383Y1185105D03*
X1800083D03*
X1791383Y1181758D03*
Y1191798D03*
Y1188451D03*
Y1195144D03*
X1800083D03*
X1791383Y1201837D03*
X1800083D03*
X1791383Y1208530D03*
X1800083D03*
X1791383Y1205184D03*
Y1198491D03*
Y1215223D03*
X1800083D03*
X1791383Y1221916D03*
X1800083D03*
X1791383Y1231955D03*
X1800083D03*
X1791383Y1238648D03*
X1800083D03*
X1788373Y1241769D03*
X1791383Y1245341D03*
X1800083D03*
X1800427Y1248125D03*
X1803100Y1262074D03*
X1800019Y1252034D03*
X1791383Y1248688D03*
X1797088Y1273344D03*
X1794288D03*
X1791383Y1265420D03*
Y1262074D03*
X1804941Y770144D03*
X1813641D03*
X1804841Y766798D03*
X1804941Y776837D03*
X1813641D03*
X1804941Y783530D03*
X1813641D03*
X1804941Y793570D03*
X1813641D03*
X1804941Y800263D03*
X1813641D03*
X1804941Y806955D03*
X1813641D03*
X1804941Y813648D03*
X1813641D03*
X1804941Y820341D03*
X1813641D03*
X1804941Y830381D03*
X1813641D03*
X1804941Y843766D03*
X1813641D03*
X1804941Y837074D03*
X1813641D03*
X1804941Y850459D03*
X1813641D03*
X1804941Y857152D03*
X1813641D03*
Y867192D03*
X1804941D03*
Y873885D03*
X1813641D03*
X1804941Y880577D03*
X1813641D03*
X1804941Y887270D03*
X1813641D03*
X1804941Y893963D03*
X1813641D03*
X1804941Y904003D03*
X1813641D03*
X1804941Y910696D03*
X1813641D03*
X1804941Y917389D03*
X1813641D03*
X1804941Y924081D03*
X1813641D03*
X1804941Y930774D03*
X1813641D03*
X1804941Y940814D03*
X1813641D03*
X1804941Y947507D03*
X1813641D03*
X1804941Y954200D03*
X1813641D03*
X1804941Y964239D03*
X1813641D03*
X1804941Y970932D03*
X1813641D03*
X1804941Y977625D03*
X1813641D03*
X1804941Y984318D03*
X1813641D03*
X1804941Y991011D03*
X1813641D03*
X1804941Y1017782D03*
X1813641D03*
X1804941Y1024475D03*
X1813641D03*
X1804941Y1031168D03*
X1813641D03*
X1804941Y1037861D03*
X1813641D03*
X1804941Y1044554D03*
X1813641D03*
Y1057940D03*
X1804941D03*
Y1051247D03*
X1813641D03*
X1804941Y1054593D03*
Y1064633D03*
X1813641D03*
Y1071326D03*
X1804941D03*
X1813641Y1078018D03*
X1804941D03*
X1813641Y1088058D03*
X1804941D03*
X1813641Y1094751D03*
X1804941D03*
X1813641Y1101444D03*
X1804941D03*
X1813641Y1108137D03*
X1804941D03*
X1813641Y1114829D03*
X1804941D03*
X1813641Y1124869D03*
X1804941D03*
X1813641Y1131562D03*
X1804941D03*
X1813641Y1138255D03*
X1804941D03*
X1813641Y1144948D03*
X1804941D03*
X1813641Y1151641D03*
X1804941D03*
X1813641Y1161680D03*
X1804941D03*
X1813641Y1168373D03*
X1804941D03*
X1813641Y1175066D03*
X1804941D03*
X1813641Y1181759D03*
X1804941D03*
X1813641Y1188452D03*
X1804941D03*
X1813641Y1198491D03*
X1804941D03*
X1813641Y1205184D03*
X1804941D03*
X1813641Y1211877D03*
X1804941D03*
X1813641Y1218570D03*
X1804941D03*
X1813641Y1225263D03*
X1804941D03*
X1813641Y1235302D03*
X1804941D03*
X1813641Y1241995D03*
X1804941D03*
X1815063Y1233103D03*
X1813641Y1248688D03*
X1804941D03*
X1819054Y1253986D03*
X1804941Y1258727D03*
X1813814Y1254693D03*
X1818188Y1273044D03*
X1810788Y1273344D03*
X1807988D03*
X1815388Y1273044D03*
X1804941Y1265420D03*
X1829783Y766798D03*
X1821083D03*
X1829783Y773491D03*
X1821083D03*
X1829783Y780184D03*
X1821083D03*
X1829783Y790223D03*
X1821083D03*
X1829783Y796916D03*
X1821083D03*
X1829783Y803609D03*
X1821083D03*
X1829783Y810302D03*
X1821083D03*
X1829783Y816995D03*
X1821083D03*
X1829783Y827034D03*
X1821083D03*
X1829783Y833727D03*
X1821083D03*
Y847113D03*
X1829783D03*
Y840420D03*
X1821083D03*
X1829783Y853806D03*
X1821083D03*
X1829783Y863845D03*
X1821083D03*
X1829783Y870538D03*
X1821083D03*
X1829783Y877231D03*
X1821083D03*
X1829783Y883924D03*
X1821083D03*
X1829783Y890617D03*
X1821083D03*
X1829783Y900656D03*
X1821083D03*
X1829783Y907349D03*
X1821083D03*
X1829783Y914042D03*
X1821083D03*
X1829783Y920735D03*
X1821083D03*
X1829783Y927428D03*
X1821083D03*
X1829783Y937467D03*
X1821083D03*
X1829783Y944160D03*
X1821083D03*
X1829783Y950853D03*
X1821083D03*
X1829783Y960892D03*
X1821083D03*
X1820983Y957546D03*
Y954200D03*
X1829783Y967585D03*
X1821083D03*
X1829783Y974278D03*
X1821083D03*
X1829783Y980971D03*
X1821083D03*
X1829783Y987664D03*
X1821083D03*
X1820983Y994357D03*
X1829783Y1017782D03*
X1821083D03*
X1829783Y1027822D03*
X1821083D03*
Y1021129D03*
Y1024475D03*
X1829783Y1034515D03*
X1821083D03*
X1829783Y1041207D03*
X1821083D03*
X1829783Y1047900D03*
X1821083D03*
X1829783Y1054593D03*
X1821083D03*
X1829783Y1061286D03*
X1821083D03*
Y1051247D03*
X1829783Y1067979D03*
X1821083D03*
Y1074672D03*
X1829783D03*
X1821083Y1084711D03*
X1829783D03*
X1821083Y1091404D03*
X1829783D03*
X1821083Y1098097D03*
X1829783D03*
X1821083Y1104790D03*
X1829783D03*
X1821083Y1111483D03*
X1829783D03*
X1821083Y1121522D03*
X1829783D03*
X1821083Y1128215D03*
X1829783D03*
X1821083Y1134908D03*
X1829783D03*
X1821083Y1141601D03*
X1829783D03*
X1821083Y1148294D03*
X1829783D03*
X1821083Y1158333D03*
X1829783D03*
X1821083Y1165026D03*
X1829783D03*
X1821083Y1171719D03*
X1829783D03*
X1821083Y1178412D03*
X1829783D03*
X1821083Y1185105D03*
X1829783D03*
X1821083Y1195144D03*
X1829783D03*
X1821083Y1201837D03*
X1829783D03*
X1821083Y1208530D03*
X1829783D03*
X1821083Y1215223D03*
X1829783D03*
X1821083Y1221916D03*
X1829783D03*
X1821083Y1231955D03*
X1829783D03*
X1821083Y1238648D03*
X1829783D03*
Y1245341D03*
X1821083D03*
X1830379Y1250358D03*
X1829920Y1258322D03*
X1821139Y1248155D03*
X1821083Y1262074D03*
Y1265420D03*
X1829940Y1263662D03*
G54D28*
X159474Y1320753D03*
X183847Y1320778D03*
X208247D03*
X275289Y575702D03*
Y599861D03*
Y624015D03*
Y648169D03*
X278126Y676260D03*
Y700414D03*
X395771Y1242785D03*
X420171D03*
X444493D03*
X468893D03*
X493293D03*
X673093Y1320778D03*
X697466Y1320803D03*
X721866D03*
X1100800Y251488D03*
X1100700Y275788D03*
X1131100Y1357088D03*
X1155500D03*
X1179900D03*
X1371912Y1242785D03*
X1396312D03*
X1420634D03*
X1445034D03*
X1469434D03*
X1577000Y591888D03*
Y616388D03*
Y640888D03*
Y665288D03*
Y689788D03*
Y714288D03*
X1634259Y1354374D03*
X1658632Y1354399D03*
X1683032D03*
G54D48*
X705760Y-26500D03*
Y-16500D03*
D03*
Y-6500D03*
X730760Y-26500D03*
Y-16500D03*
D03*
Y-6500D03*
X822720Y3500D03*
Y13500D03*
D03*
Y23500D03*
X847720Y3500D03*
Y13500D03*
D03*
Y23500D03*
X973180Y-26500D03*
Y-16500D03*
D03*
Y-6500D03*
Y3500D03*
Y13500D03*
Y23500D03*
Y13500D03*
X998180Y-26500D03*
Y-16500D03*
D03*
Y-6500D03*
Y3500D03*
Y13500D03*
Y23500D03*
Y13500D03*
X1015152Y-26511D03*
Y-36511D03*
Y-26511D03*
Y-16511D03*
D03*
Y-6511D03*
D03*
Y3489D03*
D03*
Y13489D03*
D03*
Y23489D03*
X1040152Y-26511D03*
Y-36511D03*
Y-26511D03*
Y-16511D03*
D03*
Y-6511D03*
D03*
Y3489D03*
D03*
Y13489D03*
D03*
Y23489D03*
X1282572Y-36511D03*
Y-26511D03*
D03*
Y-16511D03*
D03*
Y-6511D03*
Y3489D03*
Y-6511D03*
Y3489D03*
Y13489D03*
Y23489D03*
Y13489D03*
X1307572Y-36511D03*
Y-26511D03*
D03*
Y-16511D03*
D03*
Y-6511D03*
Y3489D03*
Y-6511D03*
Y3489D03*
Y13489D03*
Y23489D03*
Y13489D03*
X1324471Y-26511D03*
Y-36511D03*
Y-26511D03*
Y-16511D03*
D03*
Y-6511D03*
D03*
Y3489D03*
D03*
Y13489D03*
D03*
Y23489D03*
X1349471Y-26511D03*
Y-36511D03*
Y-26511D03*
Y-16511D03*
D03*
Y-6511D03*
D03*
Y3489D03*
D03*
Y13489D03*
D03*
Y23489D03*
X1474931Y-36511D03*
Y-26511D03*
D03*
Y-16511D03*
D03*
Y-6511D03*
Y3489D03*
Y-6511D03*
Y3489D03*
Y13489D03*
Y23489D03*
Y13489D03*
X1499931Y-36511D03*
Y-26511D03*
D03*
Y-16511D03*
D03*
Y-6511D03*
Y3489D03*
Y-6511D03*
Y3489D03*
Y13489D03*
Y23489D03*
Y13489D03*
X1565236Y184783D03*
Y264035D03*
G54D21*
X57646Y12480D03*
X137272D03*
X186622D03*
X266858D03*
X315598D03*
X502528Y33268D03*
X582154D03*
X631504D03*
X711740D03*
X760480D03*
X1156378Y133866D03*
X1532055Y12480D03*
X1611681D03*
X1661031D03*
X1741267D03*
X1790007D03*
G54D25*
X73865Y763164D03*
X79451Y699517D03*
X102384Y505374D03*
X108909Y654926D03*
X102909Y648926D03*
Y642926D03*
Y655102D03*
X108909Y642926D03*
X114909Y654926D03*
Y648926D03*
Y642926D03*
X151277Y1339183D03*
X153877D03*
X156417Y1336343D03*
X151217Y1336393D03*
X153817D03*
X156417Y1333843D03*
X151217Y1333893D03*
X153817D03*
X151277Y1346883D03*
X153877D03*
X151277Y1349383D03*
X153877D03*
X156477Y1344383D03*
X151277D03*
X153877D03*
X156477Y1341883D03*
X151277D03*
X153877D03*
X157490Y1421454D03*
X154990D03*
X157530Y1432124D03*
X155030D03*
X157530Y1424124D03*
X155030D03*
X157530Y1429124D03*
X155030Y1426624D03*
Y1429124D03*
X157530Y1426624D03*
Y1435124D03*
X155030D03*
X157530Y1437754D03*
X155030D03*
X170877Y1333783D03*
Y1336383D03*
X170907Y1339233D03*
X170877Y1341883D03*
X160490Y1421454D03*
X160530Y1432124D03*
Y1424124D03*
Y1429124D03*
Y1426624D03*
Y1435124D03*
Y1437754D03*
X165500Y1440362D03*
X189377Y1333783D03*
Y1336383D03*
X191977D03*
X191947Y1339263D03*
X189347D03*
X189377Y1349383D03*
X191977D03*
X189377Y1346883D03*
X191977D03*
Y1344383D03*
X189377D03*
X191977Y1341883D03*
X189377D03*
X194858Y684348D03*
X208977Y1336383D03*
Y1333783D03*
X194577Y1336383D03*
X209007Y1339263D03*
X194547D03*
X208977Y1341883D03*
X194577Y1344383D03*
Y1341883D03*
X285357Y105003D03*
X288557D03*
X280857Y107303D03*
X285857Y115603D03*
X282857D03*
X280857Y109903D03*
X284482Y566022D03*
X286582Y637809D03*
Y634283D03*
X301183Y107103D03*
Y110003D03*
Y112803D03*
X311057Y107103D03*
Y110003D03*
Y112803D03*
X320578Y1290197D03*
X323028Y1297967D03*
X320428D03*
Y1295467D03*
X323028D03*
Y1292967D03*
X320428D03*
X339148Y1269717D03*
X339088Y1272287D03*
X339028Y1274887D03*
X325688Y1290167D03*
X325718Y1287587D03*
X328078Y1288747D03*
X323178Y1290197D03*
X323208Y1287617D03*
X328168Y1280967D03*
X325748Y1284987D03*
X328108Y1286147D03*
X328138Y1283567D03*
X328018Y1291317D03*
X339035Y1280218D03*
X339040Y1277594D03*
X328065Y1299248D03*
X325538Y1297937D03*
Y1292937D03*
Y1295437D03*
X328058Y1293917D03*
X328070Y1296624D03*
X331515Y1326704D03*
X344258Y1267117D03*
X341748Y1267147D03*
X355036Y1272433D03*
Y1269933D03*
X355378Y1262027D03*
X355318Y1264597D03*
X355258Y1267197D03*
X355036Y1274933D03*
X341605Y1280248D03*
X344115Y1280218D03*
X355048Y1277440D03*
X355025Y1280248D03*
X352713Y1399336D03*
X355513Y1402306D03*
X352513D03*
X349513D03*
X355325Y1405386D03*
X349463Y1405286D03*
X352463D03*
X355325Y1408386D03*
X352401Y1414432D03*
X355325Y1414386D03*
Y1417386D03*
X352401Y1411432D03*
X355325Y1411386D03*
X352401Y1408432D03*
X349123Y1411376D03*
X349323Y1408406D03*
X349073Y1414356D03*
X352231Y1417332D03*
X348903Y1417256D03*
X371578Y1248967D03*
X371458Y1254137D03*
X371330Y1256687D03*
X371518Y1251537D03*
X371278Y1259257D03*
X360198Y1269777D03*
X357546Y1272403D03*
Y1269903D03*
X360138Y1272347D03*
X357828Y1264567D03*
X357888Y1261997D03*
X360378Y1264627D03*
X360438Y1262057D03*
X357768Y1267167D03*
X360318Y1267227D03*
X357546Y1274903D03*
X360128Y1274957D03*
X371218Y1261857D03*
X371225Y1267188D03*
X371230Y1264564D03*
X357558Y1277410D03*
X357535Y1280218D03*
X360120Y1277654D03*
X355713Y1399336D03*
X361703Y1399386D03*
X364703D03*
X367703D03*
X370703D03*
X358703Y1402386D03*
X361703D03*
X364703D03*
X367703D03*
X370703D03*
X358713Y1399336D03*
X358573Y1405336D03*
X361573D03*
X364573D03*
X367573D03*
X370573D03*
X358703Y1414606D03*
X361703D03*
X364703D03*
X361703Y1417386D03*
X358703D03*
X364703D03*
X367703D03*
Y1414606D03*
X358217Y1411405D03*
X370517Y1414615D03*
X370717Y1417405D03*
X357917Y1408205D03*
X376638Y1248997D03*
X374088Y1248937D03*
X374028Y1251507D03*
X376518Y1254167D03*
X376578Y1251567D03*
X373968Y1254107D03*
X387478Y1248967D03*
X387358Y1254137D03*
X387117Y1256851D03*
X387418Y1251537D03*
X387117Y1259351D03*
X376285Y1267218D03*
X373735Y1267158D03*
X387117Y1261851D03*
X387129Y1264358D03*
X387125Y1267188D03*
X376825Y1399386D03*
X379825D03*
X373703D03*
X379825Y1402386D03*
X376825D03*
X373703D03*
X376825Y1405386D03*
X379825D03*
X373573Y1405336D03*
X374027Y1411365D03*
X373703Y1414606D03*
X376825Y1414386D03*
X379825D03*
X376825Y1417386D03*
Y1411386D03*
X379825D03*
X373703Y1417386D03*
X376825Y1408386D03*
X379825D03*
X374307Y1408135D03*
X403738Y1249027D03*
X403618Y1254197D03*
X403498Y1256747D03*
X403678Y1251597D03*
X392538Y1248997D03*
X389928Y1251507D03*
X389988Y1248937D03*
X389868Y1254107D03*
X392298Y1256717D03*
X392418Y1254167D03*
X389627Y1256821D03*
X392478Y1251567D03*
X392238Y1259287D03*
X389627Y1259321D03*
X403438Y1259317D03*
X392220Y1264594D03*
X392228Y1261897D03*
X389627Y1261821D03*
X389639Y1264328D03*
X389635Y1267158D03*
X392185Y1267218D03*
X403385Y1267248D03*
X403378Y1261917D03*
X403390Y1264624D03*
X406248Y1248997D03*
X408798Y1249057D03*
X406128Y1254167D03*
X408678Y1254227D03*
X406188Y1251567D03*
X419638Y1248967D03*
X419295Y1256851D03*
X419518Y1254137D03*
X419578Y1251537D03*
X419295Y1259351D03*
X408738Y1251627D03*
X419295Y1261851D03*
X419307Y1264358D03*
X419285Y1267188D03*
X405895Y1267218D03*
X408445Y1267278D03*
X422148Y1248937D03*
X424698Y1248997D03*
X422088Y1251507D03*
X421805Y1256821D03*
X422028Y1254107D03*
X424458Y1256717D03*
X424578Y1254167D03*
X424638Y1251567D03*
X421805Y1259321D03*
X424398Y1259287D03*
X436068Y1248967D03*
X435828Y1256687D03*
X435948Y1254137D03*
X436008Y1251537D03*
X435768Y1259257D03*
X421805Y1261821D03*
X421817Y1264328D03*
X421795Y1267158D03*
X424345Y1267218D03*
X424380Y1264594D03*
X424388Y1261897D03*
X435715Y1267188D03*
X435720Y1264564D03*
X435708Y1261857D03*
X448276Y1170069D03*
X445776D03*
X443276D03*
X441128Y1248997D03*
X438578Y1248937D03*
X438518Y1251507D03*
X441008Y1254167D03*
X438458Y1254107D03*
X441068Y1251567D03*
X451642Y1256851D03*
X451878Y1254107D03*
X451642Y1259351D03*
X451938Y1251507D03*
X451998Y1248937D03*
X438225Y1267158D03*
X440775Y1267218D03*
X451642Y1261851D03*
X451654Y1264358D03*
X451645Y1267158D03*
X456818Y1256687D03*
X454388Y1254077D03*
X454152Y1256821D03*
X456998Y1251537D03*
X456758Y1259257D03*
X454152Y1259321D03*
X468258Y1249107D03*
X468018Y1256827D03*
X468138Y1254277D03*
X468198Y1251677D03*
X467958Y1259397D03*
X457058Y1248967D03*
X454508Y1248907D03*
X454448Y1251477D03*
X456938Y1254137D03*
X456705Y1267188D03*
X454155Y1267128D03*
X456748Y1261867D03*
X456740Y1264564D03*
X454152Y1261821D03*
X454164Y1264328D03*
X467905Y1267328D03*
X467910Y1264704D03*
X467898Y1261997D03*
X458441Y1414893D03*
X456619Y1431189D03*
X473318Y1249137D03*
X470768Y1249077D03*
X473198Y1254307D03*
X470648Y1254247D03*
X473258Y1251707D03*
X470708Y1251647D03*
X484098Y1248997D03*
X483819Y1256851D03*
X483978Y1254167D03*
X484038Y1251567D03*
X483819Y1259351D03*
X472965Y1267358D03*
X470415Y1267298D03*
X483819Y1261851D03*
X483831Y1264358D03*
X483745Y1267218D03*
X486608Y1248967D03*
X489158Y1249027D03*
X486329Y1256821D03*
X486488Y1254137D03*
X488918Y1256747D03*
X489038Y1254197D03*
X486548Y1251537D03*
X489098Y1251597D03*
X486329Y1259321D03*
X488858Y1259317D03*
X500228Y1259237D03*
X486329Y1261821D03*
X486341Y1264328D03*
X488840Y1264624D03*
X488848Y1261927D03*
X488805Y1267248D03*
X486255Y1267188D03*
X500138Y1269637D03*
X500150Y1272344D03*
X500198Y1267037D03*
Y1264467D03*
X500168Y1261807D03*
X500150Y1275224D03*
X505398Y1259377D03*
X502858Y1259257D03*
X502718Y1271417D03*
X505218Y1271447D03*
X505290Y1267254D03*
X505338Y1261947D03*
X505278Y1264547D03*
X502750Y1267134D03*
X502798Y1261827D03*
X502738Y1264427D03*
X502718Y1274114D03*
X505218Y1274144D03*
X515898Y1271447D03*
X515950Y1274144D03*
X502718Y1276994D03*
X505218Y1277024D03*
X515950D03*
X521118Y1273097D03*
X518488Y1271477D03*
X521058Y1275667D03*
X518490Y1274144D03*
X521058Y1278277D03*
X521020Y1280974D03*
X518490Y1277024D03*
X530398Y1288557D03*
X530548Y1283377D03*
X530428Y1285947D03*
X530410Y1291254D03*
X532558Y1289967D03*
X532618Y1287367D03*
X532678Y1284797D03*
X530450Y1294134D03*
X532570Y1295554D03*
Y1292674D03*
X524892Y1341462D03*
X522818Y1342930D03*
X537648Y1290037D03*
X535058Y1290007D03*
X535148Y1287397D03*
X535110Y1292704D03*
Y1295584D03*
X537650Y1292704D03*
X540210D03*
X537650Y1295584D03*
X540210D03*
X670037Y1336396D03*
X664987D03*
X667487D03*
X664987Y1338896D03*
X667487D03*
X670037D03*
Y1333896D03*
X664987D03*
X667487D03*
X664987Y1343896D03*
Y1341396D03*
X667487D03*
Y1343896D03*
X670037Y1341396D03*
Y1343896D03*
X674149Y1434149D03*
X671149D03*
X668649D03*
X674149Y1426149D03*
Y1431149D03*
Y1428649D03*
X671149Y1426149D03*
X668649D03*
X671149Y1431149D03*
X668649Y1428649D03*
Y1431149D03*
X671149Y1428649D03*
X677319Y1428359D03*
Y1433359D03*
Y1430859D03*
X671112Y1639962D03*
X681899Y1434049D03*
Y1426049D03*
Y1431049D03*
Y1428549D03*
X697122Y1632667D03*
X683592Y1634844D03*
X697197Y1644667D03*
X712733Y117488D03*
Y114588D03*
X708137Y1336396D03*
Y1338896D03*
X703087Y1336396D03*
X705587D03*
Y1338896D03*
X703087D03*
X708137Y1333896D03*
X705587D03*
X703087D03*
X708137Y1341396D03*
Y1343896D03*
X705587Y1341396D03*
X703087D03*
Y1343896D03*
X705587D03*
X715933Y117488D03*
Y114588D03*
X728733Y132088D03*
Y129288D03*
X720433Y135088D03*
X717433D03*
X728733Y126388D03*
X719933Y124488D03*
X723133D03*
X745725Y167537D03*
X744800Y1664840D03*
X989910Y-27961D03*
X989925Y-25446D03*
X983632Y-26655D03*
X989925Y-21572D03*
X983632Y-16626D03*
X989910Y-17932D03*
X989925Y-15417D03*
Y-11543D03*
X989910Y-7903D03*
X989925Y-5388D03*
X983632Y-6597D03*
X989925Y4641D03*
X989910Y2126D03*
X983632Y3432D03*
X989925Y14670D03*
X989910Y12155D03*
X989925Y8515D03*
X983632Y13461D03*
X989925Y19044D03*
X983632Y23990D03*
X978012Y276436D03*
X975512Y282096D03*
X978012D03*
X975512Y279266D03*
X978012D03*
X979940Y292262D03*
Y289762D03*
X975512Y294996D03*
X978012D03*
X979940Y284762D03*
Y287262D03*
X1077973Y246362D03*
X1083973D03*
X1080973D03*
X1077883Y260842D03*
X1076823Y265438D03*
X1083823D03*
X1083883Y260842D03*
X1080883D03*
X1080323Y265438D03*
X1082853Y269492D03*
X1079853D03*
X1075400Y273762D03*
X1078400D03*
X1081400D03*
X1084400D03*
X1087400D03*
X1076018Y289400D03*
X1079018D03*
X1082018D03*
X1085018D03*
X1088018D03*
X1127179Y1372700D03*
X1124679D03*
Y1370200D03*
X1127179D03*
X1129729Y1372700D03*
Y1370200D03*
Y1375200D03*
X1127179D03*
X1124679D03*
X1129729Y1377700D03*
Y1380200D03*
Y1382700D03*
X1127179D03*
X1124679D03*
X1127179Y1380200D03*
Y1377700D03*
X1124679D03*
Y1380200D03*
X1141591Y1462853D03*
Y1465353D03*
Y1468353D03*
Y1471353D03*
Y1460353D03*
X1165279Y1372700D03*
X1162779D03*
X1167829D03*
X1162779Y1370200D03*
X1165279D03*
X1167829D03*
X1162779Y1375200D03*
X1165279D03*
X1167829D03*
Y1377700D03*
Y1380200D03*
Y1382700D03*
X1165279D03*
X1162779D03*
X1165279Y1380200D03*
X1162779D03*
Y1377700D03*
X1165279D03*
X1201110Y1681767D03*
X1279788Y1304042D03*
X1293024Y-36695D03*
Y-26666D03*
Y-16637D03*
Y-6608D03*
Y3421D03*
Y13450D03*
Y23979D03*
X1296719Y1290197D03*
X1299169Y1295467D03*
Y1297967D03*
X1296569D03*
Y1295467D03*
Y1292967D03*
X1299169D03*
X1296581Y1300474D03*
X1299181D03*
X1296576Y1303298D03*
X1299176D03*
X1299317Y-35486D03*
Y-31612D03*
X1299302Y-38001D03*
Y-27972D03*
X1299317Y-25457D03*
Y-21583D03*
X1299302Y-17943D03*
X1299317Y-15428D03*
Y-11554D03*
X1299302Y-7914D03*
X1299317Y-5399D03*
Y4630D03*
X1299302Y2115D03*
X1299317Y-1525D03*
Y14659D03*
X1299302Y12144D03*
X1299317Y8504D03*
Y19033D03*
X1315169Y1274887D03*
X1315289Y1269717D03*
X1315229Y1272287D03*
X1304149Y1291317D03*
X1301889Y1284987D03*
X1301829Y1290167D03*
X1301859Y1287587D03*
X1304299Y1280967D03*
X1304269Y1283567D03*
X1304239Y1286147D03*
X1304209Y1288747D03*
X1315176Y1280218D03*
X1315181Y1277594D03*
X1299319Y1290197D03*
X1299349Y1287617D03*
X1301686Y1303268D03*
X1304196Y1299248D03*
X1304189Y1293917D03*
X1304201Y1296624D03*
X1301679Y1292937D03*
Y1295437D03*
Y1297937D03*
X1301691Y1300444D03*
X1307656Y1326704D03*
X1331519Y1262027D03*
X1331459Y1264597D03*
X1331399Y1267197D03*
X1317889Y1267147D03*
X1320399Y1267117D03*
X1331177Y1269933D03*
Y1272433D03*
Y1274933D03*
X1331166Y1280248D03*
X1317746D03*
X1320256Y1280218D03*
X1331189Y1277440D03*
X1331304Y1401986D03*
Y1404986D03*
X1327926D03*
X1322228Y1419890D03*
X1322186Y1411326D03*
Y1414326D03*
Y1417326D03*
X1325084Y1420066D03*
X1325042Y1408502D03*
Y1411502D03*
Y1417502D03*
Y1414502D03*
X1331344Y1414456D03*
X1330804Y1411536D03*
Y1408536D03*
X1331386Y1420020D03*
X1328008D03*
X1331344Y1417456D03*
X1327966Y1408456D03*
Y1411456D03*
Y1417456D03*
Y1414456D03*
X1322312Y1425018D03*
X1325168Y1425194D03*
X1328092Y1425148D03*
X1331470D03*
X1347419Y1259257D03*
X1347379Y1256687D03*
X1336269Y1274957D03*
X1333969Y1264567D03*
X1334029Y1261997D03*
X1333909Y1267167D03*
X1336339Y1269777D03*
X1336279Y1272347D03*
X1347359Y1261857D03*
X1347371Y1264564D03*
X1336519Y1264627D03*
X1336579Y1262057D03*
X1347366Y1267188D03*
X1336459Y1267227D03*
X1333687Y1269903D03*
Y1272403D03*
Y1274903D03*
X1333676Y1280218D03*
X1336261Y1277654D03*
X1333699Y1277410D03*
X1346304Y1401986D03*
X1343304D03*
X1340304D03*
X1337304D03*
X1334304D03*
Y1404986D03*
X1346304D03*
X1343304D03*
X1340304D03*
X1337304D03*
X1337344Y1414456D03*
X1346344D03*
X1343344D03*
X1340344D03*
X1346534Y1411496D03*
Y1408496D03*
X1334344Y1414456D03*
X1346344Y1417456D03*
X1340344D03*
X1337344D03*
X1334386Y1420020D03*
X1334344Y1417456D03*
X1346386Y1420020D03*
X1343386D03*
X1340386D03*
X1337386D03*
X1343344Y1417456D03*
X1337428Y1422584D03*
X1340428D03*
X1343428D03*
X1334428D03*
X1337328Y1425164D03*
X1340328D03*
X1343328D03*
X1346178Y1425254D03*
X1346278Y1422674D03*
X1334470Y1425148D03*
X1363258Y1256851D03*
Y1259351D03*
X1349876Y1267158D03*
X1352426Y1267218D03*
X1363266Y1267188D03*
X1363258Y1261851D03*
X1363270Y1264358D03*
X1349426Y1401986D03*
Y1404986D03*
X1349508Y1420020D03*
X1349466Y1411456D03*
Y1408456D03*
Y1417456D03*
Y1414456D03*
X1349278Y1422674D03*
X1379579Y1259317D03*
X1368379Y1259287D03*
X1379639Y1256747D03*
X1368439Y1256717D03*
X1365768Y1256821D03*
Y1259321D03*
X1365776Y1267158D03*
X1368326Y1267218D03*
X1379519Y1261917D03*
X1379531Y1264624D03*
X1379526Y1267248D03*
X1368361Y1264594D03*
X1368369Y1261897D03*
X1365768Y1261821D03*
X1365780Y1264328D03*
X1396081Y1153369D03*
X1395436Y1256851D03*
Y1259351D03*
X1384586Y1267278D03*
X1395426Y1267188D03*
X1382036Y1267218D03*
X1395436Y1261851D03*
X1395448Y1264358D03*
X1398831Y1153369D03*
X1411909Y1259257D03*
X1400599Y1256717D03*
X1411969Y1256687D03*
X1397946Y1256821D03*
Y1259321D03*
X1400539Y1259287D03*
X1400521Y1264594D03*
X1400529Y1261897D03*
X1397936Y1267158D03*
X1400486Y1267218D03*
X1411849Y1261857D03*
X1411861Y1264564D03*
X1411856Y1267188D03*
X1397946Y1261821D03*
X1397958Y1264328D03*
X1424119Y1161520D03*
X1426619D03*
X1424119Y1153369D03*
X1426619D03*
Y1169570D03*
X1424119D03*
X1427783Y1256851D03*
Y1259351D03*
X1414366Y1267158D03*
X1416916Y1267218D03*
X1427786Y1267158D03*
X1427783Y1261851D03*
X1427795Y1264358D03*
X1444099Y1259397D03*
X1432899Y1259257D03*
X1444159Y1256827D03*
X1432959Y1256687D03*
X1430293Y1256821D03*
Y1259321D03*
X1444051Y1264704D03*
X1444039Y1261997D03*
X1444046Y1267328D03*
X1432889Y1261867D03*
X1432881Y1264564D03*
X1432846Y1267188D03*
X1430296Y1267128D03*
X1430293Y1261821D03*
X1430305Y1264328D03*
X1433750Y1429208D03*
X1447299Y1153369D03*
X1449799D03*
X1459960Y1259351D03*
Y1256851D03*
X1449106Y1267358D03*
X1459886Y1267218D03*
X1446556Y1267298D03*
X1459960Y1261851D03*
X1459972Y1264358D03*
X1464999Y1259317D03*
X1476369Y1259237D03*
X1465059Y1256747D03*
X1462470Y1259321D03*
Y1256821D03*
X1476291Y1275224D03*
X1464946Y1267248D03*
X1464989Y1261927D03*
X1464981Y1264624D03*
X1476339Y1264467D03*
Y1267037D03*
X1476309Y1261807D03*
X1476279Y1269637D03*
X1476291Y1272344D03*
X1462396Y1267188D03*
X1462470Y1261821D03*
X1462482Y1264328D03*
X1491661Y-27972D03*
X1491676Y-25457D03*
X1485383Y-26666D03*
X1491661Y-38001D03*
X1491676Y-35486D03*
Y-31612D03*
X1485383Y-36695D03*
X1491661Y-17943D03*
X1491676Y-15428D03*
Y-11554D03*
X1485383Y-16637D03*
X1491676Y-21583D03*
X1485383Y3421D03*
X1491661Y2115D03*
X1491676Y4630D03*
X1491661Y-7914D03*
X1491676Y-5399D03*
Y-1525D03*
X1485383Y-6608D03*
X1491676Y14659D03*
X1491661Y12144D03*
X1485383Y13450D03*
X1491676Y8504D03*
Y19033D03*
X1485383Y23979D03*
X1481539Y1259377D03*
X1478999Y1259257D03*
X1481479Y1261947D03*
X1481419Y1264547D03*
X1481431Y1267254D03*
X1478939Y1261827D03*
X1478879Y1264427D03*
X1478891Y1267134D03*
X1481359Y1271447D03*
X1492039D03*
X1481359Y1274144D03*
X1492091D03*
X1478859Y1271417D03*
Y1274114D03*
X1481359Y1277024D03*
X1492091D03*
X1478859Y1276994D03*
X1497199Y1275667D03*
X1497259Y1273097D03*
X1494629Y1271477D03*
X1494631Y1274144D03*
X1506569Y1285947D03*
X1508819Y1284797D03*
X1506539Y1288557D03*
X1508759Y1287367D03*
X1508699Y1289967D03*
X1494631Y1277024D03*
X1506551Y1291254D03*
X1497199Y1278277D03*
X1497161Y1280974D03*
X1506689Y1283377D03*
X1506591Y1294134D03*
X1508711Y1295554D03*
Y1292674D03*
X1501033Y1341462D03*
X1498959Y1342930D03*
X1513789Y1290037D03*
X1511289Y1287397D03*
X1511199Y1290007D03*
X1513791Y1292704D03*
X1516351D03*
X1513791Y1295584D03*
X1516351D03*
X1511251Y1292704D03*
Y1295584D03*
X1588314Y592553D03*
X1585714D03*
X1583114D03*
X1590914D03*
X1588254Y595103D03*
X1588284Y597613D03*
X1585654Y595103D03*
X1585684Y597613D03*
X1583084D03*
X1583054Y595103D03*
X1588284Y608655D03*
X1585684D03*
X1583084D03*
X1590854Y595103D03*
X1590884Y597613D03*
Y608655D03*
X1588254Y613715D03*
X1588224Y611205D03*
X1585654Y613715D03*
X1585624Y611205D03*
X1583024D03*
X1583054Y613715D03*
X1590854D03*
X1590824Y611205D03*
X1593514Y592553D03*
X1593484Y597613D03*
X1593454Y595103D03*
X1593484Y608655D03*
X1593424Y611205D03*
X1593454Y613715D03*
X1619980Y615201D03*
X1635315Y1465745D03*
Y1462745D03*
X1632315Y1468745D03*
X1629815D03*
X1632315Y1465745D03*
X1629815D03*
X1632315Y1462745D03*
X1629815D03*
X1635315Y1468745D03*
Y1460245D03*
X1629815D03*
X1632315D03*
X1629815Y1457745D03*
X1632315D03*
X1635315D03*
X1639645Y1473645D03*
X1649149Y607022D03*
X1653929Y604546D03*
X1649139Y604576D03*
X1653736Y607033D03*
X1649117Y602139D03*
X1653930Y602099D03*
X1643065Y1462645D03*
Y1465645D03*
Y1468645D03*
Y1460145D03*
Y1457645D03*
X1642645Y1473645D03*
X1659458Y671149D03*
X1658085Y673511D03*
X1659458Y705149D03*
X1658085Y707511D03*
X1698725Y217409D03*
X1696225D03*
X1698725Y219909D03*
X1696225D03*
X1700852Y639381D03*
X1698232Y639440D03*
X1700852Y647341D03*
Y649941D03*
Y652541D03*
Y644741D03*
X1698232Y644800D03*
Y647400D03*
Y650000D03*
Y652600D03*
X1700852Y641981D03*
X1698232Y642040D03*
X1757978Y116727D03*
X1760978D03*
X1763678Y106127D03*
X1769278Y108027D03*
Y110927D03*
Y113727D03*
X1755978Y108427D03*
Y111027D03*
X1760478Y106127D03*
X1784178Y108227D03*
Y111127D03*
Y113927D03*
X1778165Y1307422D03*
Y1304422D03*
X1784165Y1307422D03*
X1781165D03*
X1778165Y1310422D03*
X1784165D03*
X1781165D03*
X1825762Y167662D03*
X1846691Y166450D03*
G54D27*
X69809Y1333918D03*
Y1331418D03*
Y1336418D03*
X72809Y1333918D03*
Y1331418D03*
Y1336418D03*
X75809Y1333918D03*
Y1331418D03*
Y1336418D03*
X72909Y1339938D03*
X79009Y1340238D03*
X75909Y1339938D03*
X73027Y1347925D03*
X73059Y1345138D03*
X72987Y1342535D03*
X75909Y1342438D03*
X79009Y1342738D03*
Y1345238D03*
X78977Y1348025D03*
X75859Y1348138D03*
Y1345138D03*
X87565Y670441D03*
X94473Y698926D03*
X94209Y1337738D03*
X81809Y1340238D03*
X84809D03*
X87809D03*
X90809D03*
X94209D03*
X84809Y1345238D03*
X81809Y1342738D03*
X84809D03*
X81809Y1348238D03*
Y1345238D03*
X84809Y1348238D03*
X87809D03*
Y1345238D03*
Y1342738D03*
X94209D03*
Y1348238D03*
Y1345238D03*
X90809Y1348238D03*
Y1345238D03*
Y1342738D03*
X96809Y1340238D03*
Y1345238D03*
Y1348238D03*
Y1342738D03*
X127313Y649765D03*
X114021Y669409D03*
X118021D03*
X127738Y659226D03*
X130067Y650213D03*
X134205Y643603D03*
X128193Y662015D03*
X128275Y665515D03*
X176393Y575189D03*
X173793D03*
X176393Y572689D03*
X173793D03*
X171293D03*
Y575189D03*
X173793Y577790D03*
X171293D03*
X176393D03*
X186793Y575189D03*
X184193D03*
X186793Y572689D03*
X184193D03*
X181593Y575189D03*
X178993D03*
X181593Y572689D03*
X178993D03*
X189293Y575189D03*
X186793Y577790D03*
X184193D03*
X189293D03*
X181593D03*
X178993D03*
X190800Y675662D03*
X256885Y574805D03*
X254385D03*
X256855Y571995D03*
X251885Y574805D03*
X249800Y563262D03*
X254355Y589235D03*
X256855D03*
X251855D03*
X256855Y605995D03*
X251885Y608805D03*
X257643Y594220D03*
X255043D03*
Y596820D03*
X257643D03*
X256885Y608805D03*
X254385D03*
X256855Y603495D03*
X251855Y623265D03*
X254355D03*
X256855D03*
Y639995D03*
Y637495D03*
X257643Y628220D03*
X255043D03*
Y630820D03*
X257643D03*
X256885Y642805D03*
X254385D03*
X251855Y657265D03*
X251885Y642805D03*
X254355Y657265D03*
X256855D03*
X257643Y662220D03*
X255043D03*
Y664820D03*
X257643D03*
X264055Y574505D03*
X264025Y571995D03*
X261555Y574505D03*
X261525Y571995D03*
X266555Y574505D03*
X266525Y571995D03*
X269055Y574505D03*
X269025Y571995D03*
X261465Y592115D03*
X261525Y589565D03*
X264025D03*
X263965Y592115D03*
X266525Y589565D03*
X266465Y592115D03*
X269025Y589565D03*
X268965Y592115D03*
X264025Y605995D03*
X261525D03*
X264055Y608505D03*
X261555D03*
X261435Y597175D03*
X261495Y594625D03*
X263995D03*
X263935Y597175D03*
X266525Y605995D03*
X266555Y608505D03*
X266435Y597175D03*
X266495Y594625D03*
X261525Y603495D03*
X264025D03*
X266525D03*
X269025Y605995D03*
X269055Y608505D03*
X268935Y597175D03*
X268995Y594625D03*
X269025Y603495D03*
X261495Y621055D03*
X263995D03*
X261525Y623565D03*
X264025D03*
X263995Y611055D03*
X261495D03*
X266495Y621055D03*
X266525Y623565D03*
X266495Y611055D03*
X268995Y621055D03*
X269025Y623565D03*
X268995Y611055D03*
X261525Y639995D03*
X264025D03*
X261525Y637495D03*
X266525Y639995D03*
X269025D03*
X264025Y637495D03*
X266525D03*
X269025D03*
X263965Y626115D03*
X261465D03*
X266465D03*
X268965D03*
X261495Y655055D03*
X263995D03*
X261525Y657565D03*
X264025D03*
X263995Y645055D03*
X264055Y642505D03*
X261495Y645055D03*
X261555Y642505D03*
X266495Y655055D03*
X266525Y657565D03*
X266495Y645055D03*
X266555Y642505D03*
X268995Y655055D03*
X269025Y657565D03*
X268995Y645055D03*
X269055Y642505D03*
X261465Y660115D03*
X263965D03*
X266465D03*
X268965D03*
X349636Y1399601D03*
X346426Y1414401D03*
X346256Y1417301D03*
X646815Y517974D03*
X648296Y528255D03*
X702462Y1673258D03*
X725537Y-23978D03*
Y-19022D03*
Y-13978D03*
Y-9022D03*
X714203Y1639776D03*
X730282Y1580391D03*
X741382Y1585251D03*
Y1580121D03*
X735882Y1580391D03*
X730282Y1590651D03*
Y1585521D03*
X735882Y1590651D03*
X732504Y1600321D03*
Y1597321D03*
X744504D03*
Y1600321D03*
X741504Y1597321D03*
Y1600321D03*
X735504Y1597321D03*
Y1600321D03*
X738504Y1597321D03*
Y1600321D03*
X744504Y1609521D03*
Y1612521D03*
X741504Y1609521D03*
X738504D03*
X735504D03*
X741504Y1612521D03*
X738504D03*
X735504D03*
X732504Y1603321D03*
Y1606321D03*
X744504Y1603321D03*
Y1606321D03*
X741504Y1603321D03*
Y1606321D03*
X738504Y1603321D03*
X735504D03*
X738504Y1606321D03*
X735504D03*
X742655Y1682362D03*
Y1678362D03*
X747504Y1600321D03*
Y1609521D03*
Y1612521D03*
X750504D03*
Y1609521D03*
X747504Y1603321D03*
Y1606321D03*
X755859Y1686090D03*
X755183Y1709850D03*
X776052Y1611893D03*
X763359Y1729520D03*
X788079Y1580393D03*
X782479D03*
X793579D03*
X788079Y1590653D03*
X782479D03*
Y1585523D03*
X793579Y1590653D03*
Y1585523D03*
X785052Y1600693D03*
Y1597693D03*
X782052D03*
Y1600693D03*
X794052D03*
X788052D03*
X791052D03*
X794052Y1597693D03*
X788052D03*
X791052D03*
X785052Y1607793D03*
X782052D03*
X779052D03*
X785052Y1611893D03*
X782052D03*
X779052D03*
X794052Y1607793D03*
X791052D03*
X788052D03*
X797052Y1611893D03*
X794052D03*
X788052D03*
X791052D03*
X785052Y1603693D03*
X782052D03*
X794052D03*
X788052D03*
X791052D03*
X797052Y1607793D03*
X824479Y1580393D03*
Y1590653D03*
Y1585523D03*
X824052Y1597693D03*
Y1600693D03*
X827052D03*
Y1597693D03*
X824052Y1611893D03*
Y1607793D03*
Y1603693D03*
X827052Y1611893D03*
Y1607793D03*
Y1603693D03*
X821052Y1611893D03*
Y1607793D03*
X818052Y1611893D03*
X842497Y6022D03*
Y16022D03*
Y20978D03*
Y10978D03*
X830079Y1580393D03*
X835579D03*
X833052Y1597693D03*
X836052D03*
X830079Y1590653D03*
X835579D03*
X833052Y1600693D03*
X836052D03*
X835579Y1585523D03*
X830052Y1600693D03*
Y1597693D03*
X833052Y1603693D03*
X836052D03*
X839052Y1611893D03*
X833052Y1607793D03*
Y1611893D03*
X836052Y1607793D03*
Y1611893D03*
X830052D03*
Y1607793D03*
Y1603693D03*
X839052Y1607793D03*
X866479Y1580393D03*
X872079D03*
X866052Y1597693D03*
X869052D03*
X866479Y1590653D03*
X869052Y1600693D03*
X866052D03*
X872052Y1597693D03*
X872079Y1590653D03*
X872052Y1600693D03*
X866479Y1585523D03*
X875052Y1597693D03*
Y1600693D03*
X869052Y1603693D03*
X866052D03*
X872052D03*
X869052Y1607793D03*
Y1611893D03*
X866052Y1607793D03*
X863052Y1611893D03*
X866052D03*
X872052Y1607793D03*
Y1611893D03*
X875052Y1603693D03*
Y1607793D03*
Y1611893D03*
X863052Y1607793D03*
X860052Y1611893D03*
X877579Y1580393D03*
Y1585523D03*
X878052Y1597693D03*
Y1600693D03*
X877579Y1590653D03*
X878052Y1603693D03*
Y1607793D03*
X881052Y1611893D03*
X878052D03*
X881052Y1607793D03*
X908479Y1580393D03*
Y1590653D03*
Y1585523D03*
X908052Y1600693D03*
Y1597693D03*
Y1611893D03*
X905052D03*
X902052D03*
X908052Y1607793D03*
X905052D03*
X908052Y1603693D03*
X919579Y1580393D03*
X914079D03*
X919579Y1590653D03*
X914079D03*
X919579Y1585523D03*
X917052Y1600693D03*
Y1597693D03*
X914052Y1600693D03*
Y1597693D03*
X911052Y1600693D03*
Y1597693D03*
X920052Y1600693D03*
Y1597693D03*
X917052Y1611893D03*
X914052D03*
X911052D03*
X917052Y1607793D03*
X914052D03*
X911052D03*
X920052Y1611893D03*
X923052D03*
Y1607793D03*
X920052D03*
X917052Y1603693D03*
X914052D03*
X911052D03*
X920052D03*
X968022Y1620730D03*
X965022D03*
X971022D03*
X965022Y1632730D03*
X968022Y1629730D03*
X965022D03*
X968022Y1626730D03*
X965022D03*
Y1623730D03*
X968022D03*
X971022Y1626730D03*
Y1623730D03*
Y1629730D03*
Y1632730D03*
X968022D03*
X985431Y181058D03*
X981795Y216623D03*
X990195Y216823D03*
X996662Y1620870D03*
X999662D03*
X1002662D03*
Y1626870D03*
Y1623870D03*
X996662Y1629870D03*
X999662Y1626870D03*
X996662D03*
Y1623870D03*
X999662D03*
X996662Y1632870D03*
X1034929Y-33989D03*
Y-29033D03*
Y-13989D03*
Y-9033D03*
Y-23989D03*
Y-19033D03*
Y-3989D03*
Y967D03*
X1034252Y1623870D03*
Y1626870D03*
X1031252Y1623870D03*
Y1626870D03*
X1028252Y1623870D03*
Y1626870D03*
X1031252Y1620870D03*
X1034252D03*
X1028252D03*
X1065721Y1633043D03*
X1068721D03*
Y1624043D03*
Y1627043D03*
Y1630043D03*
X1065721Y1624043D03*
Y1627043D03*
Y1630043D03*
X1062721Y1633043D03*
Y1624043D03*
Y1627043D03*
Y1630043D03*
X1059721Y1633043D03*
Y1624043D03*
Y1627043D03*
Y1630043D03*
X1068721Y1621043D03*
X1065721D03*
X1062721D03*
X1059721D03*
X1099901Y1633203D03*
Y1624203D03*
Y1627203D03*
Y1630203D03*
Y1621203D03*
X1093901Y1633203D03*
X1096901D03*
Y1624203D03*
Y1627203D03*
Y1630203D03*
X1093901Y1624203D03*
Y1627203D03*
Y1630203D03*
X1090901Y1633203D03*
X1087901D03*
X1090901Y1624203D03*
X1087901D03*
Y1627203D03*
X1090901D03*
X1087901Y1630203D03*
X1090901D03*
X1096901Y1621203D03*
X1093901D03*
X1087901D03*
X1090901D03*
X1111918Y234718D03*
X1109088Y234668D03*
X1111918Y237718D03*
Y240718D03*
X1109088Y237668D03*
Y240668D03*
X1344248Y-33989D03*
Y-29033D03*
Y-13989D03*
Y-9033D03*
Y-23989D03*
Y-19033D03*
Y-3989D03*
Y967D03*
X1619980Y590685D03*
X1620170Y623762D03*
X1622770D03*
X1620170Y626362D03*
X1622770D03*
X1620170Y657762D03*
X1622770D03*
X1622109Y652469D03*
X1619509D03*
X1620170Y660362D03*
X1622770D03*
X1622109Y686469D03*
X1619509D03*
X1622770Y691762D03*
Y694362D03*
X1620170Y691762D03*
Y694362D03*
X1619509Y720469D03*
X1622109D03*
X1637667Y587844D03*
Y590444D03*
X1629867D03*
Y587844D03*
X1632467Y590444D03*
Y587844D03*
X1635067Y590444D03*
Y587844D03*
X1626606Y616576D03*
X1629206D03*
X1631806D03*
X1634406D03*
X1637006D03*
X1639606D03*
X1630570Y623762D03*
X1627970D03*
X1625370D03*
X1636412Y638451D03*
X1636417Y630007D03*
X1640061Y639497D03*
X1636412Y641051D03*
X1630570Y626362D03*
X1627970D03*
X1625370D03*
X1630198Y638651D03*
Y636051D03*
Y641251D03*
X1633305Y638651D03*
Y641251D03*
X1630198Y632851D03*
X1630214Y629907D03*
X1633321D03*
X1640061Y644457D03*
Y641977D03*
X1630570Y657762D03*
X1627970D03*
X1625370D03*
X1629909Y652469D03*
X1632509D03*
X1624709D03*
X1627309D03*
X1630198Y643851D03*
X1633305Y646451D03*
Y643851D03*
X1630198Y646451D03*
X1636412Y672451D03*
X1636417Y664007D03*
X1640061Y673497D03*
X1630570Y660362D03*
X1627970D03*
X1625370D03*
X1630198Y672651D03*
Y670051D03*
X1633305Y672651D03*
X1630198Y666851D03*
X1630214Y663907D03*
X1633321D03*
X1629909Y686469D03*
X1632509D03*
X1624709D03*
X1627309D03*
X1640061Y678457D03*
Y675977D03*
X1636412Y675051D03*
X1630198Y677851D03*
Y675251D03*
X1633305Y680451D03*
Y675251D03*
Y677851D03*
X1630198Y680451D03*
X1636417Y698007D03*
X1636412Y706451D03*
X1630214Y697907D03*
X1633321D03*
X1630198Y704051D03*
Y706651D03*
X1633305D03*
X1630198Y700851D03*
X1625370Y691762D03*
Y694362D03*
X1630570D03*
Y691762D03*
X1627970D03*
Y694362D03*
X1640061Y707497D03*
Y712457D03*
Y709977D03*
X1636412Y709051D03*
X1632509Y720469D03*
X1627309D03*
X1629909D03*
X1624709D03*
X1633305Y711851D03*
Y709251D03*
X1630198D03*
Y711851D03*
X1633305Y714451D03*
X1630198D03*
X1642873Y604206D03*
Y607206D03*
X1645625Y600495D03*
Y603295D03*
X1642873Y601206D03*
Y598206D03*
X1645625Y597795D03*
Y594995D03*
X1642873Y595006D03*
X1642340Y618546D03*
X1642873Y610206D03*
X1645661Y639497D03*
X1656550Y653086D03*
X1645661Y644457D03*
Y641977D03*
Y673497D03*
X1656550Y687086D03*
X1645661Y678457D03*
Y675977D03*
Y707497D03*
Y709977D03*
Y712457D03*
X1667739Y187187D03*
X1659914Y683681D03*
Y717681D03*
X1763829Y1337548D03*
X1766829D03*
Y1340448D03*
X1769829Y1337548D03*
Y1340448D03*
X1781829Y1324448D03*
X1784829D03*
X1778829D03*
X1781829Y1333148D03*
Y1330248D03*
Y1327348D03*
X1784829Y1333148D03*
Y1330248D03*
Y1327348D03*
X1781829Y1337548D03*
Y1340448D03*
X1784829Y1337548D03*
Y1340448D03*
X1778829Y1333148D03*
Y1330248D03*
Y1327348D03*
Y1337548D03*
X1772829D03*
X1775829D03*
X1778829Y1340448D03*
X1775829D03*
X1772829D03*
X1829514Y1498198D03*
Y1500807D03*
X1832114Y1498198D03*
Y1500807D03*
X1824995Y1502201D03*
G54D22*
X60303Y20354D03*
X312921Y24291D03*
X505185Y41142D03*
X757803Y45079D03*
X922441Y237697D03*
X929331Y160413D03*
X1534712Y20354D03*
X1787330Y24291D03*
G54D41*
X338211Y1118243D03*
Y1131060D03*
X348879Y860993D03*
X349311Y1105426D03*
X351162Y1127856D03*
X353011Y1118243D03*
X354861Y1121447D03*
X347461Y1134264D03*
X354861D03*
X356278Y848176D03*
X371078D03*
X363678D03*
X356278Y860993D03*
X371078D03*
X363678D03*
X371078Y873810D03*
X356278D03*
X363678D03*
Y886627D03*
X371078D03*
X367811Y1105426D03*
X369661Y1102221D03*
X358562D03*
X360412Y1105426D03*
X369662Y1121447D03*
X362261D03*
X369662Y1134264D03*
X362262D03*
X385878Y848176D03*
X378478D03*
Y873810D03*
Y886627D03*
X380762Y1095813D03*
X382611Y1099017D03*
X384462Y1121447D03*
X377062D03*
X384462Y1134264D03*
X377062D03*
X400678Y848176D03*
Y860993D03*
X402529Y947509D03*
X398829Y953917D03*
X402529D03*
X400680Y950713D03*
X401111Y1022114D03*
X402960Y1018910D03*
X402962Y1025318D03*
X399262D03*
Y1044544D03*
X402962D03*
X401111Y1041340D03*
X399262Y1082995D03*
X391862Y1102221D03*
X393711Y1105426D03*
X391862Y1121447D03*
Y1134264D03*
X399262D03*
X408078Y848176D03*
X415478D03*
Y860993D03*
X408078D03*
X415478Y873810D03*
X404785Y971100D03*
X407085D03*
X409385D03*
X411685D03*
X420205D03*
X412385Y1000080D03*
X410085D03*
X420215Y1000040D03*
X404811Y1041340D03*
X415911Y1079791D03*
X404811Y1092608D03*
X417762Y1095813D03*
X415912Y1124651D03*
X419612D03*
Y1118243D03*
X417761Y1121447D03*
Y1127856D03*
X406662Y1134264D03*
X415912Y1137469D03*
Y1131060D03*
X414061Y1140973D03*
X419612Y1137469D03*
Y1131060D03*
X417761Y1134264D03*
Y1140973D03*
X422878Y848176D03*
X430278Y860993D03*
X422878D03*
Y873810D03*
X427875Y941930D03*
Y944230D03*
X430280Y944305D03*
X432129Y947510D03*
X427875Y956373D03*
Y954073D03*
X430280Y957123D03*
X432129Y960327D03*
Y953918D03*
X430280Y950714D03*
X435830Y960327D03*
Y953918D03*
X432129Y966736D03*
X430280Y963531D03*
X435830Y966736D03*
X430268Y976348D03*
X432129Y973144D03*
X430280Y969940D03*
X427875Y971267D03*
X422685Y971100D03*
X427875Y968967D03*
X435830Y973144D03*
X430280Y982757D03*
X432129Y979553D03*
X427875Y983111D03*
X435830Y979553D03*
X427875Y985411D03*
Y997521D03*
X430712Y1009298D03*
X427875Y1012152D03*
X430712Y1002889D03*
X427875Y999821D03*
X422685Y1000060D03*
X436263Y1006094D03*
Y999685D03*
X432562Y1006094D03*
Y999685D03*
X427875Y1014452D03*
X436263Y1012502D03*
X432562D03*
X430712Y1022115D03*
Y1015706D03*
X427875Y1026704D03*
X430712Y1028524D03*
X436263Y1018911D03*
X432562D03*
Y1025319D03*
X436263D03*
X427875Y1029004D03*
Y1031304D03*
X436263Y1031728D03*
X432562D03*
X423285Y1036884D03*
X430711Y1041340D03*
X430712Y1034932D03*
X427875Y1033604D03*
X423285Y1032284D03*
Y1034584D03*
X436262Y1038137D03*
X436261Y1044544D03*
X432562Y1038137D03*
X434412Y1041340D03*
X432561Y1044544D03*
X434412Y1047749D03*
X436262Y1057361D03*
Y1050952D03*
Y1063770D03*
X423311Y1079791D03*
X436262Y1070178D03*
Y1076587D03*
Y1082995D03*
Y1089404D03*
X436261Y1095813D03*
X421462Y1102221D03*
X423311Y1099017D03*
X428861Y1108630D03*
X427012Y1105426D03*
X425162Y1108630D03*
X430711Y1105426D03*
Y1099017D03*
X428861Y1102221D03*
X436262Y1108630D03*
Y1102221D03*
X432561Y1108630D03*
Y1102221D03*
X434412Y1099017D03*
X430711Y1111834D03*
X427012D03*
X430711Y1124651D03*
X428861Y1121447D03*
X427012Y1124651D03*
X425162Y1121447D03*
X421461D03*
X430711Y1118243D03*
X428861Y1115039D03*
X427012Y1118243D03*
X425162Y1115039D03*
X436262Y1121447D03*
Y1115039D03*
X432561Y1121447D03*
Y1115039D03*
X428861Y1127856D03*
X425162D03*
X421461D03*
X436262D03*
X432561D03*
X430711Y1137769D03*
X427012Y1137569D03*
X430711Y1131060D03*
X428861Y1134264D03*
X427012Y1131060D03*
X425162Y1134264D03*
X421461D03*
X428861Y1140973D03*
X425161D03*
X421461D03*
X436261Y1134264D03*
X432561D03*
X445078Y860993D03*
X452479D03*
X450630Y941101D03*
X448780Y944305D03*
X443229Y947510D03*
X450630D03*
X445079Y957123D03*
X437680D03*
X441380D03*
X439529Y960327D03*
X443229D03*
Y953918D03*
X439529D03*
X437680Y950714D03*
X441380D03*
X445079D03*
X448780Y957123D03*
X450630Y953918D03*
Y960327D03*
X448780Y950714D03*
X445079Y963531D03*
X437680D03*
X441380D03*
X439529Y966736D03*
X443229D03*
X448780Y963531D03*
X450630Y966736D03*
X445079Y976348D03*
Y969940D03*
X439529Y973144D03*
X443229D03*
X437680Y976348D03*
X441380D03*
X437680Y969940D03*
X441380D03*
X450630Y973144D03*
X448780Y976348D03*
Y969940D03*
X445079Y982757D03*
X437680D03*
X441380D03*
X439529Y979553D03*
X443229D03*
X448780Y982757D03*
X450630Y979553D03*
X439962Y1006094D03*
X443662D03*
X445511Y1009298D03*
X438113D03*
X441813D03*
X445512Y1002889D03*
X438113D03*
X441813D03*
X439962Y999685D03*
X443662D03*
X451062Y1006094D03*
X449213Y1009298D03*
Y1002889D03*
X451062Y999685D03*
X439962Y1012502D03*
X443662D03*
X451062D03*
X445511Y1022115D03*
X438113D03*
X441813D03*
X445512Y1015706D03*
X438113D03*
X439962Y1018911D03*
X441813Y1015706D03*
X443662Y1018911D03*
Y1025319D03*
X439962D03*
X445511Y1028524D03*
X441813D03*
X438113D03*
X449213Y1022115D03*
X451062Y1018911D03*
X449213Y1015706D03*
X451062Y1025319D03*
X449213Y1028524D03*
X439962Y1031728D03*
X443662D03*
X451062D03*
X439962Y1038137D03*
X443662D03*
X438112Y1041340D03*
X439961Y1044544D03*
X441812Y1041340D03*
X443661Y1044544D03*
X447361D03*
X445511Y1041340D03*
X445512Y1034932D03*
X438113D03*
X441813D03*
X451062Y1038137D03*
X449211Y1041340D03*
X449213Y1034932D03*
X445510Y1047749D03*
X441812D03*
X438112D03*
Y1060565D03*
Y1054157D03*
X439961Y1057361D03*
X441812Y1054157D03*
Y1060565D03*
X443661Y1057361D03*
X445511Y1060565D03*
Y1054157D03*
X439961Y1050952D03*
X443661D03*
X439961Y1063770D03*
X443661D03*
X439961Y1076587D03*
Y1070178D03*
X441812Y1073383D03*
X438112D03*
X443661Y1070178D03*
Y1076587D03*
X445511Y1073383D03*
X441812Y1066974D03*
X438112D03*
X445511D03*
X441812Y1079791D03*
X438112D03*
X445511D03*
X443661Y1082995D03*
X439961D03*
X441812Y1086200D03*
X445511D03*
X439961Y1089404D03*
X441812Y1092608D03*
X438112D03*
X443661Y1089404D03*
X445511Y1092608D03*
X447361Y1089404D03*
X438112Y1086200D03*
X449211Y1092608D03*
X439961Y1095813D03*
X443661D03*
X447361D03*
X441812Y1105426D03*
X438112D03*
X439961Y1108630D03*
X443661D03*
X445511Y1105426D03*
X439961Y1102221D03*
X441812Y1099017D03*
X438112D03*
X443661Y1102221D03*
X445511Y1099017D03*
X452912Y1105426D03*
X451061Y1108630D03*
X449212Y1105426D03*
X451061Y1102221D03*
X449212Y1099017D03*
X441812Y1111834D03*
X438112D03*
X445511D03*
X452912D03*
X449212D03*
X438112Y1124651D03*
X439961Y1121447D03*
X441812Y1124651D03*
X445511D03*
X443661Y1121447D03*
X438112Y1118243D03*
X441812D03*
X439961Y1115039D03*
X445511Y1118243D03*
X443661Y1115039D03*
X452912Y1124651D03*
Y1118243D03*
X451061Y1121447D03*
X449212Y1124651D03*
Y1118243D03*
X451061Y1115039D03*
X439961Y1127856D03*
X443661D03*
X451061D03*
X441812Y1137769D03*
X438112D03*
X445511D03*
X443661Y1134264D03*
X441812Y1131060D03*
X439961Y1134264D03*
X438112Y1131060D03*
X445511D03*
X452912Y1137769D03*
Y1131060D03*
X449212Y1137769D03*
Y1131060D03*
X451061Y1134264D03*
X459878Y848176D03*
X467278D03*
X459878Y860993D03*
X467278D03*
Y873810D03*
X459878D03*
Y886627D03*
X467278D03*
X459878Y899445D03*
X467712Y1054157D03*
Y1060565D03*
X465862Y1082995D03*
X462162D03*
X467711Y1099017D03*
X462162Y1102221D03*
X458461Y1108630D03*
X456612Y1105426D03*
X454761Y1108630D03*
Y1102221D03*
X460312Y1111834D03*
X456611D03*
X464012Y1124651D03*
X462161Y1121447D03*
X460312Y1124651D03*
X456611D03*
X454761Y1121447D03*
X464011Y1118243D03*
X462161Y1115039D03*
X460312Y1118243D03*
X456611D03*
X454761Y1115039D03*
X462161Y1127856D03*
X454761D03*
X465861D03*
X464012Y1137469D03*
X460312D03*
X456612D03*
X464012Y1131060D03*
X462161Y1134264D03*
X460312Y1131060D03*
X456611D03*
X454761Y1134264D03*
X462161Y1140973D03*
X458461D03*
X454761D03*
X467712Y1137469D03*
X465861Y1134264D03*
X467712Y1131060D03*
X465861Y1140973D03*
X474678Y848176D03*
X482078D03*
X474678Y860993D03*
X482078D03*
X474678Y873810D03*
X482078D03*
X474678Y886627D03*
X482078D03*
Y905853D03*
X480229Y947509D03*
X478378Y950713D03*
X480229Y953917D03*
X478378Y957122D03*
X476285Y973826D03*
Y971526D03*
X480661Y1018910D03*
X478811Y1022114D03*
Y1028523D03*
Y1015705D03*
X476325Y1031795D03*
Y1027195D03*
Y1029495D03*
X470724Y1028827D03*
X476962Y1044544D03*
X478811Y1047749D03*
X473261Y1057361D03*
X471412Y1060565D03*
X475112Y1054157D03*
X469562Y1063770D03*
X469561Y1057361D03*
X473262Y1063770D03*
X469561Y1050952D03*
X473262D03*
X482511Y1054157D03*
X480662Y1063770D03*
X480661Y1057361D03*
X478812Y1060565D03*
X476962Y1063770D03*
Y1057361D03*
X478812Y1054157D03*
X476961Y1050952D03*
X473262Y1095813D03*
X469562Y1082995D03*
X480662Y1089404D03*
Y1102221D03*
X473262Y1121447D03*
X480662D03*
Y1134264D03*
X469561D03*
X489478Y848176D03*
X496878D03*
X489478Y860993D03*
X496878D03*
Y873810D03*
X489478D03*
Y886627D03*
X496878D03*
X488062Y1095813D03*
Y1115039D03*
Y1121447D03*
X495462Y1134264D03*
X488062D03*
X511678Y848176D03*
X504278D03*
X511678Y860993D03*
X504278D03*
X511678Y873810D03*
X504278D03*
X511678Y886627D03*
X504278D03*
X510262Y1102221D03*
X502862Y1115039D03*
X510262Y1121447D03*
X502862D03*
X517662D03*
X510262Y1134264D03*
X502862D03*
X517662D03*
X519078Y848176D03*
X526479Y860993D03*
X519078D03*
X526479Y873810D03*
X519078D03*
X526479Y886627D03*
X519078D03*
X533879D03*
X528762Y1102221D03*
X525062D03*
X523212Y1099017D03*
X530611Y1105426D03*
X526911Y1118243D03*
X525062Y1121447D03*
X534311Y1118243D03*
X525062Y1134264D03*
X528761Y1140973D03*
X532461D03*
X541711Y1118243D03*
X748399Y1051247D03*
X1309832Y209249D03*
X1314353Y1131060D03*
X1325853Y174099D03*
X1331102Y179724D03*
Y182874D03*
Y186024D03*
X1324802Y179724D03*
Y186024D03*
Y182874D03*
Y195474D03*
X1327952D03*
X1318502D03*
X1321652D03*
X1327952Y201774D03*
X1321652D03*
X1331102Y189174D03*
X1329062Y212949D03*
X1325852Y211099D03*
X1325021Y860993D03*
X1325453Y1105426D03*
X1327304Y1127856D03*
X1329153Y1118243D03*
X1331003Y1121447D03*
Y1134264D03*
X1323603D03*
X1332268Y170399D03*
X1332262Y211099D03*
X1347220Y848176D03*
X1339820D03*
X1332420D03*
X1339820Y860993D03*
X1347220D03*
X1332420D03*
X1339820Y873810D03*
X1332420D03*
X1347220D03*
Y886627D03*
X1339820D03*
X1334704Y1102221D03*
X1345803D03*
X1343953Y1105426D03*
X1336554D03*
X1345804Y1121447D03*
X1338403D03*
X1338404Y1134264D03*
X1345804D03*
X1362020Y848176D03*
X1354620D03*
Y873810D03*
Y886627D03*
X1356904Y1095813D03*
X1358753Y1099017D03*
X1360604Y1121447D03*
X1353204D03*
Y1134264D03*
X1360604D03*
X1376820Y848176D03*
X1369420D03*
X1376820Y860993D03*
X1378671Y947509D03*
Y953917D03*
X1374971D03*
X1376822Y950713D03*
X1375404Y1025318D03*
X1377253Y1022114D03*
X1379102Y1018910D03*
X1379104Y1025318D03*
X1375404Y1044544D03*
X1377253Y1041340D03*
X1379104Y1044544D03*
X1375404Y1082995D03*
X1368004Y1102221D03*
X1369853Y1105426D03*
X1368004Y1121447D03*
Y1134264D03*
X1375404D03*
X1374847Y1153069D03*
X1391620Y848176D03*
X1384220D03*
Y860993D03*
X1391620D03*
Y873810D03*
X1392534Y942097D03*
X1394834D03*
X1380926Y971099D03*
X1383226D03*
X1387826D03*
X1385526D03*
X1396346D03*
X1386226Y1000079D03*
X1396356Y1000039D03*
X1388526Y1000079D03*
X1380953Y1041340D03*
X1392053Y1079791D03*
X1380953Y1092608D03*
X1393904Y1095813D03*
X1392054Y1124651D03*
X1393903Y1121447D03*
Y1127856D03*
X1395754Y1118243D03*
Y1124651D03*
X1382804Y1134264D03*
X1390203Y1140973D03*
X1392054Y1131060D03*
Y1137469D03*
X1393903Y1134264D03*
Y1140973D03*
X1395754Y1131060D03*
Y1137469D03*
X1399020Y848176D03*
X1406420Y860993D03*
X1399020D03*
Y873810D03*
X1406421Y944304D03*
X1408271Y941100D03*
X1411971D03*
X1404016Y944229D03*
Y941929D03*
X1408270Y947509D03*
X1411971D03*
X1406421Y950713D03*
Y957122D03*
X1408270Y953917D03*
Y960326D03*
X1411971Y953917D03*
Y960326D03*
X1404016Y954072D03*
Y956372D03*
X1406421Y963530D03*
X1408270Y966735D03*
X1411971D03*
X1406421Y969939D03*
X1406409Y976347D03*
X1408270Y973143D03*
X1411971D03*
X1404016Y971266D03*
Y968966D03*
X1398826Y971099D03*
X1406421Y982756D03*
X1408270Y979552D03*
X1411971D03*
X1404016Y983110D03*
Y985410D03*
Y997520D03*
X1412404Y999684D03*
Y1006093D03*
Y1012501D03*
X1406853Y1002888D03*
Y1009297D03*
X1408703Y999684D03*
Y1006093D03*
Y1012501D03*
X1404016Y1012151D03*
Y999820D03*
X1398826Y1000059D03*
X1404016Y1014451D03*
X1406853Y1028523D03*
X1412404Y1018910D03*
X1406853Y1015705D03*
Y1022114D03*
X1408703Y1018910D03*
X1412404Y1025318D03*
X1408703D03*
X1404016Y1026703D03*
X1412404Y1031727D03*
X1408703D03*
X1404016Y1029003D03*
Y1031303D03*
X1412403Y1038136D03*
Y1044544D03*
X1406853Y1034931D03*
Y1041340D03*
X1408703Y1038136D03*
Y1044544D03*
X1410554Y1041340D03*
X1404016Y1033603D03*
X1399426Y1036883D03*
Y1034583D03*
Y1032283D03*
X1410554Y1047749D03*
X1412404Y1050952D03*
Y1057361D03*
Y1063770D03*
Y1070178D03*
Y1076587D03*
Y1082995D03*
Y1089404D03*
X1412403Y1095813D03*
X1397604Y1102221D03*
X1399453Y1099017D03*
X1412404Y1102221D03*
Y1108630D03*
X1401304D03*
X1403154Y1105426D03*
Y1111834D03*
X1405003Y1102221D03*
Y1108630D03*
X1406853Y1099017D03*
Y1105426D03*
Y1111834D03*
X1408703Y1102221D03*
Y1108630D03*
X1410554Y1099017D03*
X1412404Y1115039D03*
Y1121447D03*
Y1127856D03*
X1397603Y1121447D03*
Y1127856D03*
X1401304Y1115039D03*
Y1121447D03*
Y1127856D03*
X1403154Y1118243D03*
Y1124651D03*
X1405003Y1115039D03*
Y1121447D03*
Y1127856D03*
X1406853Y1118243D03*
Y1124651D03*
X1408703Y1115039D03*
Y1121447D03*
Y1127856D03*
X1412403Y1134264D03*
X1397603D03*
Y1140973D03*
X1401304Y1134264D03*
X1401303Y1140973D03*
X1403154Y1131060D03*
Y1137569D03*
X1405003Y1134264D03*
Y1140973D03*
X1406853Y1131060D03*
Y1137769D03*
X1408703Y1134264D03*
X1421220Y860993D03*
X1428621D03*
X1413821Y944304D03*
X1415671Y941100D03*
X1417521Y944304D03*
X1419371Y941100D03*
X1421220Y944304D03*
X1424921D03*
X1426771Y941100D03*
X1415670Y947509D03*
X1419370D03*
X1426771D03*
X1413821Y950713D03*
Y957122D03*
X1415670Y953917D03*
Y960326D03*
X1417521Y950713D03*
Y957122D03*
X1419370Y953917D03*
Y960326D03*
X1421220Y950713D03*
Y957122D03*
X1424921Y950713D03*
Y957122D03*
X1426771Y953917D03*
Y960326D03*
X1413821Y963530D03*
X1415670Y966735D03*
X1417521Y963530D03*
X1419370Y966735D03*
X1421220Y963530D03*
X1424921D03*
X1426771Y966735D03*
X1413821Y969939D03*
Y976347D03*
X1415670Y973143D03*
X1417521Y969939D03*
Y976347D03*
X1419370Y973143D03*
X1421220Y969939D03*
Y976347D03*
X1424921Y969939D03*
Y976347D03*
X1426771Y973143D03*
X1413821Y982756D03*
X1415670Y979552D03*
X1417521Y982756D03*
X1419370Y979552D03*
X1421220Y982756D03*
X1424921D03*
X1426771Y979552D03*
X1414254Y1002888D03*
Y1009297D03*
X1416103Y999684D03*
Y1006093D03*
Y1012501D03*
X1417954Y1002888D03*
Y1009297D03*
X1419803Y999684D03*
Y1006093D03*
Y1012501D03*
X1421653Y1002888D03*
Y1009297D03*
X1425354Y1002888D03*
Y1009297D03*
X1427203Y999684D03*
Y1006093D03*
Y1012501D03*
X1421653Y1028523D03*
X1414254D03*
X1417954D03*
X1425354D03*
X1414254Y1015705D03*
Y1022114D03*
X1416103Y1018910D03*
X1417954Y1015705D03*
Y1022114D03*
X1419803Y1018910D03*
X1421653Y1015705D03*
Y1022114D03*
X1425354Y1015705D03*
Y1022114D03*
X1427203Y1018910D03*
X1416103Y1025318D03*
X1419803D03*
X1427203D03*
X1416103Y1031727D03*
X1419803D03*
X1427203D03*
X1414254Y1034931D03*
Y1041340D03*
X1416103Y1038136D03*
Y1044544D03*
X1417954Y1034931D03*
Y1041340D03*
X1419803Y1038136D03*
Y1044544D03*
X1421653Y1034931D03*
Y1041340D03*
X1423503Y1044544D03*
X1425354Y1034931D03*
X1425353Y1041340D03*
X1427203Y1038136D03*
X1421653Y1047749D03*
X1414254D03*
X1417954D03*
X1414254Y1054157D03*
X1416103Y1050952D03*
X1417954Y1054157D03*
X1419803Y1050952D03*
X1421653Y1054157D03*
X1414254Y1060565D03*
X1416103Y1057361D03*
X1417954Y1060565D03*
X1419803Y1057361D03*
X1421653Y1060565D03*
X1416103Y1063770D03*
X1419803D03*
X1414254Y1066974D03*
Y1073383D03*
X1416103Y1070178D03*
Y1076587D03*
X1417954Y1066974D03*
Y1073383D03*
X1419803Y1070178D03*
Y1076587D03*
X1421653Y1066974D03*
Y1073383D03*
X1414254Y1079791D03*
X1417954D03*
X1421653D03*
X1416103Y1082995D03*
X1419803D03*
X1414254Y1086200D03*
Y1092608D03*
X1416103Y1089404D03*
Y1095813D03*
X1417954Y1086200D03*
Y1092608D03*
X1419803Y1089404D03*
Y1095813D03*
X1421653Y1086200D03*
Y1092608D03*
X1423503Y1089404D03*
Y1095813D03*
X1425353Y1092608D03*
X1414254Y1099017D03*
Y1105426D03*
Y1111834D03*
X1416103Y1102221D03*
Y1108630D03*
X1417954Y1099017D03*
Y1105426D03*
Y1111834D03*
X1419803Y1102221D03*
Y1108630D03*
X1421653Y1099017D03*
Y1105426D03*
Y1111834D03*
X1425354Y1099017D03*
Y1105426D03*
Y1111834D03*
X1427203Y1102221D03*
Y1108630D03*
X1429054Y1105426D03*
Y1111834D03*
X1414254Y1118243D03*
Y1124651D03*
X1416103Y1115039D03*
Y1121447D03*
Y1127856D03*
X1417954Y1118243D03*
Y1124651D03*
X1419803Y1115039D03*
Y1121447D03*
Y1127856D03*
X1421653Y1118243D03*
Y1124651D03*
X1425354Y1118243D03*
Y1124651D03*
X1427203Y1115039D03*
Y1121447D03*
Y1127856D03*
X1429054Y1118243D03*
Y1124651D03*
X1414254Y1131060D03*
Y1137769D03*
X1416103Y1134264D03*
X1417954Y1131060D03*
Y1137769D03*
X1419803Y1134264D03*
X1421653Y1131060D03*
Y1137769D03*
X1425354Y1131060D03*
Y1137769D03*
X1427203Y1134264D03*
X1429054Y1131060D03*
Y1137769D03*
X1443420Y848176D03*
X1436020D03*
X1443420Y860993D03*
X1436020D03*
Y873810D03*
X1443420D03*
X1436020Y899445D03*
Y886627D03*
X1443420D03*
X1443854Y1054157D03*
Y1060565D03*
X1438304Y1082995D03*
X1442004D03*
X1438304Y1102221D03*
X1443853Y1099017D03*
X1430903Y1102221D03*
Y1108630D03*
X1432754Y1105426D03*
X1432753Y1111834D03*
X1434603Y1108630D03*
X1436454Y1111834D03*
X1430903Y1115039D03*
Y1121447D03*
Y1127856D03*
X1432753Y1118243D03*
Y1124651D03*
X1436454Y1118243D03*
Y1124651D03*
X1438303Y1115039D03*
Y1121447D03*
Y1127856D03*
X1440153Y1118243D03*
X1440154Y1124651D03*
X1442003Y1127856D03*
X1443854Y1131060D03*
Y1137469D03*
X1430903Y1134264D03*
Y1140973D03*
X1432753Y1131060D03*
X1432754Y1137469D03*
X1434603Y1140973D03*
X1436454Y1131060D03*
Y1137469D03*
X1438303Y1134264D03*
Y1140973D03*
X1440154Y1131060D03*
Y1137469D03*
X1442003Y1134264D03*
Y1140973D03*
X1450820Y848176D03*
X1458220D03*
X1450820Y860993D03*
X1458220D03*
Y873810D03*
X1450820D03*
X1458220Y886627D03*
X1450820D03*
X1458220Y905853D03*
X1456371Y947509D03*
Y953917D03*
X1454520Y957122D03*
Y950713D03*
X1452426Y973825D03*
Y971525D03*
X1454953Y1028523D03*
Y1022114D03*
X1456803Y1018910D03*
X1454953Y1015705D03*
X1446934Y1028889D03*
X1452466Y1031794D03*
Y1029494D03*
Y1027194D03*
X1454953Y1047749D03*
X1453104Y1044544D03*
X1456804Y1063770D03*
X1458653Y1054157D03*
X1454954D03*
X1453104Y1057361D03*
Y1063770D03*
X1454954Y1060565D03*
X1456803Y1057361D03*
X1453103Y1050952D03*
X1445703Y1057361D03*
X1445704Y1063770D03*
X1447554Y1060565D03*
X1449403Y1057361D03*
X1449404Y1063770D03*
X1451254Y1054157D03*
X1445703Y1050952D03*
X1449404D03*
X1445704Y1082995D03*
X1456804Y1089404D03*
X1449404Y1095813D03*
X1456804Y1102221D03*
Y1121447D03*
X1449404D03*
X1456804Y1134264D03*
X1445703D03*
X1465620Y848176D03*
X1473020D03*
X1465620Y860993D03*
X1473020D03*
Y873810D03*
X1465620D03*
X1473020Y886627D03*
X1465620D03*
X1464204Y1095813D03*
Y1115039D03*
Y1121447D03*
X1471604Y1134264D03*
X1464204D03*
X1487820Y848176D03*
X1480420D03*
X1487820Y860993D03*
X1480420D03*
X1487820Y873810D03*
X1480420D03*
Y886627D03*
X1487820D03*
X1486404Y1102221D03*
X1479004Y1115039D03*
Y1121447D03*
X1493804D03*
X1486404D03*
X1479004Y1134264D03*
X1493804D03*
X1486404D03*
X1495220Y848176D03*
Y860993D03*
X1502621D03*
X1495220Y873810D03*
X1502621D03*
X1495220Y886627D03*
X1502621D03*
X1510021D03*
X1506753Y1105426D03*
X1504904Y1102221D03*
X1501204D03*
X1499354Y1099017D03*
X1503053Y1118243D03*
X1510453D03*
X1501204Y1121447D03*
Y1134264D03*
X1508603Y1140973D03*
X1504903D03*
X1517853Y1118243D03*
X1724541Y1051247D03*
G54D49*
X717313Y-27626D03*
Y-21471D03*
Y-17597D03*
X717298Y-15082D03*
X717313Y-11442D03*
X717298Y-25111D03*
X717313Y-7568D03*
X717298Y-5053D03*
X834273Y2374D03*
X834258Y4889D03*
X834273Y22432D03*
Y8529D03*
Y12403D03*
X834258Y14918D03*
X834273Y18558D03*
X834258Y24947D03*
X1026705Y-27695D03*
Y-38224D03*
X1023437Y-38210D03*
X1026690Y-35709D03*
X1023422Y-35695D03*
X1026705Y-32069D03*
Y-17666D03*
X1026690Y-15151D03*
X1026705Y-11511D03*
X1026690Y-25180D03*
X1026705Y-21540D03*
X1026690Y4907D03*
X1026705Y2392D03*
X1026690Y-5122D03*
X1026705Y-7637D03*
Y-1482D03*
Y22450D03*
Y18576D03*
Y8547D03*
X1026690Y14936D03*
X1026705Y12421D03*
X1026690Y24965D03*
X1336024Y-27695D03*
Y-32069D03*
X1332741Y-35695D03*
X1336009Y-35709D03*
X1332756Y-38210D03*
X1336024Y-38224D03*
Y-11511D03*
X1336009Y-15151D03*
X1336024Y-17666D03*
Y-21540D03*
X1336009Y-25180D03*
X1336024Y2392D03*
X1336009Y4907D03*
X1336024Y-1482D03*
Y-7637D03*
X1336009Y-5122D03*
X1336024Y18576D03*
Y22450D03*
Y12421D03*
X1336009Y14936D03*
X1336024Y8547D03*
X1336009Y24965D03*
G54D65*
X1879155Y468898D03*
Y716798D03*
X1889155Y468898D03*
Y716798D03*
X1900275Y840758D03*
X1910275D03*
X1921395Y-19332D03*
X1931395D03*
X1942395Y593048D03*
X1952395D03*
X1963362Y-19190D03*
X1973362D03*
X1984482Y593020D03*
X1994482D03*
X2005452Y-19180D03*
X2015452D03*
X2026452Y593200D03*
X2047419Y-19038D03*
X2036452Y593200D03*
X2057419Y-19038D03*
X2068539Y593172D03*
X2078539D03*
G54D58*
X918780Y1684890D03*
Y1694890D03*
Y1714890D03*
X928780Y1684890D03*
X938780D03*
X928780Y1694890D03*
X938780D03*
X928780Y1704890D03*
X938780D03*
X928780Y1714890D03*
X938780D03*
G54D64*
X1879155Y354948D03*
Y458898D03*
Y478898D03*
Y582848D03*
Y602848D03*
Y706798D03*
Y726798D03*
Y830748D03*
X1900275Y-9342D03*
X1889155Y354948D03*
Y458898D03*
Y478898D03*
X1900275Y582858D03*
X1889155Y582848D03*
Y602848D03*
Y706798D03*
X1900275Y726808D03*
X1889155Y726798D03*
X1900275Y830758D03*
X1889155Y830748D03*
X1900275Y850758D03*
Y954708D03*
X1910275Y-9342D03*
Y582858D03*
Y726808D03*
Y830758D03*
Y850758D03*
Y954708D03*
X1921395Y-9332D03*
X1931395D03*
Y582868D03*
X1921395D03*
X1931395Y602868D03*
X1921395D03*
Y1195068D03*
X1931395D03*
X1942395Y-9152D03*
Y583048D03*
Y603048D03*
Y1195248D03*
X1963362Y-9190D03*
X1952395Y-9152D03*
X1963362Y583010D03*
X1952395Y583048D03*
X1963362Y603010D03*
X1952395Y603048D03*
X1963362Y1195210D03*
X1952395Y1195248D03*
X1973362Y-9190D03*
Y583010D03*
Y603010D03*
Y1195210D03*
X1994482Y-9180D03*
X1984482D03*
Y583020D03*
X1994482D03*
X1984482Y603020D03*
X1994482D03*
Y1195220D03*
X1984482D03*
X2005452Y-9180D03*
X2015452D03*
Y583020D03*
X2005452D03*
X2015452Y603020D03*
X2005452D03*
Y1195220D03*
X2015452D03*
X2026452Y-9000D03*
Y583200D03*
Y603200D03*
Y1195400D03*
X2047419Y-9038D03*
X2036452Y-9000D03*
X2047419Y583162D03*
X2036452Y583200D03*
X2047419Y603162D03*
X2036452Y603200D03*
X2047419Y1195362D03*
X2036452Y1195400D03*
X2057419Y-9038D03*
Y583162D03*
Y603162D03*
Y1195362D03*
X2068539Y603172D03*
X2078539D03*
Y1195372D03*
X2068539D03*
G54D66*
X1879155Y468898D03*
Y716798D03*
X1889155Y468898D03*
X1900275Y592858D03*
X1889155Y716798D03*
X1900275Y840758D03*
X1910275Y592858D03*
Y840758D03*
X1921395Y1205068D03*
X1931395D03*
X1942395Y593048D03*
X1952395D03*
X1963362Y1205210D03*
X1984482Y593020D03*
X1973362Y1205210D03*
X1994482Y593020D03*
X2005452Y1205220D03*
X2015452D03*
X2026452Y593200D03*
X2036452D03*
X2047419Y1205362D03*
X2057419D03*
G54D46*
X676508Y224606D03*
G54D19*
X36399Y960892D03*
Y957546D03*
Y967585D03*
X52541Y964239D03*
X66099Y816995D03*
Y810302D03*
Y833727D03*
Y823688D03*
Y827034D03*
Y840420D03*
Y960892D03*
Y957546D03*
Y967585D03*
Y1221916D03*
Y1215223D03*
Y1238648D03*
Y1228609D03*
Y1231955D03*
Y1245341D03*
X82241Y813648D03*
Y806955D03*
Y820341D03*
Y830381D03*
Y823688D03*
Y837074D03*
Y964239D03*
Y1218570D03*
Y1211877D03*
Y1225263D03*
Y1241995D03*
Y1235302D03*
Y1228609D03*
X95799Y960892D03*
Y957546D03*
Y967585D03*
Y1054593D03*
X125499Y780184D03*
Y773491D03*
Y786877D03*
Y803609D03*
Y796916D03*
Y790223D03*
Y816995D03*
Y810302D03*
Y833727D03*
Y823688D03*
Y827034D03*
Y847113D03*
Y840420D03*
Y853806D03*
Y860499D03*
Y863845D03*
Y883924D03*
Y877231D03*
Y870538D03*
Y890617D03*
Y897310D03*
Y900656D03*
Y914042D03*
Y907349D03*
Y927428D03*
Y920735D03*
Y934121D03*
Y944160D03*
Y937467D03*
Y960892D03*
Y950853D03*
X111941Y964239D03*
X125499Y957546D03*
Y980971D03*
Y974278D03*
Y967585D03*
Y994357D03*
Y987664D03*
X111941Y1021129D03*
Y1024475D03*
X125499Y1027822D03*
Y1021129D03*
Y1047900D03*
Y1041207D03*
Y1034515D03*
X111941Y1051247D03*
X125499Y1054593D03*
Y1074672D03*
Y1067979D03*
Y1091404D03*
Y1081365D03*
Y1084711D03*
Y1098097D03*
Y1111483D03*
Y1104790D03*
Y1128215D03*
Y1118176D03*
Y1121522D03*
Y1141601D03*
Y1134908D03*
Y1148294D03*
Y1154987D03*
Y1158333D03*
Y1171719D03*
Y1165026D03*
Y1185105D03*
Y1178412D03*
Y1191798D03*
Y1208530D03*
Y1201837D03*
Y1195144D03*
Y1221916D03*
Y1215223D03*
Y1238648D03*
Y1228609D03*
Y1231955D03*
Y1245341D03*
X141641Y770144D03*
Y776837D03*
Y786877D03*
Y783530D03*
Y800263D03*
Y793570D03*
Y813648D03*
Y806955D03*
Y820341D03*
Y830381D03*
Y823688D03*
Y850459D03*
Y843766D03*
Y837074D03*
Y867192D03*
Y860499D03*
Y857152D03*
Y873885D03*
Y880577D03*
Y887270D03*
Y897310D03*
Y893963D03*
Y917389D03*
Y910696D03*
Y904003D03*
Y924081D03*
Y934121D03*
Y930774D03*
Y947507D03*
Y940814D03*
Y964239D03*
Y977625D03*
Y970932D03*
Y991011D03*
Y984318D03*
Y1021129D03*
Y1024475D03*
Y1031168D03*
Y1044554D03*
Y1037861D03*
Y1051247D03*
Y1071326D03*
Y1064633D03*
Y1078018D03*
Y1094751D03*
Y1088058D03*
Y1081365D03*
Y1108137D03*
Y1101444D03*
Y1124869D03*
Y1118176D03*
Y1114829D03*
Y1144948D03*
Y1138255D03*
Y1131562D03*
Y1161680D03*
Y1154987D03*
Y1151641D03*
Y1175066D03*
Y1168373D03*
Y1181759D03*
Y1191798D03*
Y1188452D03*
Y1205184D03*
Y1198491D03*
Y1218570D03*
Y1211877D03*
Y1225263D03*
Y1241995D03*
Y1235302D03*
Y1228609D03*
X155199Y960892D03*
Y957546D03*
Y967585D03*
Y1054593D03*
X171341Y964239D03*
Y1021129D03*
Y1024475D03*
Y1051247D03*
X184899Y780184D03*
Y773491D03*
Y786877D03*
Y803609D03*
Y796916D03*
Y790223D03*
Y816995D03*
Y810302D03*
Y833727D03*
Y823688D03*
Y827034D03*
Y847113D03*
Y840420D03*
Y853806D03*
Y860499D03*
Y863845D03*
Y883924D03*
Y877231D03*
Y870538D03*
Y890617D03*
Y897310D03*
Y900656D03*
Y914042D03*
Y907349D03*
Y927428D03*
Y920735D03*
Y934121D03*
Y944160D03*
Y937467D03*
Y960892D03*
Y950853D03*
Y957546D03*
Y980971D03*
Y974278D03*
Y967585D03*
Y994357D03*
Y987664D03*
Y1027822D03*
Y1021129D03*
Y1047900D03*
Y1041207D03*
Y1034515D03*
Y1054593D03*
Y1074672D03*
Y1067979D03*
Y1091404D03*
Y1081365D03*
Y1084711D03*
Y1098097D03*
Y1111483D03*
Y1104790D03*
Y1128215D03*
Y1118176D03*
Y1121522D03*
Y1141601D03*
Y1134908D03*
Y1148294D03*
Y1154987D03*
Y1158333D03*
Y1171719D03*
Y1165026D03*
Y1185105D03*
Y1178412D03*
Y1191798D03*
Y1208530D03*
Y1201837D03*
Y1195144D03*
Y1221916D03*
Y1215223D03*
Y1238648D03*
Y1228609D03*
Y1231955D03*
Y1245341D03*
X201041Y770144D03*
Y776837D03*
Y786877D03*
Y783530D03*
Y800263D03*
Y793570D03*
Y813648D03*
Y806955D03*
Y820341D03*
Y830381D03*
Y823688D03*
Y850459D03*
Y843766D03*
Y837074D03*
Y867192D03*
Y860499D03*
Y857152D03*
Y873885D03*
Y880577D03*
Y887270D03*
Y897310D03*
Y893963D03*
Y917389D03*
Y910696D03*
Y904003D03*
Y924081D03*
Y934121D03*
Y930774D03*
Y947507D03*
Y940814D03*
Y964239D03*
Y977625D03*
Y970932D03*
Y991011D03*
Y984318D03*
X201141Y1021129D03*
Y1024475D03*
Y1031168D03*
Y1044554D03*
Y1037861D03*
Y1051247D03*
Y1071326D03*
Y1064633D03*
Y1078018D03*
Y1094752D03*
Y1088059D03*
Y1081366D03*
Y1108137D03*
Y1101444D03*
X201041Y1124869D03*
X201141Y1118177D03*
Y1114830D03*
Y1144948D03*
Y1138255D03*
X201041Y1131562D03*
X201141Y1161680D03*
Y1154988D03*
Y1151641D03*
Y1175066D03*
Y1168373D03*
Y1181759D03*
Y1191799D03*
Y1188452D03*
Y1205184D03*
Y1198491D03*
Y1218570D03*
Y1211877D03*
Y1225263D03*
Y1241995D03*
Y1235302D03*
Y1228609D03*
X214599Y960892D03*
Y957546D03*
X244299Y883924D03*
Y890617D03*
Y897310D03*
Y900656D03*
Y914042D03*
Y907349D03*
Y960892D03*
Y957546D03*
Y1185105D03*
Y1178412D03*
Y1191798D03*
Y1208530D03*
Y1201837D03*
Y1195144D03*
X260441Y880577D03*
Y887270D03*
Y897310D03*
Y893963D03*
Y910696D03*
Y904003D03*
Y1175066D03*
Y1181759D03*
Y1191798D03*
Y1188452D03*
Y1205184D03*
Y1198491D03*
X337779Y880219D03*
X335928Y883423D03*
X337779Y893036D03*
X335928Y889832D03*
X334079Y886627D03*
X337779D03*
X350727Y851380D03*
X354427Y844971D03*
X348878Y848176D03*
X352578D03*
X350729Y857789D03*
X352578Y860993D03*
X354429Y857789D03*
X341479Y880219D03*
X343329Y883423D03*
X348878Y899445D03*
Y893036D03*
X350729Y889832D03*
X354429D03*
X341478Y893036D03*
X343328Y889832D03*
X347029Y896240D03*
X354429D03*
X341479Y886627D03*
X350729Y896240D03*
X345179Y886627D03*
X348878Y912262D03*
X350729Y909057D03*
X354429D03*
X350729Y902649D03*
X354429D03*
X347029Y915466D03*
X354429D03*
X350729D03*
X348879Y931488D03*
X350729Y928283D03*
X354429D03*
Y921875D03*
X350729D03*
X348878Y918670D03*
X350729Y941100D03*
X348878Y937896D03*
X354429Y941100D03*
X347029Y934691D03*
X354429D03*
X350729D03*
Y947509D03*
X354429D03*
X348878Y950713D03*
X350729Y960326D03*
X348878Y957122D03*
X354429Y960326D03*
X350729Y966735D03*
X354429D03*
X350729Y953917D03*
X354429D03*
X347030D03*
X350729Y979552D03*
X354429D03*
X348878Y976347D03*
X347029Y973143D03*
X348878Y969939D03*
X347461Y1006093D03*
X349311Y1002888D03*
X351161Y999684D03*
X354861D03*
X351161Y1012501D03*
X349311Y1009297D03*
X354861Y1012501D03*
X351162Y1031727D03*
X349311Y1028523D03*
X354861Y1031727D03*
X349311Y1022114D03*
X351161Y1018910D03*
X354861D03*
X347461Y1025318D03*
X354862D03*
X351162D03*
X349311Y1047749D03*
Y1041340D03*
X351161Y1038136D03*
X354861D03*
X347461Y1044544D03*
X354861D03*
X351161D03*
X349311Y1060565D03*
X351161Y1057361D03*
X354861D03*
X347461Y1063770D03*
X351161D03*
X354861D03*
X351161Y1050952D03*
X354861D03*
Y1070178D03*
X351162D03*
X349311Y1066974D03*
Y1079791D03*
X351161Y1076587D03*
X354861D03*
X351161Y1089404D03*
X349311Y1086200D03*
X354861Y1089404D03*
X347461Y1082995D03*
X354861D03*
X351161D03*
X341911Y1105426D03*
X343762Y1108630D03*
X345611Y1111834D03*
X351161Y1102221D03*
X349312Y1111834D03*
X353011Y1105426D03*
X345611D03*
X341912Y1111834D03*
X354861Y1102221D03*
X353012Y1111834D03*
X351162Y1108630D03*
X353011Y1124651D03*
X354861Y1127856D03*
X347461Y1115039D03*
X349312Y1137469D03*
X351161Y1134264D03*
X356279Y841467D03*
X361827Y844971D03*
X363679Y841467D03*
X369227Y844971D03*
X371079Y841467D03*
X358127Y844971D03*
X359978Y848176D03*
X365527Y844971D03*
X367378Y848176D03*
X356278Y854584D03*
X358129Y857789D03*
X363678Y854584D03*
X365529Y857789D03*
X371078Y854584D03*
X359978Y860993D03*
X361829Y857789D03*
X367378Y860993D03*
X369229Y857789D03*
X356278Y899445D03*
Y893036D03*
X358129Y896240D03*
X363678Y899445D03*
X367378D03*
X371078Y893036D03*
X356278Y912262D03*
X358129Y915466D03*
X363678Y912262D03*
X361829Y909057D03*
X367378Y912262D03*
X369229Y909057D03*
X361829Y902649D03*
X369229D03*
X359978Y905853D03*
X367378D03*
X363678D03*
X371078D03*
X356278Y931488D03*
X363678D03*
X356278Y918670D03*
X361829Y928283D03*
X367378Y931488D03*
X369229Y928283D03*
X361829Y921875D03*
X363678Y918670D03*
X369229Y921875D03*
X367378Y918670D03*
X359978Y925079D03*
X367378D03*
X363678D03*
X371078D03*
X356278Y937896D03*
X358129Y934691D03*
X361829Y941100D03*
X363678Y937896D03*
X369229Y941100D03*
X367378Y937896D03*
X361829Y947509D03*
X369229D03*
X367378Y944304D03*
X359978D03*
X371078D03*
X363678D03*
X356278Y950713D03*
Y957122D03*
X358129Y953917D03*
X361829Y966735D03*
X369229D03*
X359978Y963530D03*
X363678Y950713D03*
X367378D03*
X361829Y960326D03*
X363678Y957122D03*
X369229Y960326D03*
X367378Y957122D03*
X371078Y963530D03*
X359978Y982756D03*
X367378D03*
X363678D03*
X371078D03*
X369229Y979552D03*
X367378Y976347D03*
X361829Y979552D03*
X363678Y976347D03*
X356278D03*
Y969939D03*
X358129Y973143D03*
X363678Y969939D03*
X367378D03*
X358562Y1006093D03*
X356711Y1002888D03*
Y1009297D03*
X362262Y1012501D03*
X369662D03*
X364111Y1009297D03*
X367811D03*
X364111Y1002888D03*
X362262Y999684D03*
X371511Y1002888D03*
X369662Y999684D03*
X356711Y1028523D03*
Y1022114D03*
X362262Y1031727D03*
X364111Y1028523D03*
X369662Y1031727D03*
X367811Y1028523D03*
X358562Y1025318D03*
X360411Y1015705D03*
X371511D03*
X364111Y1022114D03*
X362262Y1018910D03*
X367811Y1022114D03*
X369662Y1018910D03*
X356711Y1047749D03*
Y1041340D03*
X364111D03*
X362262Y1038136D03*
X367811Y1041340D03*
X369662Y1038136D03*
X360411Y1034931D03*
X371511D03*
X364111D03*
X358562Y1044544D03*
X367811Y1034931D03*
X364111Y1047749D03*
X367811D03*
X356711Y1060565D03*
X358562Y1063770D03*
X364111Y1060565D03*
X362262Y1057361D03*
X367811Y1060565D03*
X369662Y1057361D03*
X362262Y1050952D03*
X369662D03*
X360411Y1054157D03*
X371511D03*
X364111D03*
X367811D03*
X356711Y1066974D03*
X367811Y1079791D03*
X369662Y1076587D03*
X362262Y1070178D03*
X364111Y1066974D03*
X369662Y1070178D03*
X367811Y1066974D03*
X356711Y1079791D03*
X364111D03*
X362262Y1076587D03*
X360411Y1073383D03*
X371511D03*
X364111D03*
X367811D03*
X356711Y1086200D03*
X358562Y1082995D03*
X362262Y1095813D03*
X369662D03*
X362262Y1089404D03*
X364111Y1086200D03*
X369662Y1089404D03*
X367811Y1086200D03*
X360411Y1092608D03*
X367811D03*
X364111D03*
X371511D03*
X364111Y1099017D03*
X367811D03*
X358561Y1121447D03*
X360412Y1124651D03*
X364111D03*
X367811D03*
X371511D03*
X356712D03*
X362262Y1127856D03*
X365962Y1121447D03*
X369662Y1127856D03*
X358561Y1134264D03*
X362261Y1140973D03*
X365962Y1134264D03*
X369661Y1140973D03*
X356712Y1137469D03*
X360412D03*
X364112D03*
X367812D03*
X371512D03*
X387727Y844971D03*
X376627D03*
X380327D03*
X384027D03*
X385879Y841467D03*
X372927Y844971D03*
X374778Y848176D03*
X378479Y841467D03*
X382178Y848176D03*
X387729Y857789D03*
X372929D03*
X378478Y854584D03*
X380329Y857789D03*
X384029D03*
X374778Y860993D03*
X376629Y857789D03*
X382178Y860993D03*
X385878Y854584D03*
X374778Y899445D03*
X382178D03*
Y893036D03*
X374778D03*
X385878D03*
X372929Y896240D03*
X380329D03*
X376629D03*
X384029D03*
X376629Y902649D03*
X380329D03*
X374778Y912262D03*
X376629Y909057D03*
X382178Y912262D03*
X380329Y909057D03*
X372929Y915466D03*
X380329D03*
X376629D03*
X384029D03*
X374778Y931488D03*
X376629Y928283D03*
X382178Y931488D03*
X380329Y928283D03*
X376629Y921875D03*
X374778Y918670D03*
X380329Y921875D03*
X382178Y918670D03*
X380329Y941100D03*
X382178Y937896D03*
X376629Y947509D03*
X380329D03*
X376629Y941100D03*
X374778Y937896D03*
X372929Y934691D03*
X380329D03*
X376629D03*
X384029D03*
X376629Y960326D03*
X374778Y957122D03*
X380329Y960326D03*
X382178Y957122D03*
X374778Y950713D03*
X382178D03*
X372929Y953917D03*
X380329D03*
X376629D03*
X384029D03*
X380329Y966735D03*
X376629D03*
X374778Y969939D03*
X382178D03*
X373362Y1006093D03*
X380762D03*
X377062D03*
X384462D03*
X375211Y1002888D03*
X377062Y999684D03*
X382611Y1002888D03*
X380762Y999684D03*
X377062Y1012501D03*
X375211Y1009297D03*
X380762Y1012501D03*
X382611Y1009297D03*
X377062Y1031727D03*
X375211Y1028523D03*
X380762Y1031727D03*
X382611Y1028523D03*
X375211Y1022114D03*
X377062Y1018910D03*
X382611Y1022114D03*
X380762Y1018910D03*
X377062Y1025318D03*
X384462D03*
X373360D03*
X380760D03*
X375211Y1047749D03*
X382611D03*
X375211Y1041340D03*
X377062Y1038136D03*
X382611Y1041340D03*
X380762Y1038136D03*
X373362Y1044544D03*
X380762D03*
X377062D03*
X384462D03*
X375211Y1060565D03*
X377062Y1057361D03*
X382611Y1060565D03*
X380762Y1057361D03*
X377062Y1050952D03*
X380762D03*
X373362Y1063770D03*
X384462D03*
X377062D03*
X380762D03*
Y1070178D03*
X382611Y1066974D03*
X377062Y1070178D03*
X375211Y1066974D03*
Y1079791D03*
X377062Y1076587D03*
X382611Y1079791D03*
X380762Y1076587D03*
X377062Y1089404D03*
X375211Y1086200D03*
X380762Y1089404D03*
X382611Y1086200D03*
X373362Y1082995D03*
X384462D03*
X377062D03*
X380762D03*
X386311Y1105426D03*
X382611Y1111834D03*
X375211Y1105426D03*
X377062Y1108630D03*
X380762Y1102221D03*
X378911Y1111834D03*
X384462Y1108630D03*
X386311Y1111834D03*
X378912Y1105426D03*
X375211Y1111834D03*
X382611Y1105426D03*
X375211Y1124651D03*
X378911D03*
X382611D03*
X386311D03*
X373362Y1121447D03*
X377062Y1127856D03*
X380762Y1121447D03*
X384462Y1127856D03*
X380762Y1115039D03*
X373362Y1134264D03*
X377061Y1140973D03*
X380762Y1134264D03*
X384461Y1140973D03*
X375212Y1137469D03*
X378912D03*
X382612D03*
X386312D03*
X391427Y844971D03*
X395127D03*
X398827D03*
X400679Y841467D03*
X389578Y848176D03*
X393279Y841467D03*
X396978Y848176D03*
X402527Y844971D03*
X393278Y854584D03*
X395129Y857789D03*
X400678Y854584D03*
X402529Y857789D03*
X389578Y860993D03*
X391429Y857789D03*
X396978Y860993D03*
X398829Y857789D03*
Y973143D03*
X400678Y976347D03*
X402529Y979552D03*
Y973143D03*
X390011Y1002888D03*
X388162Y999684D03*
X393711Y1002888D03*
X395562Y999684D03*
X402962Y1082995D03*
X402961Y1089404D03*
X390011Y1124651D03*
X395562Y1121447D03*
X397411Y1124651D03*
X401111D03*
X391862Y1127856D03*
X393711Y1124651D03*
X399262Y1127856D03*
X402962Y1121447D03*
X388162D03*
X391861Y1140973D03*
X395562Y1134264D03*
X399261Y1140973D03*
X402962Y1134264D03*
X388162D03*
X390012Y1137469D03*
X393712D03*
X397412D03*
X401112D03*
X406227Y844971D03*
X409927D03*
X413627D03*
X417327D03*
X404378Y848176D03*
X408079Y841467D03*
X411778Y848176D03*
X415479Y841467D03*
X419178Y848176D03*
X408078Y854584D03*
X409929Y857789D03*
X415478Y854584D03*
X417329Y857789D03*
X404378Y860993D03*
X406229Y857789D03*
X411778Y860993D03*
X413629Y857789D03*
X419178Y860993D03*
X417329Y883423D03*
X415478Y880219D03*
X413629Y883423D03*
X419178Y886627D03*
X408511Y1079791D03*
X406662Y1089404D03*
X410362D03*
X404811Y1086200D03*
X419611D03*
X414062Y1082995D03*
X410362D03*
X406662D03*
X408511Y1092608D03*
X414062Y1089404D03*
X419611Y1092608D03*
X412211Y1086200D03*
X404811Y1124651D03*
X408511D03*
X406662Y1127856D03*
X410362Y1121447D03*
X406661Y1140973D03*
X410362Y1134264D03*
X404812Y1137469D03*
X408512D03*
X421027Y844971D03*
X424727D03*
X428427D03*
X433978Y848176D03*
X435829Y844671D03*
X422879Y841467D03*
X426578Y848176D03*
X430278D03*
X422878Y854584D03*
X424729Y857789D03*
X430278Y854584D03*
X433979Y860993D03*
X421029Y857789D03*
X426578Y860993D03*
X428429Y857789D03*
X432129D03*
X435829D03*
X432129Y883423D03*
X430278Y880219D03*
X424729Y883423D03*
X422878Y880219D03*
X428429Y883423D03*
X421029D03*
X435829D03*
X433978Y886627D03*
X426578D03*
X421462Y1089404D03*
X423311Y1092608D03*
X427011D03*
X430710Y1086200D03*
X425162Y1082995D03*
Y1095813D03*
X430711Y1092608D03*
X423311Y1086200D03*
X428861Y1089404D03*
X427012Y1086200D03*
X450628Y844971D03*
X446927Y844671D03*
X452479Y841467D03*
X448778Y848176D03*
X443227Y844671D03*
X437678Y848176D03*
X437679Y854584D03*
X452478D03*
X450629Y857789D03*
X445078Y854584D03*
X443229Y857789D03*
X448779Y860993D03*
X446929Y857789D03*
X441378Y860993D03*
X452479Y880219D03*
X446929Y883423D03*
X445078Y880219D03*
X439529Y883423D03*
X437678Y880219D03*
X450629Y883423D03*
X443229D03*
X448778Y886627D03*
X441378D03*
X467279Y841467D03*
X463578Y848176D03*
X459879Y841467D03*
X458027Y844971D03*
X454327D03*
X469127D03*
X465427D03*
X461727D03*
X456178Y848176D03*
X467278Y854584D03*
X465429Y857789D03*
X459878Y854584D03*
X458029Y857789D03*
X469129D03*
X463578Y860993D03*
X461729Y857789D03*
X456178Y860993D03*
X454329Y857789D03*
X469129Y883423D03*
X467278Y880219D03*
X461729Y883423D03*
X459878Y880219D03*
X454329Y883423D03*
X465429D03*
X458029D03*
X463578Y886627D03*
X456178D03*
X483927Y844971D03*
X480227D03*
X476527D03*
X470978Y848176D03*
X482079Y841467D03*
X478378Y848176D03*
X474679Y841467D03*
X472827Y844971D03*
X482078Y854584D03*
X480229Y857789D03*
X474678Y854584D03*
X472829Y857789D03*
X483929D03*
X478378Y860993D03*
X476529Y857789D03*
X470978Y860993D03*
Y886627D03*
X484362Y1121447D03*
X480662Y1127856D03*
X476962Y1121447D03*
X473262Y1127856D03*
X469562Y1121447D03*
X482511Y1124651D03*
X478811D03*
X475111D03*
X471411D03*
X484362Y1134264D03*
X482512Y1137469D03*
X476962Y1134264D03*
X475112Y1137469D03*
X480661Y1140973D03*
X478812Y1137469D03*
X473261Y1140973D03*
X493178Y848176D03*
X489478Y841467D03*
X487627Y844971D03*
X500578Y848176D03*
X496878Y841467D03*
X495027Y844971D03*
X491327D03*
X485778Y848176D03*
X498727Y844971D03*
X489478Y854584D03*
X487629Y857789D03*
X500578Y860993D03*
X498729Y857789D03*
X495029D03*
X491329D03*
X485778Y860993D03*
X496878Y854584D03*
X493178Y860993D03*
X500578Y899445D03*
Y912262D03*
X498729Y909057D03*
Y902649D03*
X500578Y905853D03*
X496878D03*
X500578Y931488D03*
X498729Y921875D03*
X500578Y918670D03*
X498729Y928283D03*
X496878Y925079D03*
X500578D03*
X498729Y947509D03*
Y941100D03*
X500578Y937896D03*
X496878Y944304D03*
X500578D03*
Y950713D03*
Y957122D03*
X498729Y960326D03*
X487629Y979552D03*
X485778Y976347D03*
X491329Y979552D03*
X493178Y976347D03*
X500578Y982756D03*
X496878D03*
X498729Y979552D03*
X500578Y976347D03*
X501011Y1002888D03*
X499162Y999684D03*
Y1012501D03*
X501011Y1009297D03*
X497311Y1015705D03*
X499162Y1031727D03*
X501011Y1028523D03*
Y1022114D03*
X499162Y1018910D03*
X501011Y1041340D03*
X499162Y1038136D03*
X501011Y1047749D03*
Y1034931D03*
X497311D03*
X501011Y1060565D03*
X499162Y1057361D03*
Y1050952D03*
X501011Y1054157D03*
X497311D03*
X499162Y1070178D03*
X501011Y1066974D03*
Y1079791D03*
X499162Y1076587D03*
X497311Y1073383D03*
X501011D03*
X499162Y1089404D03*
X501011Y1086200D03*
X497311Y1092608D03*
X501011D03*
X488062Y1127856D03*
X499162Y1121447D03*
X495462Y1127856D03*
X491762Y1121447D03*
X489911Y1124651D03*
X486211D03*
X501011D03*
X497311D03*
X493611D03*
X493612Y1137469D03*
X488061Y1140973D03*
X501012Y1137469D03*
X495461Y1140973D03*
X491762Y1134264D03*
X489912Y1137469D03*
X486212D03*
X499162Y1134264D03*
X497312Y1137469D03*
X517227Y844971D03*
X511679Y841467D03*
X509827Y844971D03*
X504279Y841467D03*
X515378Y848176D03*
X513527Y844971D03*
X507978Y848176D03*
X506127Y844971D03*
X502427D03*
X517229Y857789D03*
X513529D03*
X509829D03*
X506129D03*
X515378Y860993D03*
X511678Y854584D03*
X507978Y860993D03*
X504278Y854584D03*
X502429Y857789D03*
X511678Y899445D03*
Y893036D03*
X507978D03*
X509829Y896240D03*
X517229D03*
X513529D03*
X504278Y899445D03*
X513529Y902649D03*
X517229D03*
X511678Y912262D03*
X513529Y909057D03*
X517229D03*
X513529Y915466D03*
X509829D03*
X517229D03*
X504278Y912262D03*
X506129Y909057D03*
Y902649D03*
X507978Y905853D03*
X504278D03*
X511678Y931488D03*
X513529Y928283D03*
X517229D03*
X506129D03*
Y921875D03*
X504278Y918670D03*
X513529Y921875D03*
X511678Y918670D03*
X517229Y921875D03*
X504278Y931488D03*
Y925079D03*
X507978D03*
X513529Y941100D03*
X511678Y937896D03*
X517229Y941100D03*
X513529Y934691D03*
X509829D03*
X517229D03*
X513529Y947509D03*
X517229D03*
X506129D03*
Y941100D03*
X504278Y937896D03*
X507978Y944304D03*
X504278D03*
X511678Y950713D03*
X513529Y960326D03*
X511678Y957122D03*
X517229Y960326D03*
Y966735D03*
X513529D03*
X504278Y950713D03*
X513529Y953917D03*
X517229D03*
X509829D03*
X504278Y957122D03*
X506129Y960326D03*
X507978Y982756D03*
X504278D03*
Y976347D03*
X506129Y979552D03*
X513529D03*
X517229D03*
X511678Y976347D03*
X509829Y973143D03*
X511678Y969939D03*
X517662Y1006093D03*
X513962D03*
X510262D03*
X517662Y1012501D03*
X504711Y1002888D03*
X506561Y999684D03*
X513962Y1012501D03*
X512111Y1009297D03*
X506562Y1012501D03*
X504711Y1009297D03*
X517661Y999684D03*
X512111Y1002888D03*
X513962Y999684D03*
Y1031727D03*
X512111Y1028523D03*
X517662Y1031727D03*
X512111Y1022114D03*
X513962Y1018910D03*
X517662D03*
X513962Y1025318D03*
X510262D03*
X517662D03*
X508411Y1015705D03*
X506562Y1031727D03*
X504711Y1028523D03*
Y1022114D03*
X506562Y1018910D03*
X504711Y1041340D03*
X506562Y1038136D03*
X512111Y1047749D03*
Y1041340D03*
X513962Y1038136D03*
X517662D03*
X504711Y1047749D03*
X510262Y1044544D03*
X508411Y1034931D03*
X513962Y1044544D03*
X517662D03*
X504711Y1034931D03*
X512111Y1060565D03*
X513962Y1057361D03*
X517662D03*
X510262Y1063770D03*
X513962D03*
X517662D03*
X513962Y1050952D03*
X517662D03*
X504711Y1060565D03*
X506562Y1057361D03*
Y1050952D03*
X508411Y1054157D03*
X504711D03*
X517662Y1070178D03*
X513962D03*
X512111Y1066974D03*
X504711Y1079791D03*
X506562Y1076587D03*
Y1070178D03*
X504711Y1066974D03*
X512111Y1079791D03*
X513962Y1076587D03*
X517662D03*
X508411Y1073383D03*
X504711D03*
X513962Y1089404D03*
X512111Y1086200D03*
X517662Y1089404D03*
X513962Y1082995D03*
X510262D03*
X517662D03*
X510262Y1095813D03*
X506561D03*
X506562Y1089404D03*
X504711Y1086200D03*
X508411Y1092608D03*
X504711D03*
X517662Y1102221D03*
X515811Y1099017D03*
X517662Y1127856D03*
X513962Y1121447D03*
X510262Y1127856D03*
X506562Y1121447D03*
X502862Y1127856D03*
X515811Y1124651D03*
X512111D03*
X508411D03*
X504711D03*
X517661Y1140973D03*
X513962Y1134264D03*
X512112Y1137469D03*
X506562Y1134264D03*
X504712Y1137469D03*
X515812D03*
X510261Y1140973D03*
X508412Y1137469D03*
X502861Y1140973D03*
X532028Y844671D03*
X526478Y848176D03*
X524627Y844971D03*
X519079Y841467D03*
X533878Y848176D03*
X530178D03*
X522778D03*
X520927Y844971D03*
X532029Y864197D03*
X533879Y854584D03*
X528329Y857789D03*
X522778Y860993D03*
X520929Y857789D03*
X526478Y854584D03*
X524629Y857789D03*
X519078Y854584D03*
X526479Y899445D03*
X530178D03*
X519078D03*
Y893036D03*
X522778D03*
X520929Y896240D03*
X530179Y912262D03*
X532029Y909057D03*
X524629Y902649D03*
X532029D03*
X526479Y912262D03*
X524629Y909057D03*
X526479Y905853D03*
X533879D03*
X522778D03*
X530179D03*
X519078Y912262D03*
X520929Y915466D03*
X526479Y931488D03*
X524629Y928283D03*
X530179Y931488D03*
X532029Y928283D03*
X524629Y921875D03*
X526479Y918670D03*
X532029Y921875D03*
X530179Y918670D03*
X526479Y925079D03*
X533879D03*
X522778D03*
X530179D03*
X519078Y931488D03*
Y918670D03*
X524629Y941100D03*
X526479Y937896D03*
X532029Y941100D03*
X530179Y937896D03*
X524629Y947509D03*
X532029D03*
X519078Y937896D03*
X533879Y944304D03*
X520929Y934691D03*
X526479Y944304D03*
X530178D03*
X522778D03*
X524629Y966735D03*
X532029D03*
X522778Y963530D03*
X526479Y950713D03*
X530178D03*
X532029Y960326D03*
X530178Y957122D03*
X524629Y960326D03*
X526479Y957122D03*
X533879Y963530D03*
X519078Y950713D03*
Y957122D03*
X520929Y953917D03*
X526479Y969939D03*
X530179D03*
X519078Y976347D03*
Y969939D03*
X520929Y973143D03*
X521362Y1006093D03*
X525062Y1012501D03*
X532461D03*
X526911Y1009297D03*
X530611D03*
X519511D03*
X519513Y1002888D03*
X530611D03*
X532461Y999684D03*
X526911Y1002888D03*
X525062Y999684D03*
X523211Y1015705D03*
X534311D03*
X525062Y1031727D03*
X526911Y1028523D03*
X532461Y1031727D03*
X530611Y1028523D03*
Y1022114D03*
X532461Y1018910D03*
X526911Y1022114D03*
X525062Y1018910D03*
X519511Y1028523D03*
Y1022114D03*
X521362Y1025318D03*
X526911Y1041340D03*
X525062Y1038136D03*
X530611Y1041340D03*
X532461Y1038136D03*
X526911Y1047749D03*
X530611D03*
X526911Y1034931D03*
X534311D03*
X523211D03*
X530611D03*
X519511Y1047749D03*
Y1041340D03*
X521362Y1044544D03*
X519511Y1060565D03*
X526911D03*
X525062Y1057361D03*
X530611Y1060565D03*
X532462Y1057361D03*
X525061Y1050952D03*
X532462Y1050953D03*
X523211Y1054157D03*
X521362Y1063770D03*
X534311Y1054157D03*
X526911D03*
X530611D03*
Y1079791D03*
X532462Y1076587D03*
X525062Y1070178D03*
X526911Y1066974D03*
X532462Y1070178D03*
X530611Y1066974D03*
X526911Y1079791D03*
X525062Y1076587D03*
X523211Y1073383D03*
X534311D03*
X526911D03*
X530611D03*
X519511Y1066974D03*
Y1079791D03*
X521362Y1095813D03*
X532461D03*
X525062D03*
Y1089404D03*
X526911Y1086200D03*
X532462Y1089404D03*
X530611Y1086200D03*
X526911Y1092608D03*
X534310D03*
X523211D03*
X530611D03*
X519511Y1086200D03*
X521362Y1082995D03*
X530611Y1099017D03*
X526911Y1124651D03*
X521362Y1121447D03*
X525062Y1127856D03*
X523211Y1124651D03*
X519511D03*
X532462Y1134264D03*
X525061Y1140973D03*
X523212Y1137469D03*
X534312D03*
X526912D03*
X521362Y1134264D03*
X519512Y1137469D03*
X543129Y851380D03*
X539429D03*
X535729Y864197D03*
X543128D03*
X546828D03*
X535729Y857789D03*
X543130D03*
X539429D03*
X541279Y860993D03*
Y854584D03*
X539429Y883423D03*
X537578Y880219D03*
X543129Y883423D03*
X544979Y880219D03*
X537578Y873810D03*
X539429Y870606D03*
X544979Y873810D03*
X543129Y870606D03*
X539428Y877014D03*
X546828D03*
X535729D03*
X543129D03*
X620799Y883924D03*
Y890617D03*
Y897310D03*
Y900656D03*
Y914042D03*
Y907349D03*
Y960892D03*
Y957546D03*
Y1185105D03*
Y1178412D03*
Y1191798D03*
Y1208530D03*
Y1201837D03*
Y1195144D03*
X636941Y880577D03*
Y887270D03*
Y897310D03*
Y893963D03*
Y910696D03*
Y904003D03*
Y1175066D03*
Y1181759D03*
Y1191798D03*
Y1188451D03*
Y1205184D03*
Y1198491D03*
X650499Y960892D03*
Y957546D03*
X680299Y780184D03*
Y773491D03*
Y786877D03*
Y803609D03*
Y796916D03*
Y790223D03*
Y816995D03*
Y810302D03*
Y833727D03*
Y823688D03*
Y827034D03*
Y847113D03*
Y840420D03*
Y853806D03*
Y860499D03*
Y863845D03*
Y883924D03*
Y877231D03*
Y870538D03*
Y890617D03*
Y897310D03*
Y900656D03*
Y914042D03*
Y907349D03*
Y927428D03*
Y920735D03*
Y934121D03*
Y944160D03*
Y937467D03*
Y960892D03*
Y950853D03*
Y957546D03*
Y980971D03*
Y974278D03*
Y967585D03*
Y994357D03*
Y987664D03*
X679999Y1027822D03*
X680299Y1021129D03*
X679999Y1047900D03*
Y1041207D03*
Y1034514D03*
Y1054593D03*
X680299Y1074672D03*
Y1067979D03*
Y1091404D03*
Y1081365D03*
Y1084711D03*
Y1098097D03*
Y1111483D03*
Y1104790D03*
Y1128215D03*
Y1118176D03*
Y1121522D03*
Y1141601D03*
Y1134908D03*
Y1148294D03*
Y1154987D03*
Y1158333D03*
Y1171719D03*
Y1165026D03*
Y1185105D03*
Y1178412D03*
Y1191798D03*
Y1208530D03*
Y1201837D03*
Y1195144D03*
Y1221916D03*
Y1215223D03*
Y1238648D03*
Y1228609D03*
Y1231955D03*
Y1245341D03*
X696441Y770144D03*
Y776837D03*
Y786877D03*
Y783530D03*
Y800263D03*
Y793570D03*
Y813648D03*
Y806955D03*
Y820341D03*
Y830381D03*
Y823688D03*
Y850459D03*
Y843766D03*
Y837074D03*
Y867192D03*
Y860499D03*
Y857152D03*
Y873885D03*
Y880577D03*
Y887270D03*
Y897310D03*
Y893963D03*
Y917389D03*
Y910696D03*
Y904003D03*
Y924081D03*
Y934121D03*
Y930774D03*
Y947507D03*
Y940814D03*
Y964239D03*
Y977625D03*
Y970932D03*
Y991011D03*
Y984318D03*
Y1021129D03*
Y1024475D03*
Y1031168D03*
X696141Y1044554D03*
Y1037861D03*
X696441Y1051247D03*
Y1071325D03*
Y1064633D03*
Y1078018D03*
Y1094751D03*
Y1088058D03*
Y1081365D03*
Y1108136D03*
Y1101444D03*
Y1124869D03*
Y1118176D03*
Y1114829D03*
Y1144947D03*
Y1138255D03*
Y1131562D03*
Y1161680D03*
Y1154987D03*
Y1151640D03*
Y1175066D03*
Y1168373D03*
Y1181758D03*
Y1191798D03*
Y1188451D03*
Y1205184D03*
Y1198491D03*
Y1218569D03*
Y1211877D03*
Y1225262D03*
Y1241995D03*
Y1235302D03*
Y1228609D03*
X709899Y960892D03*
Y957546D03*
X709999Y967585D03*
Y1054593D03*
X726141Y964239D03*
Y1021129D03*
Y1024475D03*
Y1051247D03*
X739699Y780184D03*
Y773491D03*
Y786877D03*
Y803609D03*
Y796916D03*
Y790223D03*
Y816995D03*
Y810302D03*
Y833727D03*
Y823688D03*
Y827034D03*
Y847113D03*
Y840420D03*
Y853806D03*
Y860499D03*
Y863845D03*
Y883924D03*
Y877231D03*
Y870538D03*
Y890617D03*
Y897310D03*
Y900656D03*
Y914042D03*
Y907349D03*
Y927428D03*
Y920735D03*
Y934121D03*
Y944160D03*
Y937467D03*
Y960892D03*
Y950853D03*
Y957546D03*
Y980971D03*
Y974278D03*
Y967585D03*
Y994357D03*
Y987664D03*
Y1027822D03*
Y1021129D03*
Y1047900D03*
Y1041207D03*
Y1034514D03*
Y1054593D03*
Y1074672D03*
Y1067979D03*
Y1091404D03*
Y1081365D03*
Y1084711D03*
Y1098097D03*
Y1111483D03*
Y1104790D03*
Y1128215D03*
Y1118176D03*
Y1121522D03*
Y1141601D03*
Y1134908D03*
Y1148294D03*
Y1154987D03*
Y1158333D03*
Y1171719D03*
Y1165026D03*
Y1185105D03*
Y1178412D03*
Y1191798D03*
Y1208530D03*
Y1201837D03*
Y1195144D03*
Y1221916D03*
Y1215223D03*
Y1238648D03*
Y1228609D03*
Y1231955D03*
Y1245341D03*
X755841Y770144D03*
Y776837D03*
Y786877D03*
Y783530D03*
Y800263D03*
Y793570D03*
Y813648D03*
Y806955D03*
Y820341D03*
Y830381D03*
Y823688D03*
Y850459D03*
Y843766D03*
Y837074D03*
Y867192D03*
Y860499D03*
Y857152D03*
Y873885D03*
Y880577D03*
Y887270D03*
Y897310D03*
Y893963D03*
Y917389D03*
Y910696D03*
Y904003D03*
Y924081D03*
Y934121D03*
Y930774D03*
Y947507D03*
Y940814D03*
Y964239D03*
Y977625D03*
X755741Y970932D03*
X755841Y991011D03*
Y984318D03*
Y1021129D03*
Y1024475D03*
Y1031168D03*
X755541Y1044554D03*
Y1037861D03*
X755841Y1051247D03*
X755676Y1071326D03*
X755741Y1064633D03*
X755841Y1078018D03*
Y1094751D03*
Y1088058D03*
Y1081365D03*
X755676Y1108137D03*
X755841Y1101444D03*
Y1124869D03*
Y1118176D03*
Y1114829D03*
Y1144947D03*
Y1138255D03*
Y1131562D03*
Y1161680D03*
Y1154987D03*
Y1151640D03*
Y1175066D03*
Y1168373D03*
X755676Y1181759D03*
X755841Y1191798D03*
X755676Y1188452D03*
X755841Y1205184D03*
Y1198491D03*
Y1218569D03*
Y1211877D03*
Y1225262D03*
Y1241995D03*
Y1235302D03*
Y1228609D03*
X769399Y960892D03*
Y957546D03*
Y967585D03*
Y1054593D03*
X785541Y964239D03*
Y1021129D03*
Y1024475D03*
Y1051247D03*
X799099Y816995D03*
Y810302D03*
Y833727D03*
Y823688D03*
Y827034D03*
Y840420D03*
Y960892D03*
Y957546D03*
Y967585D03*
Y1221916D03*
Y1215223D03*
Y1238648D03*
Y1228609D03*
Y1231955D03*
Y1245341D03*
X815241Y813648D03*
Y806955D03*
Y820341D03*
Y830381D03*
Y823688D03*
Y837074D03*
Y964239D03*
Y1218570D03*
Y1211877D03*
Y1225263D03*
Y1241995D03*
Y1235302D03*
Y1228609D03*
X828799Y960892D03*
Y957546D03*
Y967585D03*
X844941Y964239D03*
X1012541Y960892D03*
Y957546D03*
Y967585D03*
X1028683Y964239D03*
X1042241Y816995D03*
Y810302D03*
Y833727D03*
Y823688D03*
Y827034D03*
Y840420D03*
Y960892D03*
Y957546D03*
Y967585D03*
Y1221916D03*
Y1215223D03*
Y1238648D03*
Y1228609D03*
Y1231955D03*
Y1245341D03*
X1058383Y813648D03*
Y806955D03*
Y820341D03*
Y830381D03*
Y823688D03*
Y837074D03*
Y964239D03*
Y1218570D03*
Y1211877D03*
Y1225263D03*
Y1241995D03*
Y1235302D03*
Y1228609D03*
X1071941Y960892D03*
Y957546D03*
Y967585D03*
Y1054593D03*
X1101641Y780184D03*
Y773491D03*
Y786877D03*
Y803609D03*
Y796916D03*
Y790223D03*
Y816995D03*
Y810302D03*
Y833727D03*
Y823688D03*
Y827034D03*
Y847113D03*
Y840420D03*
Y853806D03*
Y860499D03*
Y863845D03*
Y883924D03*
Y877231D03*
Y870538D03*
Y890617D03*
Y897310D03*
Y900656D03*
Y914042D03*
Y907349D03*
Y927428D03*
Y920735D03*
Y934121D03*
Y944160D03*
Y937467D03*
Y960892D03*
Y950853D03*
X1088083Y964239D03*
X1101641Y957546D03*
Y980971D03*
Y974278D03*
Y967585D03*
Y994357D03*
Y987664D03*
X1088083Y1021129D03*
Y1024475D03*
X1101641Y1027822D03*
Y1021129D03*
Y1047900D03*
Y1041207D03*
Y1034515D03*
X1088083Y1051247D03*
X1101641Y1054593D03*
Y1074672D03*
Y1067979D03*
Y1091404D03*
Y1081365D03*
Y1084711D03*
Y1098097D03*
Y1111483D03*
Y1104790D03*
Y1128215D03*
Y1118176D03*
Y1121522D03*
Y1141601D03*
Y1134908D03*
Y1148294D03*
Y1154987D03*
Y1158333D03*
Y1171719D03*
Y1165026D03*
Y1185105D03*
Y1178412D03*
Y1191798D03*
Y1208530D03*
Y1201837D03*
Y1195144D03*
Y1221916D03*
Y1215223D03*
Y1238648D03*
Y1228609D03*
Y1231955D03*
Y1245341D03*
X1117783Y770144D03*
Y776837D03*
Y786877D03*
Y783530D03*
Y800263D03*
Y793570D03*
Y813648D03*
Y806955D03*
Y820341D03*
Y830381D03*
Y823688D03*
Y850459D03*
Y843766D03*
Y837074D03*
Y867192D03*
Y860499D03*
Y857152D03*
Y873885D03*
Y880577D03*
Y887270D03*
Y897310D03*
Y893963D03*
Y917389D03*
Y910696D03*
Y904003D03*
Y924081D03*
Y934121D03*
Y930774D03*
Y947507D03*
Y940814D03*
Y964239D03*
Y977625D03*
Y970932D03*
Y991011D03*
Y984318D03*
Y1021129D03*
Y1024475D03*
Y1031168D03*
Y1044554D03*
Y1037861D03*
Y1051247D03*
Y1071326D03*
Y1064633D03*
Y1078018D03*
Y1094751D03*
Y1088058D03*
Y1081365D03*
Y1108137D03*
Y1101444D03*
Y1124869D03*
Y1118176D03*
Y1114829D03*
Y1144948D03*
Y1138255D03*
Y1131562D03*
Y1161680D03*
Y1154987D03*
Y1151641D03*
Y1175066D03*
Y1168373D03*
Y1181759D03*
Y1191798D03*
Y1188452D03*
Y1205184D03*
Y1198491D03*
Y1218570D03*
Y1211877D03*
Y1225263D03*
Y1241995D03*
Y1235302D03*
Y1228609D03*
X1131341Y960892D03*
Y957546D03*
Y967585D03*
Y1054593D03*
X1147483Y964239D03*
Y1021129D03*
Y1024475D03*
Y1051247D03*
X1161041Y780184D03*
Y773491D03*
Y786877D03*
Y803609D03*
Y796916D03*
Y790223D03*
Y816995D03*
Y810302D03*
Y833727D03*
Y823688D03*
Y827034D03*
Y847113D03*
Y840420D03*
Y853806D03*
Y860499D03*
Y863845D03*
Y883924D03*
Y877231D03*
Y870538D03*
Y890617D03*
Y897310D03*
Y900656D03*
Y914042D03*
Y907349D03*
Y927428D03*
Y920735D03*
Y934121D03*
Y944160D03*
Y937467D03*
Y960892D03*
Y950853D03*
Y957546D03*
Y980971D03*
Y974278D03*
Y967585D03*
Y994357D03*
Y987664D03*
Y1027822D03*
Y1021129D03*
Y1047900D03*
Y1041207D03*
Y1034515D03*
Y1054593D03*
Y1074672D03*
Y1067979D03*
Y1091404D03*
Y1081365D03*
Y1084711D03*
Y1098097D03*
Y1111483D03*
Y1104790D03*
Y1128215D03*
Y1118176D03*
Y1121522D03*
Y1141601D03*
Y1134908D03*
Y1148294D03*
Y1154987D03*
Y1158333D03*
Y1171719D03*
Y1165026D03*
Y1185105D03*
Y1178412D03*
Y1191798D03*
Y1208530D03*
Y1201837D03*
Y1195144D03*
Y1221916D03*
Y1215223D03*
Y1238648D03*
Y1228609D03*
Y1231955D03*
Y1245341D03*
X1177183Y770144D03*
Y776837D03*
Y786877D03*
Y783530D03*
Y800263D03*
Y793570D03*
Y813648D03*
Y806955D03*
Y820341D03*
Y830381D03*
Y823688D03*
Y850459D03*
Y843766D03*
Y837074D03*
Y867192D03*
Y860499D03*
Y857152D03*
Y873885D03*
Y880577D03*
Y887270D03*
Y897310D03*
Y893963D03*
Y917389D03*
Y910696D03*
Y904003D03*
Y924081D03*
Y934121D03*
Y930774D03*
Y947507D03*
Y940814D03*
Y964239D03*
Y977625D03*
Y970932D03*
Y991011D03*
Y984318D03*
X1177283Y1021129D03*
Y1024475D03*
Y1031168D03*
Y1044554D03*
Y1037861D03*
Y1051247D03*
Y1071326D03*
Y1064633D03*
Y1078018D03*
Y1094752D03*
Y1088059D03*
Y1081366D03*
Y1108137D03*
Y1101444D03*
X1177183Y1124869D03*
X1177283Y1118177D03*
Y1114830D03*
Y1144948D03*
Y1138255D03*
X1177183Y1131562D03*
X1177283Y1161680D03*
Y1154988D03*
Y1151641D03*
Y1175066D03*
Y1168373D03*
Y1181759D03*
Y1191799D03*
Y1188452D03*
Y1205184D03*
Y1198491D03*
Y1218570D03*
Y1211877D03*
Y1225263D03*
X1177250Y1241995D03*
X1177283Y1235302D03*
Y1228609D03*
X1190741Y960892D03*
Y957546D03*
X1220441Y883924D03*
Y890617D03*
Y897310D03*
Y900656D03*
Y914042D03*
Y907349D03*
Y960892D03*
Y957546D03*
Y1185105D03*
Y1178412D03*
Y1191798D03*
Y1208530D03*
Y1201837D03*
Y1195144D03*
X1236583Y880577D03*
Y887270D03*
Y897310D03*
Y893963D03*
Y910696D03*
Y904003D03*
Y1175066D03*
Y1181759D03*
Y1191798D03*
Y1188452D03*
Y1205184D03*
Y1198491D03*
X1313921Y880219D03*
X1312070Y883423D03*
X1313921Y893036D03*
X1312070Y889832D03*
X1310221Y886627D03*
X1313921D03*
X1312503Y1121447D03*
X1326869Y851380D03*
X1330569Y844971D03*
X1325020Y848176D03*
X1328720D03*
X1326871Y857789D03*
X1328720Y860993D03*
X1330571Y857789D03*
X1317621Y880219D03*
X1319471Y883423D03*
X1325020Y899445D03*
Y893036D03*
X1326871Y889832D03*
X1330571D03*
X1317620Y893036D03*
X1319470Y889832D03*
X1323171Y896240D03*
X1330571D03*
X1317621Y886627D03*
X1326871Y896240D03*
X1321321Y886627D03*
X1325020Y912262D03*
X1326871Y909057D03*
X1330571D03*
X1326871Y902649D03*
X1330571D03*
X1323171Y915466D03*
X1330571D03*
X1326871D03*
X1325021Y931488D03*
X1326871Y928283D03*
X1330571D03*
Y921875D03*
X1326871D03*
X1325020Y918670D03*
X1326871Y941100D03*
X1325020Y937896D03*
X1330571Y941100D03*
X1323171Y934691D03*
X1330571D03*
X1326871D03*
Y947509D03*
X1330571D03*
X1325020Y950713D03*
X1326871Y960326D03*
X1325020Y957122D03*
X1330571Y960326D03*
X1326871Y966735D03*
X1330571D03*
X1326871Y953917D03*
X1330571D03*
X1323172D03*
X1326871Y979552D03*
X1330571D03*
X1325020Y976347D03*
X1323171Y973143D03*
X1325020Y969939D03*
X1323603Y1006093D03*
X1325453Y1002888D03*
X1327303Y999684D03*
X1331003D03*
X1327303Y1012501D03*
X1325453Y1009297D03*
X1331003Y1012501D03*
X1327304Y1031727D03*
X1325453Y1028523D03*
X1331003Y1031727D03*
X1325453Y1022114D03*
X1327303Y1018910D03*
X1331003D03*
X1323603Y1025318D03*
X1331004D03*
X1327304D03*
X1325453Y1047749D03*
Y1041340D03*
X1327303Y1038136D03*
X1331003D03*
X1323603Y1044544D03*
X1331003D03*
X1327303D03*
X1325453Y1060565D03*
X1327303Y1057361D03*
X1331003D03*
X1323603Y1063770D03*
X1327303D03*
X1331003D03*
X1327303Y1050952D03*
X1331003D03*
Y1070178D03*
X1327304D03*
X1325453Y1066974D03*
Y1079791D03*
X1327303Y1076587D03*
X1331003D03*
X1327303Y1089404D03*
X1325453Y1086200D03*
X1331003Y1089404D03*
X1323603Y1082995D03*
X1331003D03*
X1327303D03*
X1329153Y1124651D03*
X1331003Y1127856D03*
X1323603Y1121447D03*
X1319903Y1127856D03*
X1316203D03*
X1318054Y1118243D03*
X1321753Y1124651D03*
X1323603Y1127856D03*
X1319903Y1121447D03*
X1316203D03*
X1325452Y1137469D03*
X1327303Y1134264D03*
X1318053Y1131060D03*
X1346137Y179649D03*
X1332421Y841467D03*
X1337969Y844971D03*
X1339821Y841467D03*
X1345369Y844971D03*
X1347221Y841467D03*
X1334269Y844971D03*
X1336120Y848176D03*
X1341669Y844971D03*
X1343520Y848176D03*
X1332420Y854584D03*
X1334271Y857789D03*
X1337971D03*
X1341671D03*
X1345371D03*
X1336120Y860993D03*
X1339820Y854584D03*
X1343520Y860993D03*
X1347220Y854584D03*
X1332420Y899445D03*
Y893036D03*
X1334271Y896240D03*
X1339820Y899445D03*
X1343520D03*
X1347220Y893036D03*
X1332420Y912262D03*
X1334271Y915466D03*
X1339820Y912262D03*
X1337971Y909057D03*
X1343520Y912262D03*
X1345371Y909057D03*
X1337971Y902649D03*
X1345371D03*
X1336120Y905853D03*
X1343520D03*
X1339820D03*
X1347220D03*
X1332420Y931488D03*
X1339820D03*
X1332420Y918670D03*
X1337971Y928283D03*
X1343520Y931488D03*
X1345371Y928283D03*
X1337971Y921875D03*
X1339820Y918670D03*
X1345371Y921875D03*
X1343520Y918670D03*
X1336120Y925079D03*
X1343520D03*
X1339820D03*
X1347220D03*
X1332420Y937896D03*
X1334271Y934691D03*
X1337971Y941100D03*
X1339820Y937896D03*
X1345371Y941100D03*
X1343520Y937896D03*
X1337971Y947509D03*
X1345371D03*
X1343520Y944304D03*
X1336120D03*
X1347220D03*
X1339820D03*
X1332420Y950713D03*
Y957122D03*
X1334271Y953917D03*
X1337971Y966735D03*
X1345371D03*
X1336120Y963530D03*
X1339820Y950713D03*
X1343520D03*
X1337971Y960326D03*
X1339820Y957122D03*
X1345371Y960326D03*
X1343520Y957122D03*
X1347220Y963530D03*
X1336120Y982756D03*
X1343520D03*
X1339820D03*
X1347220D03*
X1345371Y979552D03*
X1343520Y976347D03*
X1337971Y979552D03*
X1339820Y976347D03*
X1332420D03*
Y969939D03*
X1334271Y973143D03*
X1339820Y969939D03*
X1343520D03*
X1334704Y1006093D03*
X1332853Y1002888D03*
Y1009297D03*
X1338404Y1012501D03*
X1345804D03*
X1340253Y1009297D03*
X1343953D03*
X1340253Y1002888D03*
X1338404Y999684D03*
X1347653Y1002888D03*
X1345804Y999684D03*
X1332853Y1028523D03*
Y1022114D03*
X1338404Y1031727D03*
X1340253Y1028523D03*
X1345804Y1031727D03*
X1343953Y1028523D03*
X1334704Y1025318D03*
X1336553Y1015705D03*
X1347653D03*
X1340253Y1022114D03*
X1338404Y1018910D03*
X1343953Y1022114D03*
X1345804Y1018910D03*
X1332853Y1047749D03*
Y1041340D03*
X1340253D03*
X1338404Y1038136D03*
X1343953Y1041340D03*
X1345804Y1038136D03*
X1336553Y1034931D03*
X1347653D03*
X1340253D03*
X1334704Y1044544D03*
X1343953Y1034931D03*
X1340253Y1047749D03*
X1343953D03*
X1332853Y1060565D03*
X1334704Y1063770D03*
X1340253Y1060565D03*
X1338404Y1057361D03*
X1343953Y1060565D03*
X1345804Y1057361D03*
X1338404Y1050952D03*
X1345804D03*
X1336553Y1054157D03*
X1347653D03*
X1340253D03*
X1343953D03*
X1332853Y1066974D03*
X1343953Y1079791D03*
X1345804Y1076587D03*
X1338404Y1070178D03*
X1340253Y1066974D03*
X1345804Y1070178D03*
X1343953Y1066974D03*
X1332853Y1079791D03*
X1340253D03*
X1338404Y1076587D03*
X1336553Y1073383D03*
X1347653D03*
X1340253D03*
X1343953D03*
X1332853Y1086200D03*
X1334704Y1082995D03*
X1338404Y1095813D03*
X1345804D03*
X1338404Y1089404D03*
X1340253Y1086200D03*
X1345804Y1089404D03*
X1343953Y1086200D03*
X1336553Y1092608D03*
X1343953D03*
X1340253D03*
X1347653D03*
X1340253Y1099017D03*
X1343953D03*
X1345803Y1108630D03*
X1340254Y1105426D03*
X1336554Y1111834D03*
X1334703Y1108630D03*
X1343954Y1111834D03*
X1342103Y1108630D03*
X1338403D03*
X1334703Y1121447D03*
X1336554Y1124651D03*
X1340253D03*
X1343953D03*
X1347653D03*
X1332854D03*
X1338404Y1127856D03*
X1342104Y1121447D03*
X1345804Y1127856D03*
X1342103Y1115039D03*
X1345803D03*
X1334703D03*
Y1134264D03*
X1338403Y1140973D03*
X1342104Y1134264D03*
X1345803Y1140973D03*
X1332854Y1137469D03*
X1336554D03*
X1340254D03*
X1343954D03*
X1347654D03*
X1352557Y175948D03*
X1349351Y181498D03*
X1355761Y185198D03*
X1349351D03*
X1355761Y174098D03*
Y181498D03*
X1352557Y183348D03*
X1352561Y198148D03*
X1355771Y196298D03*
X1355765Y199999D03*
Y203699D03*
X1363869Y844971D03*
X1352769D03*
X1356469D03*
X1360169D03*
X1362021Y841467D03*
X1349069Y844971D03*
X1350920Y848176D03*
X1354621Y841467D03*
X1358320Y848176D03*
X1349071Y857789D03*
X1354620Y854584D03*
X1356471Y857789D03*
X1360171D03*
X1363871D03*
X1350920Y860993D03*
X1352771Y857789D03*
X1358320Y860993D03*
X1362020Y854584D03*
X1350920Y899445D03*
X1358320D03*
Y893036D03*
X1350920D03*
X1362020D03*
X1349071Y896240D03*
X1356471D03*
X1352771D03*
X1360171D03*
X1352771Y902649D03*
X1356471D03*
X1350920Y912262D03*
X1352771Y909057D03*
X1358320Y912262D03*
X1356471Y909057D03*
X1349071Y915466D03*
X1356471D03*
X1352771D03*
X1360171D03*
X1350920Y931488D03*
X1352771Y928283D03*
X1358320Y931488D03*
X1356471Y928283D03*
X1352771Y921875D03*
X1350920Y918670D03*
X1356471Y921875D03*
X1358320Y918670D03*
X1356471Y941100D03*
X1358320Y937896D03*
X1352771Y947509D03*
X1356471D03*
X1352771Y941100D03*
X1350920Y937896D03*
X1349071Y934691D03*
X1356471D03*
X1352771D03*
X1360171D03*
X1352771Y960326D03*
X1350920Y957122D03*
X1356471Y960326D03*
X1358320Y957122D03*
X1350920Y950713D03*
X1358320D03*
X1349071Y953917D03*
X1356471D03*
X1352771D03*
X1360171D03*
X1356471Y966735D03*
X1352771D03*
X1350920Y969939D03*
X1358320D03*
X1349504Y1006093D03*
X1356904D03*
X1353204D03*
X1360604D03*
X1351353Y1002888D03*
X1353204Y999684D03*
X1358753Y1002888D03*
X1356904Y999684D03*
X1353204Y1012501D03*
X1351353Y1009297D03*
X1356904Y1012501D03*
X1358753Y1009297D03*
X1353204Y1031727D03*
X1351353Y1028523D03*
X1356904Y1031727D03*
X1358753Y1028523D03*
X1351353Y1022114D03*
X1353204Y1018910D03*
X1358753Y1022114D03*
X1356904Y1018910D03*
X1353204Y1025318D03*
X1360604D03*
X1349502D03*
X1356902D03*
X1351353Y1047749D03*
X1358753D03*
X1351353Y1041340D03*
X1353204Y1038136D03*
X1358753Y1041340D03*
X1356904Y1038136D03*
X1349504Y1044544D03*
X1356904D03*
X1353204D03*
X1360604D03*
X1351353Y1060565D03*
X1353204Y1057361D03*
X1358753Y1060565D03*
X1356904Y1057361D03*
X1353204Y1050952D03*
X1356904D03*
X1349504Y1063770D03*
X1360604D03*
X1353204D03*
X1356904D03*
Y1070178D03*
X1358753Y1066974D03*
X1353204Y1070178D03*
X1351353Y1066974D03*
Y1079791D03*
X1353204Y1076587D03*
X1358753Y1079791D03*
X1356904Y1076587D03*
X1353204Y1089404D03*
X1351353Y1086200D03*
X1356904Y1089404D03*
X1358753Y1086200D03*
X1349504Y1082995D03*
X1360604D03*
X1353204D03*
X1356904D03*
X1351353Y1124651D03*
X1355053D03*
X1358753D03*
X1362453D03*
X1349504Y1121447D03*
X1353204Y1127856D03*
X1356904Y1121447D03*
X1360604Y1127856D03*
X1349504Y1134264D03*
X1353203Y1140973D03*
X1356904Y1134264D03*
X1360603Y1140973D03*
X1351354Y1137469D03*
X1355054D03*
X1358754D03*
X1362454D03*
X1367569Y844971D03*
X1369421Y841467D03*
X1373120Y848176D03*
X1376821Y841467D03*
X1365720Y848176D03*
X1371269Y844971D03*
X1374969D03*
X1378669D03*
X1365720Y860993D03*
X1367571Y857789D03*
X1373120Y860993D03*
X1374971Y857789D03*
X1369420Y854584D03*
X1371271Y857789D03*
X1376820Y854584D03*
X1378671Y857789D03*
X1374971Y973143D03*
X1376820Y976347D03*
X1378671Y979552D03*
Y973143D03*
X1366153Y1002888D03*
X1364304Y999684D03*
X1369853Y1002888D03*
X1371704Y999684D03*
X1369853Y1111834D03*
X1368004Y1108630D03*
X1377253Y1099017D03*
X1379104Y1108630D03*
X1373553Y1105426D03*
X1371704Y1108630D03*
X1379104Y1102221D03*
X1377253Y1111834D03*
X1375404Y1108630D03*
X1366153Y1124651D03*
X1371704Y1121447D03*
X1373553Y1124651D03*
X1377253D03*
X1368004Y1127856D03*
X1369853Y1124651D03*
X1375404Y1127856D03*
X1379104Y1121447D03*
X1364304D03*
X1375404Y1115039D03*
X1368004D03*
X1379104D03*
X1368003Y1140973D03*
X1371704Y1134264D03*
X1375403Y1140973D03*
X1379104Y1134264D03*
X1364304D03*
X1366154Y1137469D03*
X1369854D03*
X1373554D03*
X1377254D03*
X1380520Y848176D03*
X1386069Y844971D03*
X1389769D03*
X1393469D03*
X1382369D03*
X1384221Y841467D03*
X1387920Y848176D03*
X1391621Y841467D03*
X1395320Y848176D03*
X1380520Y860993D03*
X1382371Y857789D03*
X1387920Y860993D03*
X1389771Y857789D03*
X1395320Y860993D03*
X1384220Y854584D03*
X1386071Y857789D03*
X1391620Y854584D03*
X1393471Y857789D03*
Y883423D03*
X1391620Y880219D03*
X1389771Y883423D03*
X1386071Y896240D03*
X1389771D03*
X1393471D03*
X1387920Y899445D03*
X1391620Y893036D03*
X1395320Y899445D03*
Y886627D03*
X1380953Y1099017D03*
X1395753Y1105426D03*
X1393904Y1108630D03*
X1390204Y1102221D03*
X1392053Y1111834D03*
X1388353D03*
X1384653Y1105426D03*
Y1099017D03*
X1392053Y1105426D03*
X1395753Y1111834D03*
X1388353Y1105426D03*
X1384653Y1111834D03*
X1386504Y1108630D03*
X1380953Y1124651D03*
X1384653D03*
X1382804Y1127856D03*
X1386504Y1121447D03*
X1390204Y1115039D03*
X1382803Y1140973D03*
X1386504Y1134264D03*
X1380954Y1137469D03*
X1384654D03*
X1397169Y844971D03*
X1399021Y841467D03*
X1402720Y848176D03*
X1406420D03*
X1411969Y844971D03*
X1400869D03*
X1404569D03*
X1410120Y848176D03*
X1397171Y857789D03*
X1402720Y860993D03*
X1404571Y857789D03*
X1410121Y860993D03*
X1411971Y857789D03*
X1399020Y854584D03*
X1400871Y857789D03*
X1406420Y854584D03*
X1408271Y857789D03*
Y883423D03*
X1406420Y880219D03*
X1400871Y883423D03*
X1399020Y880219D03*
X1404571Y883423D03*
X1397171D03*
X1411971D03*
X1397171Y896240D03*
X1402720Y899445D03*
X1404571Y896240D03*
X1410120Y899445D03*
X1399020Y893036D03*
X1400871Y896240D03*
X1406420Y893036D03*
X1408271Y896240D03*
X1411971D03*
X1410120Y886627D03*
X1402720D03*
X1405003Y1076587D03*
X1406853Y1079791D03*
X1413820Y848176D03*
X1424921Y860993D03*
X1421220Y854584D03*
X1417520Y860993D03*
X1428620Y854584D03*
X1426771Y857789D03*
X1423071D03*
X1419371D03*
X1413821Y854584D03*
X1428621Y880219D03*
X1423071Y883423D03*
X1421220Y880219D03*
X1415671Y883423D03*
X1413820Y880219D03*
X1426771Y883423D03*
X1419371D03*
X1413820Y893036D03*
X1421220Y899445D03*
X1419371Y896240D03*
X1424920Y899445D03*
X1426772Y896240D03*
X1417520Y899445D03*
X1421220Y893036D03*
X1423071Y896240D03*
X1428621Y893036D03*
X1424920Y886627D03*
X1417520D03*
X1445271Y857789D03*
X1439720Y860993D03*
X1437871Y857789D03*
X1432320Y860993D03*
X1430471Y857789D03*
X1443420Y854584D03*
X1441571Y857789D03*
X1436020Y854584D03*
X1434171Y857789D03*
X1445271Y883423D03*
X1443420Y880219D03*
X1437871Y883423D03*
X1436020Y880219D03*
X1430471Y883423D03*
X1441571D03*
X1434171D03*
X1430471Y896240D03*
X1436020Y893036D03*
X1437871Y896240D03*
X1441571D03*
X1432320Y899445D03*
X1434171Y896240D03*
X1439720Y899445D03*
X1443420Y893036D03*
X1439720Y886627D03*
X1432320D03*
X1460071Y857789D03*
X1454520Y860993D03*
X1452671Y857789D03*
X1447120Y860993D03*
X1458220Y854584D03*
X1456371Y857789D03*
X1450820Y854584D03*
X1448971Y857789D03*
X1447120Y886627D03*
X1460504Y1121447D03*
X1456804Y1127856D03*
X1453104Y1121447D03*
X1449404Y1127856D03*
X1445704Y1121447D03*
X1458653Y1124651D03*
X1454953D03*
X1451253D03*
X1447553D03*
X1460504Y1134264D03*
X1458654Y1137469D03*
X1453104Y1134264D03*
X1451254Y1137469D03*
X1456803Y1140973D03*
X1454954Y1137469D03*
X1449403Y1140973D03*
X1467471Y857789D03*
X1461920Y860993D03*
X1476720D03*
X1474871Y857789D03*
X1471171D03*
X1465620Y854584D03*
X1463771Y857789D03*
X1473020Y854584D03*
X1469320Y860993D03*
X1476720Y899445D03*
Y912262D03*
X1474871Y909057D03*
Y902649D03*
X1476720Y905853D03*
X1473020D03*
X1476720Y931488D03*
X1474871Y921875D03*
X1476720Y918670D03*
X1474871Y928283D03*
X1473020Y925079D03*
X1476720D03*
X1474871Y947509D03*
Y941100D03*
X1476720Y937896D03*
X1473020Y944304D03*
X1476720D03*
Y950713D03*
Y957122D03*
X1474871Y960326D03*
X1463771Y979552D03*
X1461920Y976347D03*
X1467471Y979552D03*
X1469320Y976347D03*
X1476720Y982756D03*
X1473020D03*
X1474871Y979552D03*
X1476720Y976347D03*
X1477153Y1002888D03*
X1475304Y999684D03*
Y1012501D03*
X1477153Y1009297D03*
X1473453Y1015705D03*
X1475304Y1031727D03*
X1477153Y1028523D03*
Y1022114D03*
X1475304Y1018910D03*
X1477153Y1041340D03*
X1475304Y1038136D03*
X1477153Y1047749D03*
Y1034931D03*
X1473453D03*
X1477153Y1060565D03*
X1475304Y1057361D03*
Y1050952D03*
X1477153Y1054157D03*
X1473453D03*
X1475304Y1070178D03*
X1477153Y1066974D03*
Y1079791D03*
X1475304Y1076587D03*
X1473453Y1073383D03*
X1477153D03*
X1475304Y1089404D03*
X1477153Y1086200D03*
X1473453Y1092608D03*
X1477153D03*
X1464204Y1127856D03*
X1475304Y1121447D03*
X1471604Y1127856D03*
X1467904Y1121447D03*
X1466053Y1124651D03*
X1462353D03*
X1477153D03*
X1473453D03*
X1469753D03*
X1469754Y1137469D03*
X1464203Y1140973D03*
X1477154Y1137469D03*
X1471603Y1140973D03*
X1467904Y1134264D03*
X1466054Y1137469D03*
X1462354D03*
X1475304Y1134264D03*
X1473454Y1137469D03*
X1491520Y860993D03*
X1489671Y857789D03*
X1484120Y860993D03*
X1482271Y857789D03*
X1493371D03*
X1487820Y854584D03*
X1485971Y857789D03*
X1480420Y854584D03*
X1478571Y857789D03*
X1487820Y899445D03*
Y893036D03*
X1484120D03*
X1485971Y896240D03*
X1493371D03*
X1489671D03*
X1480420Y899445D03*
X1489671Y902649D03*
X1493371D03*
X1487820Y912262D03*
X1489671Y909057D03*
X1493371D03*
X1489671Y915466D03*
X1485971D03*
X1493371D03*
X1480420Y912262D03*
X1482271Y909057D03*
Y902649D03*
X1484120Y905853D03*
X1480420D03*
X1487820Y931488D03*
X1489671Y928283D03*
X1493371D03*
X1482271D03*
Y921875D03*
X1480420Y918670D03*
X1489671Y921875D03*
X1487820Y918670D03*
X1493371Y921875D03*
X1480420Y931488D03*
Y925079D03*
X1484120D03*
X1489671Y941100D03*
X1487820Y937896D03*
X1493371Y941100D03*
X1489671Y934691D03*
X1485971D03*
X1493371D03*
X1489671Y947509D03*
X1493371D03*
X1482271D03*
Y941100D03*
X1480420Y937896D03*
X1484120Y944304D03*
X1480420D03*
X1487820Y950713D03*
X1489671Y960326D03*
X1487820Y957122D03*
X1493371Y960326D03*
Y966735D03*
X1489671D03*
X1480420Y950713D03*
X1489671Y953917D03*
X1493371D03*
X1485971D03*
X1480420Y957122D03*
X1482271Y960326D03*
X1484120Y982756D03*
X1480420D03*
Y976347D03*
X1482271Y979552D03*
X1489671D03*
X1493371D03*
X1487820Y976347D03*
X1485971Y973143D03*
X1487820Y969939D03*
X1493804Y1006093D03*
X1490104D03*
X1486404D03*
X1493804Y1012501D03*
X1480853Y1002888D03*
X1482703Y999684D03*
X1490104Y1012501D03*
X1488253Y1009297D03*
X1482704Y1012501D03*
X1480853Y1009297D03*
X1493803Y999684D03*
X1488253Y1002888D03*
X1490104Y999684D03*
Y1031727D03*
X1488253Y1028523D03*
X1493804Y1031727D03*
X1488253Y1022114D03*
X1490104Y1018910D03*
X1493804D03*
X1490104Y1025318D03*
X1486404D03*
X1493804D03*
X1484553Y1015705D03*
X1482704Y1031727D03*
X1480853Y1028523D03*
Y1022114D03*
X1482704Y1018910D03*
X1480853Y1041340D03*
X1482704Y1038136D03*
X1488253Y1047749D03*
Y1041340D03*
X1490104Y1038136D03*
X1493804D03*
X1480853Y1047749D03*
X1486404Y1044544D03*
X1484553Y1034931D03*
X1490104Y1044544D03*
X1493804D03*
X1480853Y1034931D03*
X1488253Y1060565D03*
X1490104Y1057361D03*
X1493804D03*
X1486404Y1063770D03*
X1490104D03*
X1493804D03*
X1490104Y1050952D03*
X1493804D03*
X1480853Y1060565D03*
X1482704Y1057361D03*
Y1050952D03*
X1484553Y1054157D03*
X1480853D03*
X1493804Y1070178D03*
X1490104D03*
X1488253Y1066974D03*
X1480853Y1079791D03*
X1482704Y1076587D03*
Y1070178D03*
X1480853Y1066974D03*
X1488253Y1079791D03*
X1490104Y1076587D03*
X1493804D03*
X1484553Y1073383D03*
X1480853D03*
X1490104Y1089404D03*
X1488253Y1086200D03*
X1493804Y1089404D03*
X1490104Y1082995D03*
X1486404D03*
X1493804D03*
X1486404Y1095813D03*
X1482703D03*
X1482704Y1089404D03*
X1480853Y1086200D03*
X1484553Y1092608D03*
X1480853D03*
X1493804Y1102221D03*
X1491953Y1099017D03*
X1493804Y1127856D03*
X1490104Y1121447D03*
X1486404Y1127856D03*
X1482704Y1121447D03*
X1479004Y1127856D03*
X1491953Y1124651D03*
X1488253D03*
X1484553D03*
X1480853D03*
X1493803Y1140973D03*
X1490104Y1134264D03*
X1488254Y1137469D03*
X1482704Y1134264D03*
X1480854Y1137469D03*
X1491954D03*
X1486403Y1140973D03*
X1484554Y1137469D03*
X1479003Y1140973D03*
X1508171Y864197D03*
X1510021Y854584D03*
X1504471Y857789D03*
X1498920Y860993D03*
X1497071Y857789D03*
X1502620Y854584D03*
X1500771Y857789D03*
X1495220Y854584D03*
X1502621Y899445D03*
X1506320D03*
X1495220D03*
Y893036D03*
X1498920D03*
X1497071Y896240D03*
X1506321Y912262D03*
X1508171Y909057D03*
X1500771Y902649D03*
X1508171D03*
X1502621Y912262D03*
X1500771Y909057D03*
X1502621Y905853D03*
X1510021D03*
X1498920D03*
X1506321D03*
X1495220Y912262D03*
X1497071Y915466D03*
X1502621Y931488D03*
X1500771Y928283D03*
X1506321Y931488D03*
X1508171Y928283D03*
X1500771Y921875D03*
X1502621Y918670D03*
X1508171Y921875D03*
X1506321Y918670D03*
X1502621Y925079D03*
X1510021D03*
X1498920D03*
X1506321D03*
X1495220Y931488D03*
Y918670D03*
X1500771Y941100D03*
X1502621Y937896D03*
X1508171Y941100D03*
X1506321Y937896D03*
X1500771Y947509D03*
X1508171D03*
X1495220Y937896D03*
X1510021Y944304D03*
X1497071Y934691D03*
X1502621Y944304D03*
X1506320D03*
X1498920D03*
X1500771Y966735D03*
X1508171D03*
X1498920Y963530D03*
X1502621Y950713D03*
X1506320D03*
X1508171Y960326D03*
X1506320Y957122D03*
X1500771Y960326D03*
X1502621Y957122D03*
X1510021Y963530D03*
X1495220Y950713D03*
Y957122D03*
X1497071Y953917D03*
X1502621Y969939D03*
X1506321D03*
X1495220Y976347D03*
Y969939D03*
X1497071Y973143D03*
X1497504Y1006093D03*
X1501204Y1012501D03*
X1508603D03*
X1503053Y1009297D03*
X1506753D03*
X1495653D03*
X1495655Y1002888D03*
X1506753D03*
X1508603Y999684D03*
X1503053Y1002888D03*
X1501204Y999684D03*
X1499353Y1015705D03*
X1510453D03*
X1501204Y1031727D03*
X1503053Y1028523D03*
X1508603Y1031727D03*
X1506753Y1028523D03*
Y1022114D03*
X1508603Y1018910D03*
X1503053Y1022114D03*
X1501204Y1018910D03*
X1495653Y1028523D03*
Y1022114D03*
X1497504Y1025318D03*
X1503053Y1041340D03*
X1501204Y1038136D03*
X1506753Y1041340D03*
X1508603Y1038136D03*
X1503053Y1047749D03*
X1506753D03*
X1503053Y1034931D03*
X1510453D03*
X1499353D03*
X1506753D03*
X1495653Y1047749D03*
Y1041340D03*
X1497504Y1044544D03*
X1495653Y1060565D03*
X1503053D03*
X1501204Y1057361D03*
X1506753Y1060565D03*
X1508604Y1057361D03*
X1501203Y1050952D03*
X1508604Y1050953D03*
X1499353Y1054157D03*
X1497504Y1063770D03*
X1510453Y1054157D03*
X1503053D03*
X1506753D03*
Y1079791D03*
X1508604Y1076587D03*
X1501204Y1070178D03*
X1503053Y1066974D03*
X1508604Y1070178D03*
X1506753Y1066974D03*
X1503053Y1079791D03*
X1501204Y1076587D03*
X1499353Y1073383D03*
X1510453D03*
X1503053D03*
X1506753D03*
X1495653Y1066974D03*
Y1079791D03*
X1497504Y1095813D03*
X1508603D03*
X1501204D03*
Y1089404D03*
X1503053Y1086200D03*
X1508604Y1089404D03*
X1506753Y1086200D03*
X1503053Y1092608D03*
X1510452D03*
X1499353D03*
X1506753D03*
X1495653Y1086200D03*
X1497504Y1082995D03*
X1506753Y1099017D03*
X1503053Y1124651D03*
X1497504Y1121447D03*
X1501204Y1127856D03*
X1499353Y1124651D03*
X1495653D03*
X1508604Y1134264D03*
X1501203Y1140973D03*
X1499354Y1137469D03*
X1510454D03*
X1503054D03*
X1497504Y1134264D03*
X1495654Y1137469D03*
X1519271Y851380D03*
X1515571D03*
X1511871Y864197D03*
X1519270D03*
X1522970D03*
X1511871Y857789D03*
X1519271D03*
X1515571D03*
X1517421Y860993D03*
Y854584D03*
X1515571Y883423D03*
X1513720Y880219D03*
X1519271Y883423D03*
X1521121Y880219D03*
X1513720Y873810D03*
X1515571Y870606D03*
X1521121Y873810D03*
X1519271Y870606D03*
X1515570Y877014D03*
X1522970D03*
X1511871D03*
X1519271D03*
X1596941Y883924D03*
Y890617D03*
Y897310D03*
Y900656D03*
Y914042D03*
Y907349D03*
Y960892D03*
Y957546D03*
Y1185105D03*
Y1178412D03*
Y1191798D03*
Y1208530D03*
Y1201837D03*
Y1195144D03*
X1613083Y880577D03*
Y887270D03*
Y897310D03*
Y893963D03*
Y910696D03*
Y904003D03*
Y1175066D03*
Y1181759D03*
Y1191798D03*
Y1188451D03*
Y1205184D03*
Y1198491D03*
X1626641Y960892D03*
Y957546D03*
X1656441Y780184D03*
Y773491D03*
Y786877D03*
Y803609D03*
Y796916D03*
Y790223D03*
Y816995D03*
Y810302D03*
Y833727D03*
Y823688D03*
Y827034D03*
Y847113D03*
Y840420D03*
Y853806D03*
Y860499D03*
Y863845D03*
Y883924D03*
Y877231D03*
Y870538D03*
Y890617D03*
Y897310D03*
Y900656D03*
Y914042D03*
Y907349D03*
Y927428D03*
Y920735D03*
Y934121D03*
Y944160D03*
Y937467D03*
Y960892D03*
Y950853D03*
Y957546D03*
Y980971D03*
Y974278D03*
Y967585D03*
Y994357D03*
Y987664D03*
X1656141Y1027822D03*
X1656441Y1021129D03*
X1656141Y1047900D03*
Y1041207D03*
Y1034514D03*
Y1054593D03*
X1656441Y1074672D03*
Y1067979D03*
Y1091404D03*
Y1081365D03*
Y1084711D03*
Y1098097D03*
Y1111483D03*
Y1104790D03*
Y1128215D03*
Y1118176D03*
Y1121522D03*
Y1141601D03*
Y1134908D03*
Y1148294D03*
Y1154987D03*
Y1158333D03*
Y1171719D03*
Y1165026D03*
Y1185105D03*
Y1178412D03*
Y1191798D03*
Y1208530D03*
Y1201837D03*
Y1195144D03*
Y1221916D03*
Y1215223D03*
Y1238648D03*
Y1228609D03*
Y1231955D03*
Y1245341D03*
X1672583Y770144D03*
Y776837D03*
Y786877D03*
Y783530D03*
Y800263D03*
Y793570D03*
Y813648D03*
Y806955D03*
Y820341D03*
Y830381D03*
Y823688D03*
Y850459D03*
Y843766D03*
Y837074D03*
Y867192D03*
Y860499D03*
Y857152D03*
Y873885D03*
Y880577D03*
Y887270D03*
Y897310D03*
Y893963D03*
Y917389D03*
Y910696D03*
Y904003D03*
Y924081D03*
Y934121D03*
Y930774D03*
Y947507D03*
Y940814D03*
Y964239D03*
Y977625D03*
Y970932D03*
Y991011D03*
Y984318D03*
Y1021129D03*
Y1024475D03*
Y1031168D03*
X1672283Y1044554D03*
Y1037861D03*
X1672583Y1051247D03*
Y1071325D03*
Y1064633D03*
Y1078018D03*
Y1094751D03*
Y1088058D03*
Y1081365D03*
Y1108136D03*
Y1101444D03*
Y1124869D03*
Y1118176D03*
Y1114829D03*
Y1144947D03*
Y1138255D03*
Y1131562D03*
Y1161680D03*
Y1154987D03*
Y1151640D03*
Y1175066D03*
Y1168373D03*
Y1181758D03*
Y1191798D03*
Y1188451D03*
Y1205184D03*
Y1198491D03*
Y1218569D03*
Y1211877D03*
Y1225262D03*
Y1241995D03*
Y1235302D03*
Y1228609D03*
X1686041Y960892D03*
Y957546D03*
X1686141Y967585D03*
Y1054593D03*
X1702283Y964239D03*
Y1021129D03*
Y1024475D03*
Y1051247D03*
X1715841Y780184D03*
Y773491D03*
Y786877D03*
Y803609D03*
Y796916D03*
Y790223D03*
Y816995D03*
Y810302D03*
Y833727D03*
Y823688D03*
Y827034D03*
Y847113D03*
Y840420D03*
Y853806D03*
Y860499D03*
Y863845D03*
Y883924D03*
Y877231D03*
Y870538D03*
Y890617D03*
Y897310D03*
Y900656D03*
Y914042D03*
Y907349D03*
Y927428D03*
Y920735D03*
Y934121D03*
Y944160D03*
Y937467D03*
Y960892D03*
Y950853D03*
Y957546D03*
Y980971D03*
Y974278D03*
Y967585D03*
Y994357D03*
Y987664D03*
Y1027822D03*
Y1021129D03*
Y1047900D03*
Y1041207D03*
Y1034514D03*
Y1054593D03*
Y1074672D03*
Y1067979D03*
Y1091404D03*
Y1081365D03*
Y1084711D03*
Y1098097D03*
Y1111483D03*
Y1104790D03*
Y1128215D03*
Y1118176D03*
Y1121522D03*
Y1141601D03*
Y1134908D03*
Y1148294D03*
Y1154987D03*
Y1158333D03*
Y1171719D03*
Y1165026D03*
Y1185105D03*
Y1178412D03*
Y1191798D03*
Y1208530D03*
Y1201837D03*
Y1195144D03*
Y1221916D03*
Y1215223D03*
Y1238648D03*
Y1228609D03*
Y1231955D03*
Y1245341D03*
X1731983Y770144D03*
Y776837D03*
Y786877D03*
Y783530D03*
Y800263D03*
Y793570D03*
Y813648D03*
Y806955D03*
Y820341D03*
Y830381D03*
Y823688D03*
Y850459D03*
Y843766D03*
Y837074D03*
Y867192D03*
Y860499D03*
Y857152D03*
Y873885D03*
Y880577D03*
Y887270D03*
Y897310D03*
Y893963D03*
Y917389D03*
Y910696D03*
Y904003D03*
Y924081D03*
Y934121D03*
Y930774D03*
Y947507D03*
Y940814D03*
Y964239D03*
Y977625D03*
X1731883Y970932D03*
X1731983Y991011D03*
Y984318D03*
Y1021129D03*
Y1024475D03*
Y1031168D03*
X1731683Y1044554D03*
Y1037861D03*
X1731983Y1051247D03*
X1731818Y1071326D03*
X1731883Y1064633D03*
X1731983Y1078018D03*
Y1094751D03*
Y1088058D03*
Y1081365D03*
X1731818Y1108137D03*
X1731983Y1101444D03*
Y1124869D03*
Y1118176D03*
Y1114829D03*
Y1144947D03*
Y1138255D03*
Y1131562D03*
Y1161680D03*
Y1154987D03*
Y1151640D03*
Y1175066D03*
Y1168373D03*
X1731818Y1181759D03*
X1731983Y1191798D03*
X1731818Y1188452D03*
X1731983Y1205184D03*
Y1198491D03*
Y1218569D03*
Y1211877D03*
Y1225262D03*
Y1241995D03*
Y1235302D03*
Y1228609D03*
X1745541Y960892D03*
Y957546D03*
Y967585D03*
Y1054593D03*
X1761683Y964239D03*
Y1021129D03*
Y1024475D03*
Y1051247D03*
X1775241Y816995D03*
Y810302D03*
Y833727D03*
Y823688D03*
Y827034D03*
Y840420D03*
Y960892D03*
Y957546D03*
Y967585D03*
Y1221916D03*
Y1215223D03*
Y1238648D03*
Y1228609D03*
Y1231955D03*
Y1245341D03*
X1791383Y813648D03*
Y806955D03*
Y820341D03*
Y830381D03*
Y823688D03*
Y837074D03*
Y964239D03*
Y1218570D03*
Y1211877D03*
Y1225263D03*
Y1241995D03*
Y1235302D03*
Y1228609D03*
X1804941Y960892D03*
Y957546D03*
Y967585D03*
X1821083Y964239D03*
G54D45*
X676508Y145866D03*
G54D34*
X238780Y1643661D03*
X230906Y1649173D03*
X238780Y1653110D03*
Y1657834D03*
X230906Y1653897D03*
Y1663346D03*
X238780Y1667283D03*
Y1672007D03*
X230906Y1668070D03*
X238780Y1695629D03*
X230906Y1691692D03*
Y1696417D03*
X238780Y1700354D03*
Y1723976D03*
Y1728700D03*
X230906Y1720039D03*
Y1724763D03*
Y1734212D03*
X254528Y1643661D03*
X246654Y1649173D03*
X254528Y1653110D03*
Y1657834D03*
X246654Y1653897D03*
Y1663346D03*
X254528Y1667283D03*
Y1672007D03*
X246654Y1668070D03*
X254528Y1695629D03*
X246654Y1691692D03*
Y1696417D03*
X254528Y1700354D03*
Y1723976D03*
Y1728700D03*
X246654Y1720039D03*
Y1724763D03*
Y1734212D03*
X270276Y1643661D03*
X262402Y1649173D03*
X270276Y1653110D03*
Y1657834D03*
X262402Y1653897D03*
Y1663346D03*
X270276Y1667283D03*
Y1672007D03*
X262402Y1668070D03*
X270276Y1695629D03*
X262402Y1691692D03*
Y1696417D03*
X270276Y1700354D03*
Y1723976D03*
Y1728700D03*
X262402Y1720039D03*
Y1724763D03*
Y1734212D03*
X286024Y1643661D03*
X278150Y1649173D03*
X286024Y1653110D03*
Y1657834D03*
X278150Y1653897D03*
Y1663346D03*
X286024Y1667283D03*
Y1672007D03*
X278150Y1668070D03*
X286024Y1695629D03*
X278150Y1691692D03*
Y1696417D03*
X286024Y1700354D03*
Y1723976D03*
Y1728700D03*
X278150Y1720039D03*
Y1724763D03*
Y1734212D03*
X305709Y1672007D03*
X297835Y1691692D03*
Y1696417D03*
X305709Y1695629D03*
Y1700354D03*
X297835Y1720039D03*
Y1724763D03*
X305709Y1723976D03*
Y1728700D03*
X297835Y1734212D03*
X321457Y1672007D03*
X313583Y1691692D03*
Y1696417D03*
X321457Y1695629D03*
Y1700354D03*
X313583Y1720039D03*
Y1724763D03*
X321457Y1723976D03*
Y1728700D03*
X313583Y1734212D03*
X337205Y1672007D03*
X329331Y1691692D03*
Y1696417D03*
X337205Y1695629D03*
Y1700354D03*
X329331Y1720039D03*
Y1724763D03*
X337205Y1723976D03*
Y1728700D03*
X329331Y1734212D03*
X352953Y1672007D03*
X345079Y1691692D03*
Y1696417D03*
X352953Y1695629D03*
Y1700354D03*
X345079Y1720039D03*
Y1724763D03*
X352953Y1723976D03*
Y1728700D03*
X345079Y1734212D03*
X495079Y1677519D03*
Y1682244D03*
Y1705866D03*
Y1710590D03*
Y1734212D03*
X502953Y1672007D03*
X510827Y1677519D03*
X502953Y1681456D03*
X510827Y1682244D03*
X502953Y1686180D03*
X510827Y1705866D03*
X502953Y1709803D03*
X510827Y1710590D03*
X502953Y1714527D03*
X510827Y1734212D03*
X518701Y1672007D03*
X534449D03*
X526575Y1677519D03*
X518701Y1681456D03*
X526575Y1682244D03*
X534449Y1681456D03*
X518701Y1686180D03*
X534449D03*
X526575Y1705866D03*
X518701Y1709803D03*
X526575Y1710590D03*
X534449Y1709803D03*
X518701Y1714527D03*
X534449D03*
X526575Y1734212D03*
X550197Y1672007D03*
X542323Y1677519D03*
Y1682244D03*
X550197Y1681456D03*
Y1686180D03*
X542323Y1705866D03*
Y1710590D03*
X550197Y1709803D03*
Y1714527D03*
X542323Y1734212D03*
X562008Y1677519D03*
Y1682244D03*
Y1705866D03*
Y1710590D03*
Y1734212D03*
X569882Y1672007D03*
X577756Y1677519D03*
X569882Y1681456D03*
X577756Y1682244D03*
X569882Y1686180D03*
X577756Y1705866D03*
X569882Y1709803D03*
X577756Y1710590D03*
X569882Y1714527D03*
X577756Y1734212D03*
X585630Y1672007D03*
X593504Y1677519D03*
X585630Y1681456D03*
X593504Y1682244D03*
X585630Y1686180D03*
X593504Y1705866D03*
X585630Y1709803D03*
X593504Y1710590D03*
X585630Y1714527D03*
X593504Y1734212D03*
X601378Y1672007D03*
X609252Y1677519D03*
X601378Y1681456D03*
X609252Y1682244D03*
X601378Y1686180D03*
X609252Y1705866D03*
X601378Y1709803D03*
X609252Y1710590D03*
X601378Y1714527D03*
X609252Y1734212D03*
X617126Y1672007D03*
Y1681456D03*
Y1686180D03*
Y1709803D03*
Y1714527D03*
X1246654Y1672007D03*
X1238780Y1691692D03*
Y1696417D03*
X1246654Y1695629D03*
Y1700354D03*
X1238780Y1720039D03*
Y1724763D03*
X1246654Y1723976D03*
Y1728700D03*
X1238780Y1734212D03*
X1262402Y1672007D03*
X1254528Y1691692D03*
Y1696417D03*
X1262402Y1695629D03*
Y1700354D03*
X1254528Y1720039D03*
Y1724763D03*
X1262402Y1723976D03*
Y1728700D03*
X1254528Y1734212D03*
X1278150Y1672007D03*
X1270276Y1691692D03*
Y1696417D03*
X1278150Y1695629D03*
Y1700354D03*
X1270276Y1720039D03*
Y1724763D03*
X1278150Y1723976D03*
Y1728700D03*
X1270276Y1734212D03*
X1293898Y1672007D03*
X1286024Y1691692D03*
Y1696417D03*
X1293898Y1695629D03*
Y1700354D03*
X1286024Y1720039D03*
Y1724763D03*
X1293898Y1723976D03*
Y1728700D03*
X1286024Y1734212D03*
X1313583Y1672007D03*
X1305709Y1691692D03*
Y1696417D03*
X1313583Y1695629D03*
Y1700354D03*
X1305709Y1720039D03*
Y1724763D03*
X1313583Y1723976D03*
Y1728700D03*
X1305709Y1734212D03*
X1329331Y1672007D03*
X1321457Y1691692D03*
Y1696417D03*
X1329331Y1695629D03*
Y1700354D03*
X1321457Y1720039D03*
Y1724763D03*
X1329331Y1723976D03*
Y1728700D03*
X1321457Y1734212D03*
X1345079Y1672007D03*
X1337205Y1691692D03*
Y1696417D03*
X1345079Y1695629D03*
Y1700354D03*
X1337205Y1720039D03*
Y1724763D03*
X1345079Y1723976D03*
Y1728700D03*
X1337205Y1734212D03*
X1360827Y1672007D03*
X1352953Y1691692D03*
Y1696417D03*
X1360827Y1695629D03*
Y1700354D03*
X1352953Y1720039D03*
Y1724763D03*
X1360827Y1723976D03*
Y1728700D03*
X1352953Y1734212D03*
X1510827Y1672007D03*
X1502953Y1677519D03*
Y1682244D03*
X1510827Y1681456D03*
Y1686180D03*
X1502953Y1705866D03*
Y1710590D03*
X1510827Y1709803D03*
Y1714527D03*
X1502953Y1734212D03*
X1526575Y1672007D03*
X1518701Y1677519D03*
Y1682244D03*
X1526575Y1681456D03*
Y1686180D03*
X1518701Y1705866D03*
Y1710590D03*
X1526575Y1709803D03*
Y1714527D03*
X1518701Y1734212D03*
X1542323Y1672007D03*
X1534449Y1677519D03*
Y1682244D03*
X1542323Y1681456D03*
Y1686180D03*
X1534449Y1705866D03*
Y1710590D03*
X1542323Y1709803D03*
Y1714527D03*
X1534449Y1734212D03*
X1558071Y1672007D03*
X1550197Y1677519D03*
Y1682244D03*
X1558071Y1681456D03*
Y1686180D03*
X1550197Y1705866D03*
Y1710590D03*
X1558071Y1709803D03*
Y1714527D03*
X1550197Y1734212D03*
X1569882Y1677519D03*
Y1682244D03*
Y1705866D03*
Y1710590D03*
Y1734212D03*
X1577756Y1672007D03*
X1585630Y1677519D03*
X1577756Y1681456D03*
X1585630Y1682244D03*
X1577756Y1686180D03*
X1585630Y1705866D03*
X1577756Y1709803D03*
X1585630Y1710590D03*
X1577756Y1714527D03*
X1585630Y1734212D03*
X1593504Y1672007D03*
X1601378Y1677519D03*
X1593504Y1681456D03*
X1601378Y1682244D03*
X1593504Y1686180D03*
X1601378Y1705866D03*
X1593504Y1709803D03*
X1601378Y1710590D03*
X1593504Y1714527D03*
X1601378Y1734212D03*
X1609252Y1672007D03*
X1617126Y1677519D03*
X1609252Y1681456D03*
X1617126Y1682244D03*
X1609252Y1686180D03*
X1617126Y1705866D03*
X1609252Y1709803D03*
X1617126Y1710590D03*
X1609252Y1714527D03*
X1617126Y1734212D03*
X1625000Y1672007D03*
Y1681456D03*
Y1686180D03*
Y1709803D03*
Y1714527D03*
G54D69*
X1886720Y1001463D03*
X1876720D03*
X1875836Y1303980D03*
X1885836D03*
X1886211Y1364167D03*
X1876211D03*
X1876165Y1669023D03*
X1886165D03*
X1897608Y1001506D03*
X1898086Y1305044D03*
X1897682Y1364479D03*
X1897402Y1670072D03*
X1907608Y1001506D03*
X1908086Y1305044D03*
X1907682Y1364479D03*
X1907402Y1670072D03*
X1935200Y1362732D03*
X1925200D03*
X1924695Y1670036D03*
X1934695D03*
X1946178Y1362781D03*
X1945484Y1670313D03*
X1967697Y1362790D03*
X1956178Y1362781D03*
X1966555Y1669946D03*
X1955484Y1670313D03*
X1977697Y1362790D03*
X1976555Y1669946D03*
X1988618Y1363081D03*
X1998618D03*
X1998147Y1669691D03*
X1988147D03*
G54D17*
X45812Y451602D03*
X61157Y69340D03*
X61470Y84622D03*
X62812Y412708D03*
X62813Y415750D03*
X49212Y451602D03*
X64557Y69340D03*
X72157Y75340D03*
X75557D03*
X64870Y84622D03*
X78120Y1515436D03*
Y1518836D03*
X64410Y1599102D03*
Y1602502D03*
X86557Y69340D03*
X83157D03*
X94157Y75340D03*
X90998Y1518937D03*
Y1515537D03*
X108557Y69340D03*
X105157D03*
X97557Y75340D03*
X127157Y69340D03*
X116157Y75340D03*
X119557D03*
X130557Y69340D03*
X138157Y75340D03*
X141557D03*
X152557Y69340D03*
X149157D03*
X175761D03*
X172361D03*
X161361Y75340D03*
X164761D03*
X183361D03*
X186761D03*
X197761Y69340D03*
X194361D03*
X205495Y75340D03*
X208895D03*
X194197Y1614292D03*
X197597D03*
X206257D03*
X194197Y1602380D03*
X197597D03*
X206257D03*
X219895Y69340D03*
X216495D03*
X209657Y1614292D03*
X218317D03*
X221717D03*
X209657Y1602380D03*
X218317D03*
X221717D03*
X227495Y75340D03*
X230895D03*
X230377Y1614292D03*
X233777D03*
X230377Y1602380D03*
X233777D03*
X242437Y1614292D03*
X254497D03*
X245837D03*
X242437Y1602380D03*
X254497D03*
X245837D03*
X266557Y1614292D03*
X257897D03*
X269957D03*
X266557Y1602380D03*
X257897D03*
X269957D03*
X278617Y1614292D03*
X282017D03*
X278617Y1602380D03*
X282017D03*
X290677Y1614292D03*
X302737D03*
X294077D03*
X306137D03*
X290677Y1602380D03*
X302737D03*
X294077D03*
X306137D03*
X314797Y1614292D03*
X318197D03*
X314797Y1602380D03*
X318197D03*
X330257Y1614292D03*
X338917D03*
X326857D03*
X330257Y1602380D03*
X338917D03*
X326857D03*
X350977Y1614292D03*
X342317D03*
X354377D03*
X350977Y1602380D03*
X342317D03*
X354377D03*
X363037Y1614292D03*
X366437D03*
X363037Y1602380D03*
X366437D03*
X375097Y1614292D03*
X378497D03*
X375097Y1602380D03*
X378497D03*
X478351Y1614292D03*
X481751D03*
X478351Y1602380D03*
X481751D03*
X490411Y1614292D03*
X493811D03*
X490411Y1602380D03*
X493811D03*
X514531Y1614292D03*
X502471D03*
X517931D03*
X505871D03*
X514531Y1602380D03*
X502471D03*
X517931D03*
X505871D03*
X519764Y40328D03*
X523164D03*
X519742Y71436D03*
X523142D03*
X526591Y1614292D03*
X529991D03*
X526591Y1602380D03*
X529991D03*
X538651Y1614292D03*
X542051D03*
X538651Y1602380D03*
X542051D03*
X555175Y71436D03*
X558575D03*
X562771Y1614292D03*
X550711D03*
X566171D03*
X554111D03*
X562771Y1602380D03*
X550711D03*
X566171D03*
X554111D03*
X574831Y1614292D03*
X578231D03*
X574831Y1602380D03*
X578231D03*
X598951Y1614292D03*
X586891D03*
X590291D03*
X598951Y1602380D03*
X586891D03*
X590291D03*
X613970Y188752D03*
X611011Y1614292D03*
X614411D03*
X602351D03*
X611011Y1602380D03*
X614411D03*
X602351D03*
X617370Y188752D03*
X630040D03*
X626640D03*
X623071Y1614292D03*
X626471D03*
X623071Y1602380D03*
X626471D03*
X647191Y1614292D03*
X635131D03*
X638531D03*
X647191Y1602380D03*
X635131D03*
X638531D03*
X656439Y47264D03*
X659839D03*
X662651Y1614292D03*
X659251D03*
X650591D03*
X662651Y1602380D03*
X659251D03*
X650591D03*
X723041Y-13200D03*
Y-9800D03*
Y-19800D03*
Y-23200D03*
X840001Y6800D03*
Y20200D03*
Y16800D03*
Y10200D03*
X902350Y208294D03*
X907470Y211980D03*
X902350Y204894D03*
X907470Y215380D03*
X902350Y219068D03*
X907470Y226154D03*
X902350Y222468D03*
X907470Y229554D03*
X953970Y208275D03*
X947496Y215397D03*
X953970Y204875D03*
X947496Y211997D03*
X957156Y227163D03*
X947496Y226135D03*
X957156Y230563D03*
X947496Y229535D03*
X980899Y-13200D03*
Y-9800D03*
Y-19800D03*
Y-23200D03*
Y6800D03*
Y20200D03*
Y16800D03*
Y10200D03*
X1032433Y-29811D03*
Y-33211D03*
Y-23211D03*
Y-19811D03*
Y-13211D03*
Y-9811D03*
Y-3211D03*
Y189D03*
X1156770Y638192D03*
X1153370D03*
X1161860Y642112D03*
X1165260D03*
X1173220Y636052D03*
X1169820D03*
X1183360Y642062D03*
X1186760D03*
X1196772Y1578182D03*
X1200172D03*
X1196772Y1590094D03*
X1200172D03*
X1212232Y1578182D03*
X1208832D03*
X1212232Y1590094D03*
X1208832D03*
X1220892Y1578182D03*
X1232952D03*
X1224292D03*
X1220892Y1590094D03*
X1232952D03*
X1224292D03*
X1245012Y1578182D03*
X1236352D03*
X1248412D03*
X1245012Y1590094D03*
X1236352D03*
X1248412D03*
X1257072Y1578182D03*
X1260472D03*
X1257072Y1590094D03*
X1260472D03*
X1269132Y1578182D03*
X1281192D03*
X1272532D03*
X1269132Y1590094D03*
X1281192D03*
X1272532D03*
X1290291Y-29811D03*
Y-33211D03*
Y-23211D03*
Y-19811D03*
Y-13211D03*
Y-9811D03*
Y-3211D03*
Y189D03*
X1293252Y1578182D03*
X1284592D03*
X1296652D03*
X1293252Y1590094D03*
X1284592D03*
X1296652D03*
X1305312Y1578182D03*
X1308712D03*
X1305312Y1590094D03*
X1308712D03*
X1317372Y1578182D03*
X1320772D03*
X1329432D03*
X1317372Y1590094D03*
X1320772D03*
X1329432D03*
X1341752Y-29811D03*
Y-33211D03*
Y-19811D03*
Y-23211D03*
Y-9811D03*
Y-13211D03*
Y189D03*
Y-3211D03*
X1344684Y280259D03*
X1332832Y1578182D03*
X1341492D03*
X1344892D03*
X1332832Y1590094D03*
X1341492D03*
X1344892D03*
X1348084Y280259D03*
X1358624Y284644D03*
X1355224D03*
X1353552Y1578182D03*
X1356952D03*
X1353552Y1590094D03*
X1356952D03*
X1380522Y260236D03*
Y263636D03*
X1368524Y282744D03*
X1365124D03*
X1378306Y657608D03*
X1374668Y659708D03*
X1378306Y669608D03*
X1374668Y671708D03*
Y683708D03*
X1378306Y681608D03*
X1374668Y695708D03*
X1378306Y693608D03*
Y705608D03*
X1374668Y707708D03*
Y719708D03*
X1378306Y717608D03*
X1365612Y1578182D03*
X1377672D03*
X1369012D03*
X1365612Y1590094D03*
X1377672D03*
X1369012D03*
X1384002Y197668D03*
X1389256D03*
X1380602D03*
X1392656D03*
X1380638Y245694D03*
X1386630Y238651D03*
X1380638Y249094D03*
X1386630Y242051D03*
X1388754Y253803D03*
Y257203D03*
X1386273Y268670D03*
Y272070D03*
X1393206Y664708D03*
X1389568Y662608D03*
X1393206Y679208D03*
X1389568Y677108D03*
X1393206Y693708D03*
X1389568Y691608D03*
Y706108D03*
X1393206Y708208D03*
X1393199Y722708D03*
X1389561Y720608D03*
X1385338Y735098D03*
X1388976Y737198D03*
X1381072Y1578182D03*
Y1590094D03*
X1412284Y171696D03*
X1398006Y197668D03*
X1406786D03*
X1401406D03*
X1410186D03*
X1407420Y220018D03*
X1410820D03*
X1404385Y240929D03*
X1400985D03*
X1415684Y171696D03*
X1436060Y220018D03*
X1432660D03*
X1457176Y656992D03*
X1460814Y654892D03*
Y666892D03*
X1457176Y668992D03*
X1460814Y678892D03*
X1457176Y680992D03*
X1460814Y690892D03*
X1457176Y704992D03*
Y692992D03*
X1460814Y702892D03*
X1457176Y716992D03*
X1460814Y714892D03*
X1472076Y657392D03*
Y671892D03*
X1475714Y659492D03*
Y673992D03*
X1472076Y686392D03*
X1475714Y688492D03*
X1472076Y700892D03*
X1475714Y702992D03*
X1472076Y715392D03*
X1475714Y717492D03*
X1468876Y728392D03*
X1472514Y730492D03*
X1467595Y1614292D03*
X1470995D03*
X1467595Y1602380D03*
X1470995D03*
X1482650Y-29811D03*
Y-33211D03*
Y-19811D03*
Y-23211D03*
Y-9811D03*
Y-13211D03*
Y189D03*
Y-3211D03*
X1491715Y1614292D03*
X1479655D03*
X1483055D03*
X1491715Y1602380D03*
X1479655D03*
X1483055D03*
X1503775Y1614292D03*
X1507175D03*
X1495115D03*
X1503775Y1602380D03*
X1507175D03*
X1495115D03*
X1515835Y1614292D03*
X1519235D03*
X1515835Y1602380D03*
X1519235D03*
X1538996Y69297D03*
X1535596D03*
X1527895Y1614292D03*
X1539955D03*
X1531295D03*
X1527895Y1602380D03*
X1539955D03*
X1531295D03*
X1557596Y69297D03*
X1546596Y75297D03*
X1549996D03*
X1552015Y1614292D03*
X1555415D03*
X1543355D03*
X1552015Y1602380D03*
X1555415D03*
X1543355D03*
X1560996Y69297D03*
X1568596Y75297D03*
X1571996D03*
X1564075Y1614292D03*
X1567475D03*
X1564075Y1602380D03*
X1567475D03*
X1582996Y69297D03*
X1579596D03*
X1590596Y75297D03*
X1588195Y1614292D03*
X1576135D03*
X1591595D03*
X1579535D03*
X1588195Y1602380D03*
X1576135D03*
X1591595D03*
X1579535D03*
X1604996Y69297D03*
X1601596D03*
X1593996Y75297D03*
X1600255Y1614292D03*
X1603655D03*
X1600255Y1602380D03*
X1603655D03*
X1623596Y69297D03*
X1612596Y75297D03*
X1615996D03*
X1612315Y1614292D03*
X1615715D03*
X1612315Y1602380D03*
X1615715D03*
X1626996Y69297D03*
X1635800Y75297D03*
X1639200D03*
X1636435Y1614292D03*
X1624375D03*
X1639835D03*
X1627775D03*
X1636435Y1602380D03*
X1624375D03*
X1639835D03*
X1627775D03*
X1650200Y69297D03*
X1646800D03*
X1651895Y1614292D03*
X1648495D03*
X1651895Y1602380D03*
X1648495D03*
X1672200Y69297D03*
X1668800D03*
X1657800Y75297D03*
X1661200D03*
X1679934D03*
X1683334D03*
X1694334Y69297D03*
X1690934D03*
X1705334Y75297D03*
X1701934D03*
G54D40*
X338042Y849978D03*
X337778Y854584D03*
X335924Y857789D03*
X334079Y880219D03*
X332228Y877014D03*
X335928D03*
X334078Y893036D03*
X335928Y896240D03*
X332229Y902649D03*
X332228Y915466D03*
X335928D03*
X332229Y921875D03*
Y941100D03*
X332228Y934692D03*
X335928D03*
X334079Y957122D03*
X335928Y953917D03*
X332228D03*
X332229Y973143D03*
X334079Y976347D03*
X331284Y978814D03*
X335349Y985939D03*
X338210Y996480D03*
X332661Y1006093D03*
X338211Y1002888D03*
X332661Y1025318D03*
Y1018910D03*
X338211Y1015705D03*
Y1022114D03*
X332661Y1044544D03*
X338211Y1041340D03*
X334511D03*
X338211Y1060565D03*
X333834Y1062790D03*
X329632Y1092168D03*
X336360Y1082995D03*
X338211Y1111834D03*
Y1105426D03*
X335344Y1097289D03*
X338211Y1124651D03*
X336361Y1115039D03*
Y1127856D03*
Y1121447D03*
X345178Y854584D03*
X347028Y844971D03*
X345178Y848176D03*
X350727Y844971D03*
X347027Y851380D03*
X343327D03*
X354429D03*
X341478Y854584D03*
X339628Y857789D03*
X347029Y864197D03*
Y857789D03*
X348878Y854584D03*
X345179Y860993D03*
X343327Y857789D03*
X352579Y854584D03*
X354429Y864197D03*
X350729D03*
X341479Y867401D03*
X348879D03*
X352579D03*
X347029Y870606D03*
X354429Y877014D03*
X339629D03*
X341479Y873810D03*
X345179Y880219D03*
Y873810D03*
X343329Y877014D03*
X352579Y880219D03*
X350729Y877014D03*
X339629Y883423D03*
X347029D03*
X350729D03*
Y870606D03*
X354429D03*
X352578Y873810D03*
X354429Y883423D03*
X347029Y877014D03*
X348878Y880219D03*
X352578Y899445D03*
X339629Y896240D03*
Y889832D03*
X348879Y886627D03*
X347029Y889832D03*
X345179Y893036D03*
X343328Y896240D03*
X352578Y893036D03*
Y886627D03*
X345179Y899445D03*
X348878Y905853D03*
X352578D03*
X341479Y912262D03*
X341478Y905853D03*
X347029Y909057D03*
Y902649D03*
X345179Y912262D03*
X352578D03*
X339629Y915466D03*
X343329D03*
X348878Y925079D03*
X352578D03*
Y918670D03*
X341478Y925079D03*
X347029Y928283D03*
Y921875D03*
X345179Y918670D03*
X341479Y931488D03*
X345179D03*
X352578D03*
X341478Y944304D03*
X352578D03*
X347029Y941100D03*
X348878Y944304D03*
X347029Y947509D03*
X352578Y937896D03*
X339629Y934692D03*
X345179Y937896D03*
X343328Y934692D03*
X348878Y963530D03*
X347029Y960326D03*
X343328D03*
X343329Y966735D03*
X339629D03*
Y953917D03*
X343328D03*
X345179Y957122D03*
X352578D03*
X347029Y966735D03*
X352578Y963530D03*
X341479Y950713D03*
X345179D03*
X352578D03*
X354428Y973143D03*
X339629D03*
X345179Y976347D03*
Y969939D03*
X350729Y973143D03*
X347029Y979552D03*
X352579Y976347D03*
X352578Y969939D03*
X348878Y982756D03*
X352578D03*
X339629Y979552D03*
X343329Y973143D03*
X341911Y1009297D03*
Y1002888D03*
X347461Y999684D03*
X345611Y1009297D03*
X343761Y1006093D03*
X345611Y1002888D03*
X351162Y1006093D03*
X354861D03*
X353011Y1009297D03*
Y1002888D03*
X347461Y1012501D03*
X343761Y999684D03*
X353011Y1028523D03*
Y1015705D03*
X341911Y1022114D03*
Y1015705D03*
X349311D03*
X347461Y1018910D03*
X345611Y1028523D03*
X343761Y1018910D03*
X345611Y1022114D03*
Y1015705D03*
X353011Y1022114D03*
X343761Y1031727D03*
X347461D03*
X353011Y1034931D03*
Y1047749D03*
X341911Y1041340D03*
X343761Y1038136D03*
X349311Y1034931D03*
X347461Y1038136D03*
X345611Y1041340D03*
X343761Y1044544D03*
X353011Y1041340D03*
X345611Y1047749D03*
X349311Y1054157D03*
X353011Y1060565D03*
Y1054157D03*
X343761Y1057361D03*
Y1050952D03*
X347461D03*
Y1057361D03*
X345611Y1060565D03*
X343761Y1063770D03*
X353011Y1073383D03*
X343761Y1076587D03*
Y1070178D03*
X340062Y1076587D03*
X347461D03*
Y1070178D03*
X349312Y1073383D03*
X345611Y1066974D03*
X353011D03*
X345611Y1079791D03*
X341911D03*
X353011D03*
Y1086200D03*
X349310Y1092609D03*
X347461Y1089404D03*
X345610Y1086200D03*
X343760Y1082995D03*
X343707Y1091513D03*
X340060Y1082995D03*
X353011Y1092608D03*
X340061Y1095813D03*
X347461Y1108630D03*
X354861D03*
X353011Y1099017D03*
X340061Y1108630D03*
Y1102221D03*
X349311Y1099017D03*
X347461Y1102221D03*
X343761D03*
X340061Y1115039D03*
X349311Y1124651D03*
X349312Y1118243D03*
X345611D03*
X343761Y1115039D03*
X341911Y1124651D03*
X354861Y1115039D03*
X351161Y1121447D03*
Y1115039D03*
X341912Y1118243D03*
X340061Y1127856D03*
X343761D03*
X347461Y1121447D03*
X340061D03*
X343761D03*
X347461Y1127856D03*
X345611Y1124651D03*
Y1137469D03*
Y1131060D03*
X349311D03*
X343761Y1134264D03*
X353011Y1137469D03*
Y1131060D03*
X341911D03*
X359979Y841467D03*
X367379D03*
X365529Y851380D03*
X361829D03*
X358129D03*
X369229D03*
X365529Y864197D03*
X361829D03*
X359979Y854584D03*
X358129Y864197D03*
X369229D03*
X367379Y854584D03*
X359979Y867401D03*
X367379D03*
X371078D03*
X356278D03*
X363678D03*
X365529Y877014D03*
X361829D03*
X359979Y880219D03*
X358129Y877014D03*
X369229D03*
X367379Y880219D03*
X358129Y870606D03*
X361829D03*
X365529D03*
X359978Y873810D03*
X367378D03*
X369229Y870606D03*
X356278Y880219D03*
X358129Y883423D03*
X363678Y880219D03*
X365529Y883423D03*
X371078Y880219D03*
X361829Y883423D03*
X369229D03*
X356278Y886627D03*
X365529Y896240D03*
Y889832D03*
X361828Y896240D03*
X361829Y889832D03*
X359979Y893036D03*
X358128Y889832D03*
X369229Y896240D03*
Y889832D03*
X359979Y899445D03*
X371078D03*
X363679Y893036D03*
X367379D03*
X359978Y886627D03*
X367378D03*
X356278Y905853D03*
X365529Y909057D03*
Y902649D03*
X359978Y912262D03*
X358128Y909057D03*
X358129Y902649D03*
X371079Y912262D03*
X365529Y915466D03*
X361828D03*
X369229D03*
X356279Y925079D03*
X365529Y928283D03*
Y921875D03*
X359979Y918670D03*
X358128Y928283D03*
X358129Y921875D03*
X371078Y918670D03*
X359978Y931488D03*
X371079D03*
X358128Y947509D03*
X358129Y941100D03*
X356279Y944304D03*
X365529Y947509D03*
Y941100D03*
Y934691D03*
X361828D03*
X359979Y937896D03*
X369229Y934691D03*
X371078Y937896D03*
X356279Y963530D03*
X358129Y960326D03*
X359979Y957122D03*
X358128Y966735D03*
X361829Y953917D03*
X359978Y950713D03*
X371078Y957122D03*
X371079Y950713D03*
X365529Y953917D03*
X367378Y963530D03*
X363679D03*
X365529Y960326D03*
X365528Y966735D03*
X369229Y953917D03*
X359979Y976347D03*
X358129Y979552D03*
X359978Y969939D03*
X361828Y973143D03*
X356279Y982756D03*
X371078Y976347D03*
X371079Y969939D03*
X369229Y973143D03*
X365529Y979552D03*
Y973143D03*
X365962Y999684D03*
Y1006093D03*
X362261D03*
X360411Y1009297D03*
X360412Y1002888D03*
X358562Y999684D03*
X369662Y1006093D03*
X371512Y1009297D03*
X365961Y1012501D03*
X358561D03*
X367811Y1002888D03*
X356712Y1015705D03*
X365962Y1025318D03*
Y1018910D03*
X364112Y1015705D03*
X360411Y1028523D03*
X362261Y1025318D03*
X360412Y1022114D03*
X358562Y1018910D03*
X369662Y1025318D03*
X367811Y1015705D03*
X371511Y1028523D03*
Y1022114D03*
X365962Y1031727D03*
X358561D03*
X356712Y1034931D03*
X365962Y1044544D03*
Y1038136D03*
X362261Y1044544D03*
X360412Y1041340D03*
X358562Y1038136D03*
X369662Y1044544D03*
X371511Y1041340D03*
X360411Y1047749D03*
X371511D03*
X356712Y1054157D03*
X365962Y1057361D03*
Y1050952D03*
X360412Y1060565D03*
X358562Y1057361D03*
X358561Y1050952D03*
X371511Y1060565D03*
X365962Y1063770D03*
X362261D03*
X369662D03*
X356712Y1073383D03*
X365962Y1070178D03*
Y1076587D03*
X360411Y1066974D03*
X358561Y1070178D03*
X358562Y1076587D03*
X371512Y1066974D03*
X360412Y1079791D03*
X371511D03*
X365962Y1089404D03*
Y1082995D03*
X362261D03*
X360411Y1086200D03*
X358561Y1089404D03*
X356712Y1092608D03*
X369662Y1082995D03*
X371512Y1086200D03*
X365962Y1095813D03*
X358561D03*
X365962Y1102221D03*
X362262D03*
X360411Y1099017D03*
X356711Y1105426D03*
Y1099017D03*
X371512Y1105426D03*
Y1099017D03*
X364112Y1111834D03*
X356712D03*
X371512D03*
X358561Y1108630D03*
X360412Y1111834D03*
X364112Y1105426D03*
X369661Y1108630D03*
X362261D03*
X365961D03*
X367812Y1111834D03*
X364111Y1118243D03*
X362261Y1115039D03*
X360411Y1118243D03*
X356711D03*
X367811D03*
X371511D03*
X365962Y1127856D03*
X358561D03*
X365961Y1115039D03*
X358561D03*
X369661D03*
X365961Y1140973D03*
X364112Y1131060D03*
X360412D03*
X358561Y1140973D03*
X356712Y1131060D03*
X367811D03*
X371511D03*
X382179Y841467D03*
X374779D03*
X380329Y851380D03*
X376629D03*
X372929D03*
X384029D03*
X387729D03*
X382179Y854584D03*
X380329Y864197D03*
X376629D03*
X374779Y854584D03*
X372929Y864197D03*
X384029D03*
X387729D03*
X382179Y867401D03*
X374779D03*
X378478D03*
X385878D03*
X378478Y860993D03*
X385878D03*
X382179Y880219D03*
X380329Y877014D03*
X376629D03*
X374779Y880219D03*
X372929Y877014D03*
X384029D03*
X387729D03*
Y870606D03*
X372929D03*
X380329D03*
X374778Y873810D03*
X376629Y870606D03*
X382178Y873810D03*
X384029Y870606D03*
X372929Y883423D03*
X378478Y880219D03*
X380329Y883423D03*
X385878Y880219D03*
X387729Y883423D03*
X376629D03*
X384029D03*
X385878Y873810D03*
X380329Y889832D03*
X378479Y893036D03*
X376629Y889832D03*
X372929D03*
X384029D03*
X387729Y896240D03*
Y889832D03*
X378478Y899445D03*
X385879D03*
X374778Y886627D03*
X382178D03*
X385878D03*
X382179Y905853D03*
X378478Y912262D03*
Y905853D03*
X374778D03*
X372929Y909057D03*
X372928Y902649D03*
X385878Y912262D03*
X384028Y909057D03*
X384029Y902649D03*
X387728Y915466D03*
X387729Y909057D03*
Y902649D03*
X385878Y905853D03*
X382179Y925079D03*
X378478D03*
Y918670D03*
X374778Y925079D03*
X372929Y928283D03*
X372928Y921875D03*
X385879Y918670D03*
X384028Y928283D03*
X384029Y921875D03*
X378478Y931488D03*
X385878D03*
X387729Y921875D03*
Y928283D03*
X385878Y925079D03*
X384029Y941100D03*
X384028Y947509D03*
X374778Y944304D03*
X372929Y947509D03*
X372928Y941100D03*
X382179Y944304D03*
X378478D03*
Y937896D03*
X385879D03*
X387728Y934691D03*
X387729Y947509D03*
Y941100D03*
X385878Y944304D03*
X387729Y953917D03*
X372928Y960326D03*
X374778Y963530D03*
X372929Y966735D03*
X382179Y963530D03*
X378478D03*
Y957122D03*
X384029Y960326D03*
X385879Y957122D03*
X384028Y966735D03*
X385878Y950713D03*
X378478D03*
X387729Y960326D03*
Y966735D03*
X385878Y963530D03*
X387728Y973143D03*
X376629D03*
X380328D03*
X378479Y976347D03*
X378478Y969939D03*
X385879Y976347D03*
X384029Y979552D03*
X385878Y969939D03*
X374778Y982756D03*
X382179D03*
X378478D03*
X372928Y979552D03*
X385878Y982756D03*
X387729Y979552D03*
X376629D03*
X380329D03*
X374778Y976347D03*
X382178D03*
X372929Y973143D03*
X384029D03*
X375210Y996480D03*
X373361Y999684D03*
X378911Y1009297D03*
Y1002888D03*
X386311Y1009297D03*
X386312Y1002888D03*
X384462Y999684D03*
X373362Y1012501D03*
X384461D03*
X382612Y1015705D03*
X378911Y1028523D03*
Y1022114D03*
Y1015705D03*
X375211D03*
X373361Y1018910D03*
X386311Y1028523D03*
X386312Y1022114D03*
X384462Y1018910D03*
X373362Y1031727D03*
X384461D03*
X386311Y1015705D03*
X382612Y1034931D03*
X378911Y1041340D03*
Y1034931D03*
X375211D03*
X373361Y1038136D03*
X386312Y1041340D03*
X384462Y1038136D03*
X378911Y1047749D03*
X386311D03*
Y1034931D03*
X382612Y1054157D03*
X378911Y1060565D03*
Y1054157D03*
X375211D03*
X373361Y1057361D03*
X373362Y1050952D03*
X386312Y1060565D03*
X384462Y1057361D03*
X384461Y1050952D03*
X386311Y1054157D03*
X382612Y1073383D03*
X378911D03*
Y1066974D03*
X375211Y1073383D03*
X373361Y1076587D03*
X373362Y1070178D03*
X386311Y1066974D03*
X384462Y1076587D03*
X384461Y1070178D03*
X378911Y1079791D03*
X386311D03*
Y1073383D03*
X382611Y1092608D03*
X378911D03*
Y1086200D03*
X375211Y1092608D03*
X373362Y1089404D03*
X386311Y1086200D03*
X384461Y1089404D03*
X373362Y1095813D03*
X384462D03*
X386311Y1092608D03*
X375211Y1099017D03*
X380762Y1108630D03*
X378911Y1099017D03*
X377062Y1102221D03*
X373361Y1108630D03*
Y1102221D03*
X386312Y1099017D03*
X384462Y1102221D03*
X382611Y1118243D03*
X378911D03*
X377061Y1115039D03*
X375211Y1118243D03*
X373361Y1115039D03*
X386311Y1118243D03*
X384461Y1115039D03*
X380761Y1127856D03*
X373361D03*
X382611Y1131060D03*
X380761Y1140973D03*
X378911Y1131060D03*
X375211D03*
X373361Y1140973D03*
X386311Y1131060D03*
X396979Y841467D03*
X389579D03*
X398829Y851380D03*
X395129D03*
X391429D03*
X402529D03*
X398829Y864197D03*
X396979Y854584D03*
X395129Y864197D03*
X391429D03*
X389579Y854584D03*
X402529Y864197D03*
X396979Y867401D03*
X389579D03*
X400678D03*
X393278D03*
Y860993D03*
X398829Y877014D03*
X396979Y880219D03*
X395129Y877014D03*
X391429D03*
X389579Y880219D03*
X402529Y877014D03*
X391429Y870606D03*
X395129D03*
X402529D03*
X389578Y873810D03*
X396978D03*
X398829Y870606D03*
X393278Y880219D03*
X395129Y883423D03*
X400678Y880219D03*
X402529Y883423D03*
X391429D03*
X398829D03*
X393278Y873810D03*
X400678D03*
X398829Y889832D03*
X395129Y896240D03*
Y889832D03*
X391428Y896240D03*
X391429Y889832D03*
X389579Y893036D03*
X402529Y889832D03*
X396978Y899445D03*
X402529Y896240D03*
X400678Y899445D03*
X389578D03*
X393278D03*
X393279Y893036D03*
X396979D03*
X396978Y886627D03*
X389578D03*
X398829Y896240D03*
X400678Y893036D03*
X393278Y886627D03*
X400678D03*
X404378Y899445D03*
X398829Y909057D03*
X398828Y902649D03*
X396979Y912262D03*
X391429Y909057D03*
Y902649D03*
X395129Y915466D03*
X391429D03*
X400678Y905853D03*
X402529Y915466D03*
Y909057D03*
X389578Y912262D03*
X393278D03*
X395129Y909057D03*
Y902649D03*
X393278Y905853D03*
X389578D03*
X396978D03*
X406229Y915466D03*
X400678Y912262D03*
X402529Y902649D03*
X400678Y931488D03*
X402529Y928283D03*
Y921875D03*
X398829Y928283D03*
X398828Y921875D03*
X396978Y918670D03*
X391429Y928283D03*
Y921875D03*
X400678Y925079D03*
X396979Y931488D03*
X393278D03*
X395129Y928283D03*
X389578Y918670D03*
X395129Y921875D03*
X393278Y918670D03*
X389578Y931488D03*
X393278Y925079D03*
X389578D03*
X396978D03*
X398829Y934691D03*
X402529D03*
X398828Y941100D03*
X396978Y937896D03*
X395129Y934691D03*
X391429Y941100D03*
Y934691D03*
X400678Y937896D03*
X398829Y947509D03*
X391429D03*
X395129D03*
X389578Y937896D03*
X395129Y941100D03*
X393278Y937896D03*
Y944304D03*
X389578D03*
X396978D03*
X402529Y941100D03*
X400679Y944304D03*
X398828Y960326D03*
X396978Y957122D03*
X396979Y950713D03*
X395129Y953917D03*
X391429Y960326D03*
Y953917D03*
X400678Y957122D03*
X398829Y966735D03*
X391429D03*
X400678Y963530D03*
X389578Y957122D03*
X395129Y960326D03*
X393278Y957122D03*
X395129Y966735D03*
X389578Y950713D03*
X393278D03*
X396978Y963530D03*
X393278D03*
X389578D03*
X402529Y966735D03*
Y960326D03*
X398828Y979552D03*
X396978Y976347D03*
X396979Y969939D03*
X395129Y973143D03*
X391429Y979552D03*
Y973143D03*
X400678Y982756D03*
Y969939D03*
X393278Y982756D03*
X389578D03*
X396978D03*
X393278Y976347D03*
X395129Y979552D03*
X389579Y976347D03*
X389578Y969939D03*
X393278D03*
X397412Y1009297D03*
X397411Y1002888D03*
X395562Y1006093D03*
X391862D03*
Y999684D03*
X388161Y1006093D03*
X401111Y1002888D03*
X399262Y1012501D03*
X391861D03*
X399262Y1006093D03*
X402962D03*
X399262Y999684D03*
X402962D03*
X388162Y1012501D03*
X395562D03*
X390011Y1009297D03*
X393711D03*
X401111D03*
X402962Y1012501D03*
Y1031727D03*
X399261Y1018910D03*
X397411Y1028523D03*
Y1022114D03*
X395562Y1025318D03*
X393711Y1015705D03*
X391862Y1025318D03*
Y1018910D03*
X390012Y1015705D03*
X388161Y1025318D03*
X399262Y1031727D03*
X391862D03*
X397411Y1015705D03*
X388162Y1031727D03*
X390011Y1028523D03*
X395562Y1031727D03*
X393711Y1028523D03*
X390011Y1022114D03*
X388162Y1018910D03*
X393711Y1022114D03*
X395562Y1018910D03*
X401111Y1028523D03*
Y1015705D03*
X399261Y1038136D03*
X397411Y1041340D03*
X395562Y1044544D03*
X391862D03*
Y1038136D03*
X388161Y1044544D03*
X397411Y1047749D03*
X390011Y1041340D03*
X388162Y1038136D03*
X393711Y1041340D03*
X395562Y1038136D03*
X390011Y1047749D03*
X393711D03*
Y1034931D03*
X390011D03*
X397411D03*
X401111Y1047749D03*
X402962Y1038136D03*
X406662Y1057361D03*
X399261D03*
X399262Y1050952D03*
X397411Y1060565D03*
X391862Y1057361D03*
Y1050952D03*
X395562Y1063770D03*
X391862D03*
X388161D03*
X390011Y1060565D03*
X388162Y1057361D03*
X393711Y1060565D03*
X395562Y1057361D03*
X388162Y1050952D03*
X395562D03*
X393711Y1054157D03*
X390011D03*
X397411D03*
X402962Y1057361D03*
Y1063770D03*
X401113Y1060565D03*
X399262Y1063770D03*
X401111Y1054157D03*
X402962Y1050952D03*
Y1076587D03*
Y1070178D03*
X399261Y1076587D03*
X399262Y1070178D03*
X397412Y1066974D03*
X391862Y1076587D03*
Y1070178D03*
X401111Y1073383D03*
X397411Y1079791D03*
X401111D03*
X390011D03*
X388162Y1076587D03*
X393711Y1079791D03*
X395562Y1076587D03*
X388162Y1070178D03*
X390011Y1066974D03*
X395562Y1070178D03*
X393711Y1066974D03*
Y1073383D03*
X390011D03*
X397411D03*
X401112Y1066974D03*
X399262Y1089404D03*
X397412Y1086200D03*
X395562Y1082995D03*
X391862Y1089404D03*
Y1082995D03*
X388161D03*
X401112Y1092608D03*
X401111Y1086200D03*
X399261Y1095813D03*
X391862D03*
X402962D03*
X395562D03*
X388162Y1089404D03*
X390011Y1086200D03*
X395562Y1089404D03*
X393711Y1086200D03*
X388162Y1095813D03*
X393711Y1092608D03*
X390011D03*
X397411D03*
X399262Y1102221D03*
X397412Y1099017D03*
X395562Y1102221D03*
X390011Y1105426D03*
X388162Y1108630D03*
Y1102221D03*
X401111Y1105426D03*
X397411Y1111834D03*
X390011D03*
X393711Y1099017D03*
X390011D03*
X401111D03*
X391862Y1108630D03*
X393711Y1111834D03*
X397411Y1105426D03*
X402962Y1108630D03*
Y1102221D03*
X395562Y1108630D03*
X399262D03*
X401111Y1111834D03*
X397411Y1118243D03*
X395561Y1115039D03*
X393711Y1118243D03*
X390011D03*
X388161Y1115039D03*
X401111Y1118243D03*
X395561Y1127856D03*
X388161D03*
X402961D03*
X399262Y1115039D03*
X391862D03*
X402962D03*
X399262Y1121447D03*
X397411Y1131060D03*
X395561Y1140973D03*
X393711Y1131060D03*
X390011D03*
X388161Y1140973D03*
X402961D03*
X401111Y1131060D03*
X419179Y841467D03*
X404379D03*
X411779D03*
X413629Y851380D03*
X409929D03*
X406229D03*
X417329D03*
X404379Y854584D03*
X413629Y864197D03*
X411779Y854584D03*
X409929Y864197D03*
X406229D03*
X419179Y854584D03*
X417329Y864197D03*
X404379Y867401D03*
X411779D03*
X419179D03*
X408078D03*
X415478D03*
X404379Y880219D03*
X413629Y877014D03*
X411779Y880219D03*
X409929Y877014D03*
Y870606D03*
X406229Y877014D03*
X419179Y880219D03*
X417329Y877014D03*
X404378Y873810D03*
X406229Y870606D03*
X408078Y880219D03*
X409929Y883423D03*
X406229D03*
X419178Y873810D03*
X417329Y870606D03*
X411778Y873810D03*
X413629Y870606D03*
X408078Y873810D03*
X413629Y889832D03*
X411779Y893036D03*
X409929Y889832D03*
X408079Y893036D03*
X406229Y889832D03*
X419179Y893036D03*
X417329Y889832D03*
X404378Y886627D03*
X411778D03*
X404378Y893036D03*
X415478Y886627D03*
X408078D03*
X406229Y896240D03*
X408078Y899445D03*
X415478D03*
X409929Y896240D03*
X415478Y893036D03*
X417329Y896240D03*
X422878Y893036D03*
X411778Y899445D03*
X413629Y896240D03*
X419178Y899445D03*
X422878Y912262D03*
X413629Y902649D03*
X409929Y909057D03*
Y902649D03*
X404378Y912262D03*
Y905853D03*
X419178Y912262D03*
X419179Y905853D03*
X417329Y902649D03*
X409929Y915466D03*
X417329Y909057D03*
X406229D03*
X413629D03*
Y915466D03*
X411778Y905853D03*
X408078D03*
Y912262D03*
X406229Y902649D03*
X415478Y905853D03*
X411778Y912262D03*
X415478D03*
X417329Y915466D03*
X411779Y918670D03*
X406229Y921875D03*
X409929D03*
X404378Y918670D03*
X418229Y926896D03*
X419178Y918670D03*
X405048Y930812D03*
X408078Y918670D03*
X408569Y929108D03*
X406308Y928626D03*
X417329Y921875D03*
X411872Y925264D03*
X415479Y918670D03*
X405145Y946239D03*
Y948539D03*
X414093Y942098D03*
X405048Y938046D03*
Y935746D03*
X416393Y942098D03*
X418693D03*
X407589Y942164D03*
X405289D03*
X409889D03*
X405122Y965896D03*
Y963596D03*
X414365Y971140D03*
X416755D03*
X404861Y981269D03*
Y978969D03*
Y986421D03*
X405101Y992971D03*
Y995271D03*
X404861Y988721D03*
X415185Y985580D03*
X417575D03*
X415185Y1014540D03*
X417575D03*
X405227Y1007156D03*
X405231Y1004848D03*
X417575Y1000060D03*
X415185D03*
X404986Y1022427D03*
X404998Y1026821D03*
X408325Y1031971D03*
Y1034271D03*
X408511Y1041340D03*
X417762Y1044544D03*
X412211Y1047749D03*
X404811D03*
X415911D03*
X419611D03*
X406662Y1044544D03*
X410362D03*
X408511Y1047749D03*
X414062Y1044544D03*
X412211Y1041340D03*
X415911D03*
X419611D03*
X406662Y1050952D03*
X415911Y1060565D03*
Y1054157D03*
X412211Y1060565D03*
X410361Y1050952D03*
X408511Y1054157D03*
X404811Y1060565D03*
X417761Y1050952D03*
X414060D03*
X417762Y1057361D03*
X421462Y1050952D03*
X419611Y1054157D03*
X406662Y1063770D03*
X408511Y1060565D03*
X410362Y1063770D03*
X412211Y1054157D03*
X404811D03*
X414062Y1057361D03*
X410362D03*
X417762Y1063770D03*
X414062D03*
X419611Y1060565D03*
Y1079791D03*
X408511Y1073383D03*
X406662Y1070178D03*
X404811Y1073383D03*
X415911Y1066974D03*
X410362Y1076587D03*
Y1070178D03*
X406661Y1076587D03*
X404811Y1066974D03*
X419611Y1073383D03*
X412211Y1079791D03*
X404811D03*
X417762Y1076587D03*
X408511Y1066974D03*
X412211Y1073383D03*
X415911D03*
X414062Y1070178D03*
X417762D03*
X412211Y1066974D03*
X419611D03*
X415911Y1092608D03*
X415912Y1086200D03*
X412211Y1092608D03*
X408511Y1086200D03*
X417761Y1089404D03*
Y1082995D03*
X410362Y1095813D03*
X406662D03*
X419612Y1099017D03*
X414061Y1095813D03*
X415912Y1099017D03*
X414062Y1108630D03*
X412211Y1099017D03*
X410362Y1102221D03*
X406661Y1108630D03*
Y1102221D03*
X404812Y1105426D03*
X417762Y1102221D03*
X404812Y1111834D03*
X404811Y1099017D03*
X408511Y1105426D03*
X412211Y1111834D03*
X415911D03*
X414062Y1102221D03*
X417762Y1108630D03*
X419611Y1105426D03*
X408511Y1099017D03*
X410362Y1108630D03*
X408511Y1111834D03*
X412211Y1105426D03*
X419611Y1111834D03*
X415911Y1105426D03*
Y1118243D03*
X414061Y1121447D03*
X412211Y1124651D03*
Y1118243D03*
X410361Y1115039D03*
X408511Y1118243D03*
X406661Y1115039D03*
X404811Y1118243D03*
X417761Y1115039D03*
X410361Y1127856D03*
X414062Y1115039D03*
X406661Y1121447D03*
X414062Y1127856D03*
Y1134264D03*
X412212Y1131060D03*
X410361Y1140973D03*
X408511Y1131060D03*
X404811D03*
X412212Y1137469D03*
X432128Y844671D03*
X426579Y841467D03*
X432129Y851380D03*
X428429D03*
X424729D03*
X421029D03*
X435829D03*
X432129Y864197D03*
X428429D03*
X426579Y854584D03*
X424729Y864197D03*
X421029D03*
X433979Y854584D03*
X435829Y864197D03*
X426579Y867401D03*
X433979D03*
X430278D03*
X422878D03*
X432129Y877014D03*
X428429D03*
X426579Y880219D03*
X424729Y877014D03*
X421029D03*
X433979Y880219D03*
X435829Y877014D03*
X432129Y870606D03*
X426578Y873810D03*
X424729Y870606D03*
X433979Y873810D03*
X428429Y870606D03*
X421029D03*
X435829D03*
X430278Y873810D03*
X432129Y889832D03*
X428429D03*
X426579Y893036D03*
X424729Y889832D03*
X421029D03*
X433979Y893036D03*
X435829Y889832D03*
X422878Y886627D03*
X430278D03*
Y899445D03*
X422878D03*
X424729Y896240D03*
X430278Y893036D03*
X432129Y896240D03*
X437678Y893036D03*
X421029Y896240D03*
X426578Y899445D03*
X428429Y896240D03*
X433978Y899445D03*
X435829Y896240D03*
X424729Y915466D03*
X426578Y912262D03*
X424729Y902649D03*
X432129D03*
X428429Y909057D03*
Y902649D03*
X421029D03*
X435829D03*
X428429Y915466D03*
X430278Y912262D03*
X432129Y915466D03*
X421029Y909057D03*
X435829D03*
Y915466D03*
X432128Y909057D03*
X433978Y905853D03*
X424728Y909057D03*
X422878Y905853D03*
X430278D03*
X426578D03*
X421029Y915466D03*
X433979Y912262D03*
X430278Y918670D03*
X433980Y925079D03*
Y931487D03*
X428429Y921875D03*
X432129D03*
X433979Y918670D03*
X435829Y921875D03*
X424927Y927255D03*
X423176Y929465D03*
X422427Y927255D03*
X425676Y929465D03*
X424729Y921875D03*
X422878Y918670D03*
X421029Y921875D03*
X426578Y918670D03*
X430279Y925079D03*
X432130Y928283D03*
X430279Y931487D03*
X432130Y934692D03*
X435830Y928283D03*
X430279Y937897D03*
X433979D03*
X426875Y947199D03*
Y949499D03*
X427875Y936470D03*
X433980Y944305D03*
X435830Y934692D03*
X426905Y965935D03*
Y963635D03*
X433980Y957123D03*
Y950714D03*
Y963531D03*
X426905Y980336D03*
Y978036D03*
X433980Y976348D03*
Y969940D03*
Y982757D03*
X426905Y994722D03*
Y992422D03*
Y1006875D03*
Y1009175D03*
X434411Y1009298D03*
X434412Y1002889D03*
X426905Y1021963D03*
Y1019663D03*
X434411Y1028524D03*
Y1022115D03*
X434412Y1015706D03*
X428862Y1044544D03*
X434412Y1034932D03*
X430712Y1047749D03*
X423311D03*
X427011D03*
X427012Y1041340D03*
X423312D03*
X425162Y1044544D03*
X421462D03*
X427011Y1054157D03*
X430711D03*
X425162Y1057361D03*
X432561Y1050952D03*
X434411Y1060565D03*
Y1054157D03*
X421462Y1063770D03*
X428861Y1057361D03*
X432561D03*
X421462D03*
X425162Y1050952D03*
X423311Y1054157D03*
X428862Y1050952D03*
X425162Y1063770D03*
X423311Y1060565D03*
X427011D03*
X428861Y1063770D03*
X430711Y1060565D03*
X423311Y1073383D03*
X432560Y1070178D03*
X421462Y1076587D03*
X430711Y1073383D03*
X427011D03*
Y1066974D03*
X425162Y1076587D03*
X423311Y1066974D03*
X432561Y1076587D03*
X434411Y1073383D03*
Y1066974D03*
X427012Y1079791D03*
X434411D03*
X421462Y1070178D03*
X425162D03*
X428862D03*
X430711Y1066974D03*
X428861Y1076587D03*
X430711Y1079791D03*
X428861Y1082995D03*
X425162Y1089404D03*
X421462Y1082995D03*
X432561Y1089404D03*
Y1082995D03*
X434411Y1092608D03*
Y1086200D03*
X428861Y1095813D03*
X421462D03*
X432561D03*
X427011Y1099017D03*
X425161Y1102221D03*
X423311Y1105426D03*
X421462Y1108630D03*
X434411Y1105426D03*
X423311Y1111834D03*
X434411D03*
X423311Y1124651D03*
Y1118243D03*
X421462Y1115039D03*
X434411Y1124651D03*
Y1118243D03*
X423312Y1137469D03*
X423311Y1131060D03*
X434412Y1137769D03*
X434411Y1131060D03*
X452478Y848176D03*
X445078D03*
X441378D03*
X439529Y844671D03*
X446929Y851380D03*
X443228D03*
X439529D03*
X450629D03*
X448779Y854584D03*
X446929Y864197D03*
X443229D03*
X441379Y854584D03*
X439529Y864197D03*
X439528Y857789D03*
X437680Y860992D03*
X450629Y864197D03*
X448779Y867401D03*
X441379D03*
X452478D03*
X445078D03*
X437678D03*
X448779Y880219D03*
X446929Y877014D03*
X443229D03*
X441379Y880219D03*
X439529Y877014D03*
X450629D03*
X448779Y873810D03*
X446929Y870606D03*
X441378Y873810D03*
X439529Y870606D03*
X450629D03*
X443229D03*
X437679Y873810D03*
X452479D03*
X445078D03*
X448779Y893036D03*
X446929Y889832D03*
X443229D03*
X441379Y893036D03*
X439529Y896240D03*
Y889832D03*
X437678Y886627D03*
X450629Y889832D03*
X437679Y899445D03*
X452478Y886627D03*
X445078D03*
X452478Y899445D03*
X441378D03*
X445078Y893036D03*
X446929Y896240D03*
X452479Y893036D03*
X445078Y899445D03*
X443229Y896240D03*
X448778Y899445D03*
X450630Y896240D03*
X446929Y909057D03*
Y902649D03*
X443229D03*
X439528D03*
X437678Y912262D03*
X437679Y905853D03*
X450629Y902649D03*
X446929Y915466D03*
X443229Y909057D03*
X439529Y915466D03*
X445079Y905853D03*
X441379D03*
X450630Y909057D03*
X452479Y905853D03*
X448779D03*
X448780Y912262D03*
X441380D03*
X439529Y909057D03*
X445080Y912262D03*
X443229Y915466D03*
X450629D03*
X452478Y912262D03*
X448779Y918670D03*
X454329Y915466D03*
X439529Y921875D03*
X446930Y928283D03*
X441379Y925079D03*
Y931487D03*
X446929Y921875D03*
X437678Y918670D03*
X441378D03*
X450629Y921875D03*
X445078Y918670D03*
X443229Y921875D03*
X452478Y918670D03*
X446930Y934692D03*
X443230Y928283D03*
X448780Y931487D03*
X437679D03*
X450630Y928283D03*
X448780Y925079D03*
X445079Y931487D03*
X439530Y934692D03*
X445079Y925079D03*
X439530Y928283D03*
X437679Y925079D03*
X441379Y937897D03*
X445079D03*
X437679D03*
X448779D03*
X446929Y941101D03*
X446930Y947510D03*
X443230Y934692D03*
X446930Y960327D03*
Y953918D03*
Y966736D03*
Y979553D03*
Y973144D03*
X447362Y1006094D03*
Y999685D03*
Y1012502D03*
Y1025319D03*
Y1018911D03*
Y1031728D03*
X447360Y1038136D03*
X452911Y1041340D03*
X451061Y1044544D03*
X449211Y1047749D03*
X452911D03*
X447361Y1057361D03*
Y1050952D03*
X452911Y1060565D03*
X447361Y1063770D03*
X449211Y1054157D03*
X449213Y1060565D03*
X451061Y1063770D03*
X452911Y1054157D03*
X451062Y1050952D03*
X454762D03*
Y1057361D03*
X451062D03*
X451061Y1076587D03*
X452911Y1073383D03*
X447361Y1076587D03*
Y1070178D03*
X449211Y1073383D03*
X452911Y1079791D03*
X449211D03*
X452911Y1066974D03*
X449211D03*
X451062Y1070178D03*
X447361Y1082995D03*
X452911Y1092608D03*
X451062Y1089404D03*
X449212Y1086200D03*
X451062Y1095813D03*
X452911Y1086200D03*
X451060Y1082995D03*
X447361Y1108630D03*
Y1102221D03*
X452911Y1099017D03*
X447361Y1121447D03*
Y1115039D03*
Y1127856D03*
Y1134264D03*
X461729Y851380D03*
X458029D03*
X454328D03*
X456179Y841467D03*
X463579D03*
X469129Y851380D03*
X465429D03*
X456179Y854584D03*
X463579D03*
X461729Y864197D03*
X458029D03*
X454329D03*
X469129D03*
X465429D03*
X456179Y867401D03*
X463579D03*
X467278D03*
X459878D03*
X461729Y877014D03*
X458029D03*
X456179Y880219D03*
X454329Y877014D03*
X463579Y880219D03*
X469129Y877014D03*
X465429D03*
X469129Y870606D03*
X463578Y873810D03*
X461729Y870606D03*
X456178Y873810D03*
X454329Y870606D03*
X465429D03*
X458029D03*
X461729Y889832D03*
X458029D03*
X456179Y893036D03*
X454329Y889832D03*
X463579Y893036D03*
X469129Y896240D03*
Y889832D03*
X465429D03*
X454329Y896240D03*
X459878Y893036D03*
X461729Y896240D03*
X467278Y893036D03*
X456178Y899445D03*
X458029Y896240D03*
X463578Y899445D03*
X465429Y896240D03*
X470978Y899445D03*
X463578Y905853D03*
X470980Y912262D03*
X461729Y902649D03*
X458029D03*
X456178Y912262D03*
Y905853D03*
X454329Y902649D03*
X465429D03*
Y909057D03*
Y915466D03*
X469129Y902649D03*
X454329Y909057D03*
X470978Y918670D03*
X467278Y912262D03*
X469129Y915466D03*
X458029Y909057D03*
X459878Y905853D03*
X461729Y915466D03*
X467278Y905853D03*
X461729Y909057D03*
X458029Y915466D03*
X459878Y918670D03*
X463578Y912262D03*
X459878D03*
X469129Y909057D03*
X454103Y931359D03*
Y933659D03*
X461729Y921875D03*
X456178Y918670D03*
X467278D03*
X454329Y921875D03*
X468236Y928349D03*
X465936D03*
X463636D03*
X461336D03*
X459036D03*
X469129Y921875D03*
X463578Y918670D03*
X465429Y921875D03*
X458029D03*
X462261Y942152D03*
X464561D03*
X466861D03*
X454423Y949139D03*
X469251Y942246D03*
X454393Y963829D03*
Y966129D03*
X463874Y956540D03*
X466272D03*
X454423Y951439D03*
X466272Y971100D03*
X463874Y971140D03*
X454263Y981209D03*
Y978909D03*
X454463Y995299D03*
Y992999D03*
X466272Y985580D03*
X463874D03*
X466272Y1014540D03*
X463874D03*
X454443Y1009409D03*
Y1007109D03*
X466272Y1000060D03*
X463874D03*
X468895Y1014550D03*
X454434Y1022186D03*
Y1019886D03*
X457942Y1031909D03*
X467711Y1047750D03*
X460311D03*
Y1041340D03*
X467372Y1036874D03*
X465861Y1044544D03*
X456611Y1047749D03*
X464011D03*
X471411Y1041340D03*
X467711D03*
X454762Y1044544D03*
Y1038136D03*
X460971Y1037069D03*
X463271D03*
X458671D03*
X457942Y1034409D03*
X456611Y1041340D03*
X464011D03*
X462162Y1044544D03*
X458462D03*
X464011Y1054157D03*
X465860Y1050952D03*
X456611Y1060565D03*
X462161Y1057361D03*
X456611Y1054157D03*
X462162Y1050952D03*
X465862Y1057361D03*
X458462Y1063770D03*
X465862D03*
X462161D03*
X460312Y1054157D03*
X458462Y1057361D03*
X454761Y1063770D03*
X464012Y1060565D03*
X458460Y1050952D03*
X460311Y1060565D03*
X454761Y1076587D03*
X456611Y1073383D03*
X454762Y1070178D03*
X462162D03*
X467711Y1073383D03*
Y1066974D03*
X456612Y1079791D03*
X467711D03*
X460311Y1073383D03*
X458460Y1070178D03*
X460311Y1066974D03*
X464011D03*
X465860Y1070178D03*
X469560D03*
X464012Y1079791D03*
X460312D03*
X462162Y1076587D03*
X456611Y1066974D03*
X465862Y1076587D03*
X464011Y1073383D03*
X458462Y1076587D03*
X458461Y1082995D03*
X456611Y1086200D03*
X460311Y1092608D03*
X464011Y1086200D03*
X467712D03*
Y1092608D03*
X462161Y1095812D03*
X458461D03*
X465861Y1089403D03*
X456612Y1092607D03*
X454761Y1089403D03*
X460311Y1086200D03*
X454760Y1082995D03*
X465861Y1095812D03*
X464012Y1092607D03*
X454761Y1095812D03*
X458461Y1089403D03*
X462161D03*
X460312Y1105426D03*
X458462Y1102221D03*
X456611Y1099017D03*
X464012Y1105426D03*
Y1099017D03*
X462162Y1108630D03*
X465861D03*
Y1102221D03*
X464012Y1111834D03*
X467711Y1105426D03*
Y1111834D03*
X460312Y1099016D03*
X458462Y1121447D03*
Y1115039D03*
X467712Y1124651D03*
X467711Y1118243D03*
X465862Y1121447D03*
Y1115039D03*
X458462Y1127856D03*
Y1134264D03*
X478379Y841467D03*
X470979D03*
X476529Y851380D03*
X480229D03*
X472829D03*
X483929D03*
X480229Y864197D03*
X478379Y854584D03*
X476529Y864197D03*
X470979Y854584D03*
X472829Y864197D03*
X483929D03*
X478379Y867401D03*
X470979D03*
X474678D03*
X482078D03*
X480229Y877014D03*
X478379Y880219D03*
X476529Y877014D03*
X472829D03*
X472828Y870606D03*
X470979Y880219D03*
Y873810D03*
X483929Y877014D03*
X480229Y870606D03*
X476529D03*
X478378Y873810D03*
X483929Y870606D03*
X474678Y880219D03*
X476529Y883423D03*
X482078Y880219D03*
X483929Y883423D03*
X472829D03*
X480229D03*
X480228Y896240D03*
X480229Y889832D03*
X478379Y893036D03*
X470979D03*
X476529Y889832D03*
X472829D03*
X483929D03*
X474678Y899445D03*
X482078D03*
X474678Y893036D03*
X472829Y896240D03*
X482078Y893036D03*
X483929Y896240D03*
X478378Y886627D03*
Y899445D03*
X476529Y896240D03*
Y915466D03*
X478380Y912262D03*
X478379Y918670D03*
X480229Y902649D03*
X474678Y912262D03*
Y905853D03*
X483929Y909057D03*
X482079Y912262D03*
X483928Y902649D03*
X483929Y915466D03*
X480229D03*
X472828D03*
X472829Y902649D03*
X480228Y909057D03*
X476529Y902649D03*
X470978Y905853D03*
X478378D03*
X472829Y909057D03*
X476529D03*
X480229Y928283D03*
X478378Y931488D03*
Y925079D03*
X482078D03*
X476285Y930126D03*
X480229Y921875D03*
X476528D03*
X474678Y918670D03*
X483929Y928283D03*
X482078Y918670D03*
X483928Y921875D03*
X482079Y931488D03*
X472829Y921875D03*
X470536Y928349D03*
X478378Y937896D03*
X480229Y941100D03*
X476285Y934726D03*
X476180Y945355D03*
Y947655D03*
X478378Y944304D03*
X480229Y934691D03*
X483928Y941100D03*
X482079Y944304D03*
X482078Y937896D03*
X483928Y947509D03*
X483929Y934691D03*
X471550Y942152D03*
X473851Y942246D03*
X476285Y962326D03*
Y960026D03*
Y964626D03*
X483928Y960326D03*
X482078Y957122D03*
X482079Y950713D03*
X483929Y966735D03*
X478378Y963530D03*
X483929Y953917D03*
X480228Y960326D03*
X480229Y966735D03*
X482078Y963529D03*
X476285Y966926D03*
X476192Y977670D03*
X476335Y980737D03*
X482079Y969939D03*
X483928Y979552D03*
X482078Y976347D03*
X483929Y973143D03*
X482078Y982756D03*
X478379Y969939D03*
X480229Y979552D03*
X478378Y982756D03*
X480229Y973143D03*
X478378Y976347D03*
X476285Y996826D03*
Y994526D03*
Y989926D03*
Y987626D03*
X476295Y1010500D03*
X476285Y1012926D03*
Y1006026D03*
Y1003726D03*
X471204Y1014540D03*
X484361Y999684D03*
X482512Y1009297D03*
X482511Y1002888D03*
X484362Y1012501D03*
X480662Y999684D03*
X478811Y1002888D03*
Y1009297D03*
X480662Y1012501D03*
X484362Y1006093D03*
X476275Y1022636D03*
X476285Y1017526D03*
X482511Y1028523D03*
Y1022114D03*
X484361Y1018910D03*
Y1031727D03*
X484362Y1025318D03*
X480662Y1031727D03*
X482511Y1015705D03*
X480662Y1025318D03*
X471282Y1036526D03*
X473507Y1035928D03*
X475111Y1041340D03*
X482511D03*
X482512Y1034931D03*
X484361Y1038136D03*
X471411Y1047749D03*
X482511D03*
X484362Y1044544D03*
X475111Y1047749D03*
X469562Y1044544D03*
X478811Y1034931D03*
X480662Y1038136D03*
X478811Y1041340D03*
X480662Y1044544D03*
X473262D03*
X480662Y1050952D03*
X475111Y1060565D03*
X471411Y1054157D03*
X484361Y1057361D03*
X482511Y1060565D03*
X484362Y1050952D03*
Y1063770D03*
X478811Y1066974D03*
X475111D03*
X473262Y1070178D03*
X478811Y1073383D03*
X484361Y1076587D03*
X484362Y1070178D03*
X482512Y1066974D03*
X478812Y1079791D03*
X475111D03*
X482511D03*
X471411Y1066974D03*
X476962Y1076587D03*
X480662D03*
Y1070178D03*
X476962D03*
X473262Y1076587D03*
X469562D03*
X471411Y1073383D03*
Y1079791D03*
X475111Y1073383D03*
X482511D03*
X480662Y1082995D03*
X476962Y1089404D03*
X473262Y1082995D03*
X469561Y1089404D03*
X482512Y1086200D03*
X484362Y1089404D03*
X480661Y1095813D03*
X469562D03*
X484362D03*
Y1082995D03*
X478812Y1092607D03*
X475112D03*
X473261Y1089403D03*
X471412Y1086199D03*
X476961Y1082994D03*
X482512Y1092607D03*
X476961Y1095812D03*
X471412Y1092607D03*
X475112Y1086199D03*
X478812D03*
X480662Y1108630D03*
X478811Y1099017D03*
X473262Y1108630D03*
X476962Y1102221D03*
X475112Y1099017D03*
X471411D03*
X469562Y1102221D03*
X482511Y1105426D03*
Y1111834D03*
X484362Y1108630D03*
X475111Y1111834D03*
X471411D03*
X478811Y1105426D03*
X469562Y1108630D03*
X473262Y1102221D03*
X482511Y1099017D03*
X478811Y1111834D03*
X476962Y1108630D03*
X471411Y1105426D03*
X475111D03*
X484362Y1102221D03*
X480661Y1115039D03*
X478811Y1118243D03*
X476961Y1115039D03*
X475111Y1118243D03*
X471411D03*
X469561Y1115039D03*
X482511Y1118243D03*
X476961Y1127856D03*
X469562D03*
X484361D03*
X484362Y1115039D03*
X473262D03*
X478811Y1131060D03*
X476961Y1140973D03*
X475111Y1131060D03*
X471412Y1137469D03*
Y1131060D03*
X469561Y1140973D03*
X473261Y1134264D03*
X482511Y1131060D03*
X484361Y1140973D03*
X493179Y841467D03*
X485779D03*
X500579D03*
X495029Y851380D03*
X491329D03*
X487629D03*
X498729D03*
X495029Y864197D03*
X493179Y854584D03*
X491329Y864197D03*
X487629D03*
X485779Y854584D03*
X498729Y864197D03*
X500579Y854584D03*
X493179Y867401D03*
X485779D03*
X500579D03*
X489478D03*
X496878D03*
X495029Y877014D03*
X493179Y880219D03*
X491329Y877014D03*
X487629D03*
X485779Y880219D03*
X500579D03*
X498729Y877014D03*
X487629Y870606D03*
X495029D03*
X485778Y873810D03*
X491329Y870606D03*
X493178Y873810D03*
X498729Y870606D03*
X500578Y873810D03*
X489478Y880219D03*
X491329Y883423D03*
X496878Y880219D03*
X498729Y883423D03*
X487629D03*
X495029D03*
X489479Y893036D03*
X495029Y889832D03*
X491329D03*
X487629D03*
X498729D03*
X500579Y893036D03*
X498729Y896240D03*
X496879Y899445D03*
X489478D03*
X485778D03*
X493178D03*
Y893036D03*
X496878D03*
X485778D03*
X491329Y896240D03*
X487629D03*
X495029D03*
X485778Y886627D03*
X493178D03*
X500578D03*
X496878Y912262D03*
X495029Y909057D03*
X489478Y912262D03*
Y905853D03*
X495029Y902649D03*
X493179Y905853D03*
X485778D03*
X498728Y915466D03*
X485778Y912262D03*
X487629Y909057D03*
X493178Y912262D03*
X491329Y909057D03*
X487629Y902649D03*
X491329D03*
X487629Y915466D03*
X495029D03*
X491329D03*
X495028Y928283D03*
X493179Y925079D03*
X489478D03*
Y918670D03*
X485778Y925079D03*
X496879Y918670D03*
X495029Y921875D03*
X496878Y931488D03*
X489478D03*
X491329Y921875D03*
X493178Y918670D03*
X485778Y931488D03*
X491329Y928283D03*
X493178Y931488D03*
X487629Y928283D03*
Y921875D03*
X485778Y918670D03*
X496879Y937896D03*
X495029Y941100D03*
X493179Y944304D03*
X489478D03*
Y937896D03*
X485778Y944304D03*
X498729Y934691D03*
X495028Y947509D03*
X487629D03*
X491329D03*
X487629Y941100D03*
X485778Y937896D03*
X491329Y941100D03*
X493178Y937896D03*
X487629Y934691D03*
X495029D03*
X491329D03*
X496879Y957122D03*
X495029Y960326D03*
X489478Y957122D03*
Y950713D03*
X496878D03*
X498729Y953917D03*
X495028Y966735D03*
X493179Y963530D03*
X485778D03*
X489478D03*
X500579D03*
X487629Y966735D03*
X491329D03*
X498729D03*
X496878Y963530D03*
X485778Y950713D03*
X493178D03*
X491329Y960326D03*
X493178Y957122D03*
X487629Y960326D03*
X485778Y957122D03*
X495029Y953917D03*
X487629D03*
X491329D03*
X496879Y976347D03*
X496878Y969939D03*
X489478Y976347D03*
Y969939D03*
X495029Y979552D03*
X498728Y973143D03*
X493179Y982756D03*
X489478D03*
X485778D03*
X495029Y973143D03*
X487629D03*
X491329D03*
X485778Y969939D03*
X493178D03*
X500578D03*
X497311Y1009297D03*
X497312Y1002888D03*
X495462Y999684D03*
X489911Y1009297D03*
X489912Y1002888D03*
X491761Y1006093D03*
X488062D03*
X499161D03*
X495461Y1012501D03*
X495462Y1006093D03*
X486211Y1002888D03*
X493611D03*
X488062Y999684D03*
X491762D03*
X491761Y1012501D03*
X493611Y1009297D03*
X488062Y1012501D03*
X486211Y1009297D03*
X497311Y1028523D03*
X489911D03*
Y1022114D03*
Y1015705D03*
X497311Y1022114D03*
X495462Y1018910D03*
X493612Y1015705D03*
X486211D03*
X501012D03*
X499161Y1025318D03*
X495461Y1031727D03*
X488062D03*
X486211Y1028523D03*
X491762Y1031727D03*
X493611Y1028523D03*
X486211Y1022114D03*
X488062Y1018910D03*
X493611Y1022114D03*
X491762Y1018910D03*
X488062Y1025318D03*
X495462D03*
X491762D03*
X497312Y1041340D03*
X489911D03*
Y1034931D03*
X495462Y1038136D03*
X493612Y1034931D03*
X486211D03*
X499161Y1044544D03*
X489911Y1047749D03*
X497311D03*
X486211D03*
X493611D03*
X486211Y1041340D03*
X488062Y1038136D03*
X493611Y1041340D03*
X491762Y1038136D03*
X488062Y1044544D03*
X495462D03*
X491762D03*
X497311Y1060565D03*
X495462Y1057361D03*
X489911Y1060565D03*
Y1054157D03*
X495461Y1050952D03*
X493611Y1054157D03*
X486211D03*
X499162Y1063770D03*
X486211Y1060565D03*
X488062Y1057361D03*
X493611Y1060565D03*
X491762Y1057361D03*
X488062Y1050952D03*
X491762D03*
X488062Y1063770D03*
X495462D03*
X491762D03*
X495462Y1076587D03*
X493612Y1073383D03*
X489911Y1066974D03*
X486211Y1073383D03*
X497311Y1066974D03*
X495461Y1070178D03*
X489911Y1073383D03*
X497312Y1079791D03*
X489911D03*
X486211D03*
X488062Y1076587D03*
X493611Y1079791D03*
X491762Y1076587D03*
X488062Y1070178D03*
X486211Y1066974D03*
X491762Y1070178D03*
X493611Y1066974D03*
X497311Y1086200D03*
X493612Y1092608D03*
X489911D03*
Y1086200D03*
X486211Y1092608D03*
X495461Y1089404D03*
X499161Y1082995D03*
X495462Y1095813D03*
X499162D03*
X491762D03*
Y1089404D03*
X493611Y1086200D03*
X488062Y1089404D03*
X486211Y1086200D03*
X495462Y1082995D03*
X488062D03*
X491762D03*
X497312Y1105426D03*
X493611D03*
X491762Y1102221D03*
X488061D03*
X486211Y1105426D03*
X486212Y1099017D03*
X499161Y1108630D03*
Y1102221D03*
X497312Y1111834D03*
X489911D03*
Y1099017D03*
X495462Y1102221D03*
X501011Y1099017D03*
X493611D03*
X497311D03*
X495462Y1108630D03*
X489911Y1105426D03*
X486211Y1111834D03*
X493611D03*
X491762Y1108630D03*
X488062D03*
X501012Y1105426D03*
Y1111833D03*
X497311Y1118243D03*
X495462Y1121447D03*
X493612Y1118243D03*
X489911D03*
X486211D03*
X501011D03*
X499161Y1115039D03*
X491761Y1127856D03*
X499161D03*
X491762Y1115039D03*
X495462D03*
X497311Y1131060D03*
X493611D03*
X489911D03*
X486211D03*
X491761Y1140973D03*
X501011Y1131060D03*
X499161Y1140973D03*
X507979Y841467D03*
X515379D03*
X506129Y851380D03*
X502429D03*
X513529D03*
X509829D03*
X517229D03*
X513529Y864197D03*
X509829D03*
X506129D03*
X502429D03*
X507979Y854584D03*
X515379D03*
X517229Y864197D03*
X507979Y867401D03*
X515379D03*
X511678D03*
X504278D03*
X509829Y877014D03*
X507979Y880219D03*
X502429Y877014D03*
X513529D03*
X506129D03*
X515379Y880219D03*
X517229Y877014D03*
Y870606D03*
X502429D03*
X509829D03*
X513529D03*
X515378Y873810D03*
X506129Y870606D03*
X507978Y873810D03*
X511678Y880219D03*
X513529Y883423D03*
X504278Y880219D03*
X506129Y883423D03*
X509829D03*
X517229D03*
X502429D03*
X506129Y889832D03*
X502428Y896240D03*
X502429Y889832D03*
X513529D03*
X509829D03*
X506128Y896240D03*
X504279Y893036D03*
X515379D03*
X517229Y889832D03*
X507978Y899445D03*
X515378D03*
Y886627D03*
X507978D03*
X511678Y905853D03*
X509829Y909057D03*
X507979Y912262D03*
X502429Y909057D03*
Y902649D03*
X509828D03*
X515378Y912262D03*
Y905853D03*
X502429Y915466D03*
X506129D03*
X511678Y925079D03*
X509829Y928283D03*
X502429D03*
Y921875D03*
X509828D03*
X507978Y918670D03*
X515378Y925079D03*
Y918670D03*
X507979Y931488D03*
X515378D03*
X511678Y944304D03*
X509828Y941100D03*
X507978Y937896D03*
X506129Y934691D03*
X502429Y941100D03*
Y934691D03*
X515378Y944304D03*
Y937896D03*
X509829Y947509D03*
X502429D03*
X509828Y960326D03*
X507978Y957122D03*
X506129Y953917D03*
X502429Y960326D03*
Y953917D03*
X507979Y950713D03*
X515378Y957122D03*
Y950713D03*
X509829Y966735D03*
X502428D03*
X511678Y963530D03*
X504278D03*
X515378D03*
X506129Y966735D03*
X507978Y963530D03*
Y976347D03*
X507979Y969939D03*
X502429Y979552D03*
Y973143D03*
X513529D03*
X509828Y979552D03*
X506129Y973143D03*
X515379Y976347D03*
X515378Y969939D03*
X517228Y973143D03*
X511678Y982756D03*
X515378D03*
X504278Y969939D03*
X510261Y999684D03*
X508411Y1002888D03*
X506562Y1006093D03*
X502862Y999684D03*
X502861Y1012501D03*
X508412Y1009297D03*
X510262Y1012501D03*
X515811Y1009297D03*
Y1002888D03*
X502862Y1006093D03*
X508411Y1028523D03*
X502862Y1025318D03*
Y1018910D03*
X510261D03*
X508411Y1022114D03*
X506562Y1025318D03*
X504711Y1015705D03*
X515811Y1028523D03*
Y1022114D03*
X510262Y1031727D03*
X502862D03*
X515811Y1015705D03*
X512111D03*
X502862Y1044544D03*
Y1038136D03*
X512111Y1034931D03*
X510261Y1038136D03*
X508411Y1041340D03*
X506562Y1044544D03*
X515811Y1034931D03*
Y1041340D03*
X508411Y1047749D03*
X515811D03*
X510262Y1057361D03*
X508411Y1060565D03*
X502862Y1057361D03*
Y1050952D03*
X512111Y1054157D03*
X510262Y1050952D03*
X515811Y1054157D03*
Y1060565D03*
X502862Y1063770D03*
X506562D03*
X510262Y1076587D03*
Y1070178D03*
X502862Y1076587D03*
Y1070178D03*
X512111Y1073383D03*
X508411Y1066974D03*
X515811Y1073383D03*
Y1066974D03*
X508411Y1079791D03*
X515811D03*
X512112Y1092608D03*
X510262Y1089404D03*
X508412Y1086200D03*
X506562Y1082995D03*
X502862Y1089404D03*
Y1082995D03*
X515812Y1092608D03*
X515811Y1086200D03*
X513961Y1095813D03*
X502862D03*
X517662D03*
X513962Y1108630D03*
Y1102221D03*
X512112Y1099017D03*
X508411D03*
X506562Y1108630D03*
X504711Y1099017D03*
X502862Y1102221D03*
X515811Y1105426D03*
Y1111834D03*
X517662Y1108630D03*
X502861Y1108629D03*
X512112Y1105426D03*
X508412Y1111833D03*
X506561Y1102220D03*
X504712Y1111833D03*
Y1105426D03*
X510261Y1108630D03*
X512112Y1111833D03*
X508412Y1105426D03*
X513961Y1115039D03*
X512111Y1118243D03*
X508411D03*
X504711D03*
X510261Y1115039D03*
X515811Y1118243D03*
X513961Y1127856D03*
X506561D03*
X517662Y1115039D03*
X506561Y1115038D03*
X513961Y1140973D03*
X512111Y1131060D03*
X508411D03*
X504711D03*
X506561Y1140973D03*
X515811Y1131060D03*
X528329Y844671D03*
X522779Y841467D03*
X528329Y851380D03*
X524629D03*
X520929D03*
X532029D03*
X528329Y864197D03*
X524629D03*
X520929D03*
X530179Y860993D03*
Y854584D03*
X522779D03*
X532028Y857789D03*
X533879Y860993D03*
X530178Y867401D03*
X522779D03*
X533879D03*
X519078D03*
X526479D03*
X528329Y877014D03*
X522779Y880219D03*
X520929Y877014D03*
X530179Y880219D03*
X524629Y877014D03*
X532029D03*
X533879Y880219D03*
Y873810D03*
X532028Y883423D03*
X524629Y870606D03*
X532029D03*
X520929D03*
X522778Y873810D03*
X528329Y870606D03*
X530178Y873810D03*
X519078Y880219D03*
X520929Y883423D03*
X526479Y880219D03*
X528329Y883423D03*
X524629D03*
X528329Y896240D03*
Y889832D03*
X524629D03*
X526479Y893036D03*
X524629Y896240D03*
X520929Y889832D03*
X532029D03*
Y896240D03*
X533879Y893036D03*
X522779Y899445D03*
X533879D03*
X530178Y893036D03*
X522778Y886627D03*
X530179D03*
X528329Y902649D03*
X522778Y912262D03*
X520928Y909057D03*
X519079Y905853D03*
X520929Y902649D03*
X528329Y915466D03*
X524628D03*
X532029D03*
X528329Y909057D03*
X533879Y912262D03*
X528329Y921875D03*
X520928Y928283D03*
X519079Y925079D03*
X522779Y918670D03*
X520929Y921875D03*
X522778Y931488D03*
X528329Y928283D03*
X533879Y918670D03*
X533878Y931488D03*
X528329Y941100D03*
Y934691D03*
X524628D03*
X522779Y937896D03*
X520929Y941100D03*
X519079Y944304D03*
X520928Y947509D03*
X532029Y934691D03*
X533879Y937896D03*
X528329Y947509D03*
Y960326D03*
Y953917D03*
X524629D03*
X522779Y957122D03*
X520929Y960326D03*
X522778Y950713D03*
X520928Y966735D03*
X526479Y963530D03*
X519079D03*
X533879Y957122D03*
X532029Y953917D03*
X533879Y950713D03*
X530178Y963530D03*
X528329Y966735D03*
Y979552D03*
Y973143D03*
X522779Y976347D03*
X522778Y969939D03*
X524628Y973143D03*
X520929Y979552D03*
X533879Y976347D03*
X519079Y982756D03*
X533901Y980606D03*
X533879Y969939D03*
X532029Y973143D03*
X521361Y1012501D03*
Y999684D03*
X528762Y1006093D03*
Y999684D03*
X525061Y1006093D03*
X523211Y1009297D03*
X523212Y1002888D03*
X534311Y1009297D03*
Y1002888D03*
X532461Y1006093D03*
X528761Y1012501D03*
X528762Y1025318D03*
X523211Y1028523D03*
X525061Y1025318D03*
X528762Y1031727D03*
X521361D03*
X519512Y1015705D03*
X521362Y1018910D03*
X523211Y1022114D03*
X526912Y1015705D03*
X528762Y1018910D03*
X530611Y1015705D03*
X534311Y1028523D03*
X534310Y1022114D03*
X532461Y1025318D03*
X528762Y1044544D03*
X525061D03*
X523212Y1041340D03*
X521362Y1038136D03*
X519512Y1034931D03*
X532462Y1044544D03*
X523211Y1047749D03*
X528762Y1038136D03*
X534311Y1041340D03*
Y1047749D03*
X528762Y1057361D03*
Y1050952D03*
X523212Y1060565D03*
X521362Y1057361D03*
X521361Y1050952D03*
X519512Y1054157D03*
X528762Y1063770D03*
X525061D03*
X534311Y1060565D03*
X532462Y1063770D03*
X528762Y1076587D03*
Y1070178D03*
X521362Y1076587D03*
X521361Y1070178D03*
X519512Y1073383D03*
X523211Y1066974D03*
X523212Y1079791D03*
X534311Y1066974D03*
Y1079791D03*
X523211Y1086200D03*
X521361Y1089404D03*
X519511Y1092608D03*
X528762Y1089404D03*
Y1082995D03*
X525061D03*
X532462Y1082996D03*
X534311Y1086200D03*
X528761Y1095813D03*
X526911Y1105426D03*
X521361Y1102221D03*
X519511Y1105426D03*
X519512Y1099017D03*
X532461Y1108630D03*
X530612Y1111834D03*
X523211D03*
X526911Y1099017D03*
X534311D03*
X532460Y1102221D03*
X521362Y1108630D03*
X525062D03*
X534311Y1111834D03*
X523211Y1105426D03*
X534311D03*
X528762Y1108630D03*
X519511Y1111834D03*
X526911D03*
X530611Y1124651D03*
Y1118243D03*
X528762Y1121447D03*
X523211Y1118243D03*
X521361Y1115039D03*
X519511Y1118243D03*
X532461Y1115039D03*
X528761Y1127856D03*
X521361D03*
X525062Y1115039D03*
X528762D03*
X532461Y1121446D03*
X534311Y1124650D03*
X532461Y1127855D03*
X530612Y1137469D03*
Y1131060D03*
X526912D03*
X523211D03*
X519511D03*
X528761Y1134264D03*
X521361Y1140973D03*
X534311Y1131060D03*
X537580Y848176D03*
X535729Y844671D03*
Y851380D03*
X544979Y860993D03*
Y854584D03*
X539428Y864197D03*
X537579Y854584D03*
Y860993D03*
X544979Y867401D03*
X541279D03*
X537579D03*
X546829Y870606D03*
X541279Y873810D03*
X535729Y870606D03*
Y883423D03*
X541279Y880219D03*
X546829Y883423D03*
X537579Y893036D03*
X541279Y886627D03*
X544979D03*
X537579D03*
X535729Y889832D03*
X550529D03*
X537579Y899445D03*
X548679Y912262D03*
X537579D03*
X539429Y909057D03*
X537579Y905853D03*
X535729Y909057D03*
X543129D03*
X535729Y902649D03*
X548679Y905853D03*
X543129Y928283D03*
X539429D03*
X537579Y918670D03*
X537578Y925079D03*
X535729Y928283D03*
Y921875D03*
X548678Y925079D03*
X537578Y931488D03*
X548678D03*
X537579Y937896D03*
X537578Y944304D03*
X535729Y941100D03*
X548678Y944304D03*
X539429Y947509D03*
X535729D03*
X549278Y949619D03*
X549719Y962436D03*
X537579Y957122D03*
Y950713D03*
X535729Y960326D03*
Y966735D03*
X537579Y963530D03*
X548146Y965640D03*
X539429Y979552D03*
X537579Y982756D03*
X541279Y969939D03*
X539429Y973143D03*
X535729D03*
X543729Y984866D03*
X539862Y1006092D03*
X539861Y999684D03*
X536161D03*
Y1006093D03*
X543563Y1006092D03*
X549254Y1000648D03*
X536161Y1012501D03*
Y1025318D03*
X539861Y1018910D03*
X541712Y1015705D03*
X545412D03*
X538012D03*
X536161Y1018910D03*
X549112Y1015705D03*
X536161Y1031727D03*
X545412Y1034931D03*
X539862Y1044544D03*
X539861Y1038136D03*
X541711Y1034931D03*
X538011D03*
X536161Y1038136D03*
X549112Y1034931D03*
X541711Y1054157D03*
X538011D03*
X536161Y1057361D03*
X545411Y1054157D03*
X538011Y1060565D03*
X536161Y1050952D03*
X549422Y1064850D03*
X538011Y1066974D03*
X541711Y1073383D03*
X545411Y1066974D03*
X539861Y1076587D03*
X536161D03*
X536162Y1070178D03*
X538011Y1073383D03*
X547262Y1070178D03*
X536162Y1082996D03*
X538011Y1092608D03*
X536161Y1089404D03*
X545411Y1092608D03*
X547262Y1082996D03*
X543561Y1095813D03*
X536161D03*
X547261D03*
X545412Y1105426D03*
X541711D03*
X539861Y1108630D03*
Y1102221D03*
X536161D03*
X541711Y1111834D03*
X545411D03*
X538011Y1105426D03*
X536161Y1108630D03*
X538011Y1111834D03*
X543561Y1108630D03*
X545411Y1124651D03*
Y1118243D03*
X543562Y1115039D03*
X539862D03*
X538011Y1124651D03*
X536161Y1115039D03*
X538010Y1118242D03*
X543561Y1121446D03*
X539861Y1127855D03*
X536161D03*
Y1121446D03*
X539861D03*
X541711Y1124650D03*
X543561Y1127855D03*
X541711Y1131060D03*
X536162Y1134264D03*
X538012Y1131059D03*
X551429Y979057D03*
X550701Y972608D03*
X550961Y1031727D03*
X650599Y766798D03*
X918264Y506011D03*
X1030780Y1266532D03*
X1074480Y1263742D03*
X1181941Y766798D03*
X1297012Y157449D03*
X1293802Y159299D03*
Y162999D03*
X1297007Y161149D03*
X1297012Y168549D03*
X1297007Y164849D03*
X1293802Y166699D03*
X1293511Y179048D03*
X1296999Y183349D03*
X1297007Y172249D03*
X1296999Y175949D03*
X1293802Y183349D03*
Y170399D03*
X1294163Y175865D03*
X1296999Y179649D03*
Y194449D03*
Y198149D03*
Y190749D03*
X1293802Y187049D03*
Y190749D03*
Y198149D03*
Y194449D03*
Y201849D03*
X1296999Y187049D03*
Y201849D03*
X1293805Y211099D03*
X1293798Y205833D03*
X1296999Y216649D03*
Y209249D03*
X1293807Y218499D03*
Y214799D03*
X1296999Y212949D03*
Y205549D03*
X1294357Y224688D03*
X1296999Y224049D03*
X1293807Y222199D03*
X1300393Y235762D03*
X1303417Y164849D03*
X1300213Y162999D03*
X1300212Y166699D03*
X1306622D03*
X1300774Y155288D03*
X1309832Y161149D03*
X1303417D03*
X1309832Y168549D03*
X1303417D03*
X1309832Y157449D03*
X1306626Y162999D03*
Y159299D03*
X1313037Y162999D03*
X1309832Y164849D03*
X1313037Y159299D03*
X1303417Y157449D03*
X1300217Y159299D03*
X1313033Y166699D03*
X1300212Y170399D03*
X1306626D03*
X1303407Y183349D03*
X1309817Y175949D03*
X1300212Y174099D03*
X1313037Y170399D03*
X1300207Y177799D03*
X1303422Y172249D03*
X1313033Y174099D03*
X1306622D03*
X1300207Y185199D03*
X1306617Y181499D03*
Y185199D03*
X1309832Y172249D03*
X1313027Y181499D03*
Y185199D03*
X1303407Y175949D03*
Y179649D03*
X1306617Y177799D03*
X1309817Y179649D03*
X1300204Y181499D03*
X1309817Y194449D03*
X1306617Y188899D03*
X1303407Y194449D03*
X1306617Y196299D03*
X1300207D03*
X1303407Y190749D03*
Y187049D03*
X1300207Y192599D03*
X1309817Y187049D03*
X1306617Y192599D03*
X1313023Y199999D03*
X1306617D03*
X1300207D03*
X1303407Y201849D03*
X1300204Y188899D03*
X1313027Y192599D03*
X1309817Y190749D03*
X1313025Y188899D03*
X1309817Y198149D03*
X1303407D03*
X1300207Y203699D03*
Y207399D03*
X1303422Y209249D03*
X1313032Y214799D03*
X1306622Y218499D03*
X1303417Y212949D03*
Y216649D03*
X1300207Y214799D03*
X1313027Y203699D03*
X1300220Y218499D03*
X1309833Y220349D03*
X1303416Y205549D03*
X1306614Y203699D03*
X1306627Y214799D03*
X1316242Y209249D03*
X1300207Y211099D03*
X1303422Y220349D03*
X1301151Y225450D03*
X1309828Y224049D03*
X1306622Y222199D03*
X1300220D03*
X1313033D03*
X1303425Y224049D03*
X1309100Y236477D03*
X1300493Y238062D03*
X1314184Y849978D03*
X1313920Y854584D03*
X1312266Y857972D03*
X1312070Y877014D03*
X1310221Y880219D03*
X1308370Y877014D03*
X1312070Y896240D03*
X1310220Y893036D03*
X1308371Y902649D03*
X1312070Y915466D03*
X1308370D03*
X1308371Y921875D03*
X1312070Y934692D03*
X1308371Y941100D03*
X1308370Y934692D03*
X1312070Y953917D03*
X1308370D03*
X1310221Y957122D03*
X1308371Y973143D03*
X1310221Y976347D03*
X1307426Y978814D03*
X1311491Y985939D03*
X1314352Y996480D03*
X1314353Y1002888D03*
X1308803Y1006093D03*
X1314353Y1015705D03*
Y1022114D03*
X1308803Y1025318D03*
Y1018910D03*
X1314353Y1041340D03*
X1308803Y1044544D03*
X1310653Y1041340D03*
X1314353Y1060565D03*
X1309976Y1062790D03*
X1305774Y1092168D03*
X1312502Y1082995D03*
X1314353Y1111834D03*
Y1105426D03*
X1311486Y1097289D03*
X1314353Y1124651D03*
X1312503Y1115039D03*
Y1127856D03*
X1319452Y162999D03*
X1316242Y168549D03*
X1319442Y159299D03*
X1316241Y157449D03*
X1320469Y155288D03*
X1322652Y161149D03*
X1316242D03*
X1319452Y166699D03*
X1329062Y168549D03*
X1316242Y164849D03*
X1322652D03*
X1329062D03*
X1326918Y161161D03*
X1329062Y157449D03*
X1322652D03*
X1319442Y170399D03*
X1318502Y176574D03*
Y186024D03*
Y182874D03*
X1329062Y172249D03*
X1316237D03*
X1331102Y176574D03*
X1327952Y186024D03*
Y182874D03*
X1315352Y186024D03*
Y179724D03*
X1319442Y174099D03*
X1332268D03*
X1318502Y189174D03*
X1315352Y195474D03*
X1327952Y189174D03*
X1331102Y195474D03*
X1327952Y198624D03*
X1321652D03*
X1315405Y189227D03*
X1325852Y214799D03*
X1319442Y218499D03*
X1329062Y209249D03*
X1319442Y207399D03*
X1329062Y216649D03*
X1319442Y211099D03*
X1324802Y204924D03*
X1327952D03*
X1318502D03*
X1315352D03*
X1322652Y209249D03*
X1325857Y218499D03*
X1322652Y216649D03*
X1319442Y222199D03*
X1329061Y224049D03*
X1329062Y220349D03*
X1325856Y222199D03*
X1322652Y224049D03*
Y220349D03*
X1326377Y235784D03*
X1321986Y236726D03*
X1326869Y844971D03*
X1323170D03*
X1321320Y848176D03*
X1330571Y851380D03*
X1323170D03*
X1319469D03*
X1321320Y854584D03*
X1317620D03*
X1315770Y857789D03*
X1328721Y854584D03*
X1330571Y864197D03*
X1326871D03*
X1323171D03*
Y857789D03*
X1325020Y854584D03*
X1321321Y860993D03*
X1319469Y857789D03*
X1317621Y867401D03*
X1328721D03*
X1325021D03*
X1330571Y877014D03*
X1328722Y880219D03*
X1323171Y870606D03*
X1326871Y877014D03*
X1321321Y873810D03*
X1315771Y877014D03*
X1317621Y873810D03*
X1321321Y880219D03*
X1319471Y877014D03*
X1315771Y883423D03*
X1326871D03*
X1323171D03*
X1326871Y870606D03*
X1330571D03*
X1328720Y873810D03*
X1330571Y883423D03*
X1323171Y877014D03*
X1325020Y880219D03*
X1328720Y899445D03*
X1315771Y896240D03*
Y889832D03*
X1328720Y893036D03*
Y886627D03*
X1325021D03*
X1323171Y889832D03*
X1321321Y893036D03*
X1319470Y896240D03*
X1321321Y899445D03*
X1328720Y905853D03*
X1325020D03*
X1317621Y912262D03*
X1317620Y905853D03*
X1328720Y912262D03*
X1323171Y909057D03*
Y902649D03*
X1321321Y912262D03*
X1315771Y915466D03*
X1319471D03*
X1328720Y925079D03*
Y918670D03*
X1325020Y925079D03*
X1317620D03*
X1323171Y928283D03*
Y921875D03*
X1321321Y918670D03*
X1317621Y931488D03*
X1328720D03*
X1321321D03*
X1323171Y941100D03*
X1325020Y944304D03*
X1323171Y947509D03*
X1317620Y944304D03*
X1328720D03*
Y937896D03*
X1315771Y934692D03*
X1321321Y937896D03*
X1319470Y934692D03*
X1321321Y957122D03*
X1323171Y966735D03*
X1325020Y963530D03*
X1323171Y960326D03*
X1321321Y950713D03*
X1315771Y953917D03*
Y966735D03*
X1319470Y953917D03*
X1319471Y966735D03*
X1319470Y960326D03*
X1317621Y950713D03*
X1328720Y957122D03*
Y963530D03*
Y950713D03*
X1321321Y969939D03*
X1325020Y982756D03*
X1323171Y979552D03*
X1321321Y976347D03*
X1315771Y973143D03*
X1319471D03*
X1328720Y969939D03*
X1330570Y973143D03*
X1326871D03*
X1328720Y982756D03*
X1328721Y976347D03*
X1315771Y979552D03*
X1318053Y1009297D03*
Y1002888D03*
X1327304Y1006093D03*
X1331003D03*
X1329153Y1009297D03*
Y1002888D03*
X1323603Y999684D03*
X1321753Y1009297D03*
X1319903Y1006093D03*
X1321753Y1002888D03*
X1323603Y1012501D03*
X1319903Y999684D03*
X1329153Y1028523D03*
Y1015705D03*
X1318053Y1022114D03*
Y1015705D03*
X1329153Y1022114D03*
X1325453Y1015705D03*
X1323603Y1018910D03*
X1321753Y1028523D03*
X1319903Y1018910D03*
X1321753Y1022114D03*
Y1015705D03*
X1319903Y1031727D03*
X1323603D03*
X1329153Y1034931D03*
Y1047749D03*
X1318053Y1041340D03*
X1319903Y1038136D03*
X1329153Y1041340D03*
X1325453Y1034931D03*
X1323603Y1038136D03*
X1321753Y1041340D03*
X1319903Y1044544D03*
X1321753Y1047749D03*
X1329153Y1060565D03*
Y1054157D03*
X1325453D03*
X1319903Y1057361D03*
Y1050952D03*
X1323603D03*
Y1057361D03*
X1321753Y1060565D03*
X1319903Y1063770D03*
X1329153Y1073383D03*
X1319903Y1076587D03*
Y1070178D03*
X1316204Y1076587D03*
X1329153Y1066974D03*
X1323603Y1076587D03*
Y1070178D03*
X1325454Y1073383D03*
X1321753Y1066974D03*
X1329153Y1079791D03*
X1321753D03*
X1318053D03*
X1329153Y1086200D03*
Y1092608D03*
X1325452Y1092609D03*
X1323603Y1089404D03*
X1321752Y1086200D03*
X1319902Y1082995D03*
X1319849Y1091513D03*
X1316202Y1082995D03*
X1316203Y1095813D03*
X1331003Y1108630D03*
X1329153Y1099017D03*
X1323603Y1108630D03*
X1316203D03*
Y1102221D03*
X1325453Y1099017D03*
X1323603Y1102221D03*
X1319903D03*
X1329153Y1105426D03*
X1325454Y1111834D03*
X1327303Y1102221D03*
X1321753Y1111834D03*
X1318054D03*
X1318053Y1105426D03*
X1327304Y1108630D03*
X1329154Y1111834D03*
X1331003Y1102221D03*
X1319904Y1108630D03*
X1321753Y1105426D03*
X1316203Y1115039D03*
X1331003D03*
X1327303Y1121447D03*
Y1115039D03*
X1325453Y1124651D03*
X1325454Y1118243D03*
X1321753D03*
X1319903Y1115039D03*
X1318053Y1124651D03*
X1323603Y1115039D03*
X1329152Y1137469D03*
X1329153Y1131060D03*
X1321752Y1137469D03*
X1321753Y1131060D03*
X1325453D03*
X1319903Y1134264D03*
X1339727Y161149D03*
X1341992Y156897D03*
X1344103Y155288D03*
X1342936Y159301D03*
X1335472Y161149D03*
X1346137Y168549D03*
X1342907Y166699D03*
X1332268D03*
X1346137Y164849D03*
X1339727D03*
X1335472Y168549D03*
X1332268Y162999D03*
X1342903Y170399D03*
X1339727Y168549D03*
X1335472Y164849D03*
X1346140Y161149D03*
X1342937Y162999D03*
X1335472Y157449D03*
X1346140D03*
X1339727D03*
X1339568Y176028D03*
X1339727Y179649D03*
X1342937Y181499D03*
Y185199D03*
X1346137Y172249D03*
X1335472D03*
X1334252Y176574D03*
X1339727Y183349D03*
X1346137Y175949D03*
X1342937Y177799D03*
X1346137Y183349D03*
X1339727Y190749D03*
X1342937Y188899D03*
X1334252Y195474D03*
X1346137Y194449D03*
Y190749D03*
X1337901Y196035D03*
X1339727Y187049D03*
X1337345Y201831D03*
X1339727Y201849D03*
X1337402Y198624D03*
X1342937Y192599D03*
X1346137Y187049D03*
X1346147Y201849D03*
Y198149D03*
X1336527Y214799D03*
X1339727Y216649D03*
X1346147Y212949D03*
Y216649D03*
X1336527Y218499D03*
X1342937D03*
Y214799D03*
X1346147Y209248D03*
X1337102Y206675D03*
X1332262Y218499D03*
Y214799D03*
X1339686Y205478D03*
X1332262Y207399D03*
X1339727Y209249D03*
Y220349D03*
X1336527Y222199D03*
X1346147Y220349D03*
X1332285Y226210D03*
X1342937Y222199D03*
X1332267D03*
X1343521Y841467D03*
X1336121D03*
X1345371Y851380D03*
X1341671D03*
X1337971D03*
X1334271D03*
X1345371Y864197D03*
X1343521Y854584D03*
X1341671Y864197D03*
X1337971D03*
X1336121Y854584D03*
X1334271Y864197D03*
X1343521Y867401D03*
X1336121D03*
X1347220D03*
X1332420D03*
X1339820D03*
X1345371Y877014D03*
X1343521Y880219D03*
X1341671Y877014D03*
X1337971D03*
X1336121Y880219D03*
X1334271Y877014D03*
Y870606D03*
X1337971D03*
X1341671D03*
X1336120Y873810D03*
X1343520D03*
X1345371Y870606D03*
X1332420Y880219D03*
X1334271Y883423D03*
X1339820Y880219D03*
X1341671Y883423D03*
X1347220Y880219D03*
X1337971Y883423D03*
X1345371D03*
X1332420Y886627D03*
X1345371Y896240D03*
Y889832D03*
X1341671Y896240D03*
Y889832D03*
X1337970Y896240D03*
X1337971Y889832D03*
X1336121Y893036D03*
X1334270Y889832D03*
X1336121Y899445D03*
X1347220D03*
X1339821Y893036D03*
X1343521D03*
X1336120Y886627D03*
X1343520D03*
X1332420Y905853D03*
X1341671Y909057D03*
Y902649D03*
X1336120Y912262D03*
X1334270Y909057D03*
X1334271Y902649D03*
X1347221Y912262D03*
X1345371Y915466D03*
X1341671D03*
X1337970D03*
X1332421Y925079D03*
X1341671Y928283D03*
Y921875D03*
X1336121Y918670D03*
X1334270Y928283D03*
X1334271Y921875D03*
X1347220Y918670D03*
X1336120Y931488D03*
X1347221D03*
X1341671Y947509D03*
Y941100D03*
X1334270Y947509D03*
X1334271Y941100D03*
X1332421Y944304D03*
X1345371Y934691D03*
X1341671D03*
X1337970D03*
X1336121Y937896D03*
X1347220D03*
X1337971Y953917D03*
X1345371D03*
X1341671D03*
Y960326D03*
X1347220Y957122D03*
X1343520Y963530D03*
X1339821D03*
X1341670Y966735D03*
X1347221Y950713D03*
X1334271Y960326D03*
X1336121Y957122D03*
X1332421Y963530D03*
X1334270Y966735D03*
X1336120Y950713D03*
X1347221Y969939D03*
X1337970Y973143D03*
X1347220Y976347D03*
X1345371Y973143D03*
X1341671Y979552D03*
Y973143D03*
X1336120Y969939D03*
X1336121Y976347D03*
X1334271Y979552D03*
X1332421Y982756D03*
X1345804Y1006093D03*
X1342104Y999684D03*
Y1006093D03*
X1338403D03*
X1336553Y1009297D03*
X1336554Y1002888D03*
X1334704Y999684D03*
X1347654Y1009297D03*
X1342103Y1012501D03*
X1334703D03*
X1343953Y1002888D03*
X1332854Y1015705D03*
X1345804Y1025318D03*
X1343953Y1015705D03*
X1342104Y1025318D03*
Y1018910D03*
X1340254Y1015705D03*
X1336553Y1028523D03*
X1338403Y1025318D03*
X1336554Y1022114D03*
X1334704Y1018910D03*
X1347653Y1028523D03*
Y1022114D03*
X1342104Y1031727D03*
X1334703D03*
X1332854Y1034931D03*
X1345804Y1044544D03*
X1342104D03*
Y1038136D03*
X1338403Y1044544D03*
X1336554Y1041340D03*
X1334704Y1038136D03*
X1347653Y1041340D03*
X1336553Y1047749D03*
X1347653D03*
X1332854Y1054157D03*
X1342104Y1057361D03*
Y1050952D03*
X1336554Y1060565D03*
X1334704Y1057361D03*
X1334703Y1050952D03*
X1347653Y1060565D03*
X1345804Y1063770D03*
X1342104D03*
X1338403D03*
X1332854Y1073383D03*
X1342104Y1070178D03*
Y1076587D03*
X1336553Y1066974D03*
X1334703Y1070178D03*
X1334704Y1076587D03*
X1347654Y1066974D03*
X1336554Y1079791D03*
X1347653D03*
X1345804Y1082995D03*
X1342104Y1089404D03*
Y1082995D03*
X1338403D03*
X1336553Y1086200D03*
X1334703Y1089404D03*
X1332854Y1092608D03*
X1347654Y1086200D03*
X1342104Y1095813D03*
X1334703D03*
X1342104Y1102221D03*
X1338404D03*
X1336553Y1099017D03*
X1332853Y1105426D03*
Y1099017D03*
X1347654Y1105426D03*
Y1099017D03*
X1340254Y1111834D03*
X1332854D03*
X1347654D03*
X1343953Y1118243D03*
X1340253D03*
X1338403Y1115039D03*
X1336553Y1118243D03*
X1332853D03*
X1347653D03*
X1342104Y1127856D03*
X1334703D03*
X1343953Y1131060D03*
X1342103Y1140973D03*
X1340254Y1131060D03*
X1336554D03*
X1334703Y1140973D03*
X1332854Y1131060D03*
X1347653D03*
X1352550Y157449D03*
X1349351Y159298D03*
X1355758D03*
X1355761Y162998D03*
X1358865Y166732D03*
Y158854D03*
Y162793D03*
X1349351Y166698D03*
X1352557Y164848D03*
X1355961Y155458D03*
X1352557Y168548D03*
X1355762Y166698D03*
X1349344Y162999D03*
X1348386Y156646D03*
X1352551Y161148D03*
X1358865Y170671D03*
Y174603D03*
Y182484D03*
Y178544D03*
X1355761Y170398D03*
Y177798D03*
X1352557Y179648D03*
Y172248D03*
X1349351Y177798D03*
Y170398D03*
Y174098D03*
X1358371Y188778D03*
X1358865Y195240D03*
Y199180D03*
X1349351Y196298D03*
X1352561Y194448D03*
X1352551Y190748D03*
X1349345Y188898D03*
X1355761Y192598D03*
X1349351D03*
X1352551Y187048D03*
X1355761Y188898D03*
X1349361Y199998D03*
X1352561Y201848D03*
X1355766Y214798D03*
X1349351Y218498D03*
X1352561Y216648D03*
X1355766Y218498D03*
X1358865Y207060D03*
Y203120D03*
Y213994D03*
Y217934D03*
X1352560Y205549D03*
X1355765Y207399D03*
X1349351Y214798D03*
X1352561Y212948D03*
X1349351Y211098D03*
X1352561Y220348D03*
X1355766Y222198D03*
X1349351D03*
X1360186Y226264D03*
X1358321Y841467D03*
X1350921D03*
X1360171Y851380D03*
X1356471D03*
X1352771D03*
X1349071D03*
X1363871D03*
X1360171Y864197D03*
X1358321Y854584D03*
X1356471Y864197D03*
X1352771D03*
X1350921Y854584D03*
X1349071Y864197D03*
X1363871D03*
X1358321Y867401D03*
X1350921D03*
X1354620D03*
X1362020D03*
Y860993D03*
X1354620D03*
X1360171Y877014D03*
X1358321Y880219D03*
X1356471Y877014D03*
X1352771D03*
X1350921Y880219D03*
X1349071Y877014D03*
X1363871D03*
Y870606D03*
X1349071D03*
X1356471D03*
X1350920Y873810D03*
X1352771Y870606D03*
X1358320Y873810D03*
X1360171Y870606D03*
X1349071Y883423D03*
X1354620Y880219D03*
X1356471Y883423D03*
X1362020Y880219D03*
X1363871Y883423D03*
X1352771D03*
X1360171D03*
X1362020Y873810D03*
X1360171Y889832D03*
X1356471D03*
X1354621Y893036D03*
X1352771Y889832D03*
X1349071D03*
X1363871Y896240D03*
Y889832D03*
X1362021Y899445D03*
X1354620D03*
X1350920Y886627D03*
X1358320D03*
X1362020D03*
Y912262D03*
X1360170Y909057D03*
X1360171Y902649D03*
X1358321Y905853D03*
X1354620Y912262D03*
Y905853D03*
X1350920D03*
X1349071Y909057D03*
X1349070Y902649D03*
X1363870Y915466D03*
X1363871Y909057D03*
Y902649D03*
X1362020Y905853D03*
X1362021Y918670D03*
X1360170Y928283D03*
X1360171Y921875D03*
X1358321Y925079D03*
X1354620D03*
Y918670D03*
X1350920Y925079D03*
X1349071Y928283D03*
X1349070Y921875D03*
X1362020Y931488D03*
X1354620D03*
X1363871Y921875D03*
Y928283D03*
X1362020Y925079D03*
X1360171Y941100D03*
X1358321Y944304D03*
X1354620D03*
X1360170Y947509D03*
X1350920Y944304D03*
X1349071Y947509D03*
X1349070Y941100D03*
X1362021Y937896D03*
X1354620D03*
X1363870Y934691D03*
X1363871Y947509D03*
Y941100D03*
X1362020Y944304D03*
X1363871Y953917D03*
X1360171Y960326D03*
X1362021Y957122D03*
X1354620D03*
X1358321Y963530D03*
X1354620D03*
X1360170Y966735D03*
X1354620Y950713D03*
X1362020D03*
X1349070Y960326D03*
X1350920Y963530D03*
X1349071Y966735D03*
X1363871Y960326D03*
Y966735D03*
X1362020Y963530D03*
Y969939D03*
X1354620D03*
X1363870Y973143D03*
X1362021Y976347D03*
X1360171Y979552D03*
X1358321Y982756D03*
X1356470Y973143D03*
X1354620Y982756D03*
X1354621Y976347D03*
X1350920Y982756D03*
X1349070Y979552D03*
X1352771Y973143D03*
X1362020Y982756D03*
X1363871Y979552D03*
X1352771D03*
X1356471D03*
X1350920Y976347D03*
X1358320D03*
X1349071Y973143D03*
X1360171D03*
X1351352Y996480D03*
X1349503Y999684D03*
X1362453Y1009297D03*
X1362454Y1002888D03*
X1360604Y999684D03*
X1355053Y1009297D03*
Y1002888D03*
X1360603Y1012501D03*
X1349504D03*
X1362453Y1028523D03*
X1362454Y1022114D03*
X1360604Y1018910D03*
X1358754Y1015705D03*
X1355053Y1028523D03*
Y1022114D03*
Y1015705D03*
X1351353D03*
X1349503Y1018910D03*
X1360603Y1031727D03*
X1349504D03*
X1362453Y1015705D03*
X1362454Y1041340D03*
X1360604Y1038136D03*
X1358754Y1034931D03*
X1355053Y1041340D03*
Y1034931D03*
X1351353D03*
X1349503Y1038136D03*
X1362453Y1047749D03*
X1355053D03*
X1362453Y1034931D03*
X1362454Y1060565D03*
X1360604Y1057361D03*
X1360603Y1050952D03*
X1358754Y1054157D03*
X1355053Y1060565D03*
Y1054157D03*
X1351353D03*
X1349503Y1057361D03*
X1349504Y1050952D03*
X1362453Y1054157D03*
Y1066974D03*
X1360604Y1076587D03*
X1360603Y1070178D03*
X1358754Y1073383D03*
X1355053D03*
Y1066974D03*
X1351353Y1073383D03*
X1349503Y1076587D03*
X1349504Y1070178D03*
X1362453Y1079791D03*
X1355053D03*
X1362453Y1073383D03*
Y1086200D03*
X1360603Y1089404D03*
X1358753Y1092608D03*
X1355053D03*
Y1086200D03*
X1351353Y1092608D03*
X1349504Y1089404D03*
X1360604Y1095813D03*
X1349504D03*
X1362453Y1092608D03*
X1351354Y1099017D03*
X1362454D03*
X1360604Y1102221D03*
X1356904Y1108630D03*
X1355053Y1099017D03*
X1353204Y1102221D03*
X1349503Y1108630D03*
Y1102221D03*
X1362453Y1111834D03*
Y1105426D03*
X1358753D03*
X1351353Y1111834D03*
Y1105426D03*
X1358753Y1111834D03*
X1360604Y1108630D03*
X1355053Y1111834D03*
X1356904Y1102221D03*
X1353204Y1108630D03*
X1355054Y1105426D03*
X1362453Y1118243D03*
X1360603Y1115039D03*
X1358753Y1118243D03*
X1355053D03*
X1353203Y1115039D03*
X1351353Y1118243D03*
X1349503Y1115039D03*
X1356903Y1127856D03*
X1349503D03*
X1356904Y1115039D03*
X1362453Y1131060D03*
X1358753D03*
X1356903Y1140973D03*
X1355053Y1131060D03*
X1351353D03*
X1349503Y1140973D03*
X1373121Y841467D03*
X1365721D03*
X1378671Y851380D03*
X1374971D03*
X1371271D03*
X1367571D03*
X1378671Y864197D03*
X1374971D03*
X1373121Y854584D03*
X1371271Y864197D03*
X1367571D03*
X1365721Y854584D03*
X1373121Y867401D03*
X1365721D03*
X1376820D03*
X1369420D03*
Y860993D03*
X1378671Y877014D03*
X1374971D03*
X1373121Y880219D03*
X1371271Y877014D03*
X1367571D03*
X1365721Y880219D03*
X1367571Y870606D03*
X1371271D03*
X1378671D03*
X1365720Y873810D03*
X1373120D03*
X1374971Y870606D03*
X1369420Y880219D03*
X1371271Y883423D03*
X1376820Y880219D03*
X1378671Y883423D03*
X1367571D03*
X1374971D03*
X1369420Y873810D03*
X1376820D03*
X1378671Y889832D03*
X1374971D03*
X1371271Y896240D03*
Y889832D03*
X1367570Y896240D03*
X1367571Y889832D03*
X1365721Y893036D03*
X1373120Y899445D03*
X1378671Y896240D03*
X1376820Y899445D03*
X1365720D03*
X1369420D03*
X1369421Y893036D03*
X1373121D03*
X1373120Y886627D03*
X1365720D03*
X1374971Y896240D03*
X1376820Y893036D03*
X1369420Y886627D03*
X1376820D03*
X1380520Y899445D03*
X1374971Y909057D03*
X1374970Y902649D03*
X1373121Y912262D03*
X1367571Y909057D03*
Y902649D03*
X1371271Y915466D03*
X1367571D03*
X1376820Y905853D03*
X1378671Y915466D03*
Y909057D03*
X1365720Y912262D03*
X1369420D03*
X1371271Y909057D03*
Y902649D03*
X1369420Y905853D03*
X1365720D03*
X1373120D03*
X1376820Y912262D03*
X1378671Y902649D03*
X1376820Y931488D03*
X1378671Y928283D03*
X1376820Y925079D03*
X1374971Y928283D03*
X1374970Y921875D03*
X1373120Y918670D03*
X1367571Y928283D03*
Y921875D03*
X1373120Y931488D03*
X1369420D03*
X1371271Y928283D03*
X1365720Y918670D03*
X1371271Y921875D03*
X1369420Y918670D03*
X1365720Y931488D03*
X1369420Y925079D03*
X1365720D03*
X1373120D03*
X1378671Y921875D03*
X1374971Y934691D03*
X1378671D03*
X1376820Y937896D03*
X1374970Y941100D03*
X1373120Y937896D03*
X1371271Y934691D03*
X1367571Y941100D03*
Y934691D03*
X1374971Y947509D03*
X1367571D03*
X1371271D03*
X1365720Y937896D03*
X1371271Y941100D03*
X1369420Y937896D03*
Y944304D03*
X1365720D03*
X1373120D03*
X1376820Y957122D03*
X1374970Y960326D03*
X1373120Y957122D03*
X1373121Y950713D03*
X1371271Y953917D03*
X1367571Y960326D03*
Y953917D03*
X1376820Y963530D03*
X1374971Y966735D03*
X1367571D03*
X1365720Y957122D03*
X1371271Y960326D03*
X1369420Y957122D03*
X1371271Y966735D03*
X1365720Y950713D03*
X1369420D03*
X1373120Y963530D03*
X1369420D03*
X1365720D03*
X1378671Y966735D03*
Y960326D03*
X1376820Y982756D03*
Y969939D03*
X1374970Y979552D03*
X1373120Y976347D03*
X1373121Y969939D03*
X1371271Y973143D03*
X1367571Y979552D03*
Y973143D03*
X1369420Y982756D03*
X1365720D03*
X1373120D03*
X1369420Y976347D03*
X1371271Y979552D03*
X1365721Y976347D03*
X1365720Y969939D03*
X1369420D03*
X1364303Y1006093D03*
X1377253Y1002888D03*
X1373554Y1009297D03*
X1373553Y1002888D03*
X1371704Y1006093D03*
X1368004D03*
Y999684D03*
X1375404Y1012501D03*
X1368003D03*
X1375404Y1006093D03*
X1379104D03*
X1375404Y999684D03*
X1379104D03*
X1364304Y1012501D03*
X1371704D03*
X1366153Y1009297D03*
X1369853D03*
X1377253D03*
X1379104Y1012501D03*
Y1031727D03*
X1364303Y1025318D03*
X1375403Y1018910D03*
X1373553Y1028523D03*
Y1022114D03*
X1371704Y1025318D03*
X1369853Y1015705D03*
X1368004Y1025318D03*
Y1018910D03*
X1366154Y1015705D03*
X1375404Y1031727D03*
X1368004D03*
X1373553Y1015705D03*
X1364304Y1031727D03*
X1366153Y1028523D03*
X1371704Y1031727D03*
X1369853Y1028523D03*
X1366153Y1022114D03*
X1364304Y1018910D03*
X1369853Y1022114D03*
X1371704Y1018910D03*
X1377253Y1028523D03*
Y1015705D03*
X1364303Y1044544D03*
X1375403Y1038136D03*
X1373553Y1041340D03*
X1371704Y1044544D03*
X1368004D03*
Y1038136D03*
X1373553Y1047749D03*
X1366153Y1041340D03*
X1364304Y1038136D03*
X1369853Y1041340D03*
X1371704Y1038136D03*
X1366153Y1047749D03*
X1369853D03*
Y1034931D03*
X1366153D03*
X1373553D03*
X1379104Y1038136D03*
X1377253Y1047749D03*
X1375403Y1057361D03*
X1375404Y1050952D03*
X1373553Y1060565D03*
X1368004Y1057361D03*
Y1050952D03*
X1364303Y1063770D03*
X1371704D03*
X1368004D03*
X1366153Y1060565D03*
X1364304Y1057361D03*
X1369853Y1060565D03*
X1371704Y1057361D03*
X1364304Y1050952D03*
X1371704D03*
X1369853Y1054157D03*
X1366153D03*
X1373553D03*
X1379104Y1057361D03*
Y1063770D03*
X1377255Y1060565D03*
X1375404Y1063770D03*
X1377253Y1054157D03*
X1379104Y1050952D03*
X1380953Y1054157D03*
X1379104Y1076587D03*
Y1070178D03*
X1377253Y1073383D03*
X1375403Y1076587D03*
X1375404Y1070178D03*
X1373554Y1066974D03*
X1368004Y1076587D03*
Y1070178D03*
X1377253Y1079791D03*
X1373553D03*
X1366153D03*
X1364304Y1076587D03*
X1369853Y1079791D03*
X1371704Y1076587D03*
X1364304Y1070178D03*
X1366153Y1066974D03*
X1371704Y1070178D03*
X1369853Y1066974D03*
Y1073383D03*
X1366153D03*
X1373553D03*
X1377254Y1066974D03*
X1364303Y1082995D03*
X1377254Y1092608D03*
X1377253Y1086200D03*
X1375404Y1089404D03*
X1373554Y1086200D03*
X1371704Y1082995D03*
X1368004Y1089404D03*
Y1082995D03*
X1379104Y1095813D03*
X1375403D03*
X1368004D03*
X1371704D03*
X1364304Y1089404D03*
X1366153Y1086200D03*
X1371704Y1089404D03*
X1369853Y1086200D03*
X1364304Y1095813D03*
X1369853Y1092608D03*
X1366153D03*
X1373553D03*
X1379104Y1082995D03*
X1379103Y1089404D03*
X1364304Y1108630D03*
Y1102221D03*
X1377253Y1105426D03*
X1375404Y1102221D03*
X1373554Y1099017D03*
X1371704Y1102221D03*
X1366153Y1105426D03*
X1373553Y1111834D03*
X1366153D03*
X1369853Y1099017D03*
X1366153D03*
X1364303Y1115039D03*
X1377253Y1118243D03*
X1373553D03*
X1371703Y1115039D03*
X1369853Y1118243D03*
X1366153D03*
X1364303Y1127856D03*
X1379103D03*
X1371703D03*
X1375404Y1121447D03*
X1364303Y1140973D03*
X1379103D03*
X1377253Y1131060D03*
X1373553D03*
X1371703Y1140973D03*
X1369853Y1131060D03*
X1366153D03*
X1380521Y841467D03*
X1395321D03*
X1387921D03*
X1393471Y851380D03*
X1389771D03*
X1386071D03*
X1382371D03*
X1380521Y854584D03*
X1395321D03*
X1393471Y864197D03*
X1389771D03*
X1387921Y854584D03*
X1386071Y864197D03*
X1382371D03*
X1380521Y867401D03*
X1395321D03*
X1387921D03*
X1384220D03*
X1391620D03*
X1380521Y880219D03*
X1395321D03*
X1393471Y877014D03*
X1389771D03*
X1387921Y880219D03*
X1386071Y877014D03*
Y870606D03*
X1382371Y877014D03*
X1380520Y873810D03*
X1382371Y870606D03*
X1384220Y880219D03*
X1386071Y883423D03*
X1382371D03*
X1395320Y873810D03*
X1393471Y870606D03*
X1387920Y873810D03*
X1389771Y870606D03*
X1384220Y873810D03*
X1395321Y893036D03*
X1393471Y889832D03*
X1389771D03*
X1387921Y893036D03*
X1386071Y889832D03*
X1384221Y893036D03*
X1382371Y889832D03*
X1380520Y886627D03*
X1387920D03*
X1380520Y893036D03*
X1382371Y896240D03*
X1384220Y886627D03*
X1391620D03*
Y899445D03*
X1384221Y899446D03*
X1386071Y902649D03*
X1380520Y912262D03*
Y905853D03*
X1395320Y912262D03*
X1395321Y905853D03*
X1393471Y902649D03*
X1389771D03*
X1386071Y909057D03*
Y915466D03*
X1393471Y909057D03*
X1382371D03*
X1389771D03*
Y915466D03*
X1399020Y905853D03*
X1382371Y915466D03*
X1384220Y918670D03*
X1387920Y905853D03*
X1384220D03*
Y912262D03*
X1382371Y902649D03*
X1391620Y905853D03*
X1387920Y912262D03*
X1391620D03*
X1393471Y915466D03*
X1391621Y918670D03*
X1380520D03*
X1395187Y926265D03*
X1395320Y918670D03*
X1386071Y921875D03*
X1381189Y930811D03*
X1382371Y921875D03*
X1382809Y927986D03*
X1385070Y928468D03*
X1393471Y921875D03*
X1391550Y925219D03*
X1387921Y918670D03*
X1381189Y938045D03*
X1381287Y946239D03*
Y948539D03*
X1381189Y935745D03*
X1390234Y942097D03*
X1386030Y942163D03*
X1383730D03*
X1381430D03*
X1381264Y965896D03*
Y963596D03*
X1390506Y971139D03*
X1392896D03*
X1381003Y981269D03*
Y978969D03*
Y986421D03*
X1381243Y992971D03*
Y995271D03*
X1381003Y988721D03*
X1393716Y985579D03*
X1391326D03*
X1381369Y1007156D03*
X1381373Y1004848D03*
X1391326Y1014539D03*
X1393716D03*
Y1000059D03*
X1391326D03*
X1381128Y1022427D03*
X1381140Y1026821D03*
X1384466Y1034270D03*
Y1031970D03*
X1393904Y1044544D03*
X1384653Y1041340D03*
X1380953Y1047749D03*
X1388353D03*
Y1041340D03*
X1392053D03*
X1395753D03*
Y1047749D03*
X1392053D03*
X1382804Y1044544D03*
X1386504D03*
X1384653Y1047749D03*
X1390204Y1044544D03*
X1382804Y1050952D03*
X1380953Y1060565D03*
X1393904Y1050952D03*
X1392053Y1060565D03*
Y1054157D03*
X1388353Y1060565D03*
X1386504Y1050952D03*
X1384653Y1054157D03*
X1382804Y1057361D03*
X1386504D03*
X1390204Y1050952D03*
X1393904Y1057361D03*
X1395753Y1054157D03*
X1382804Y1063770D03*
X1384653Y1060565D03*
X1386504Y1063770D03*
X1388353Y1054157D03*
X1390204Y1057361D03*
X1393904Y1063770D03*
X1390204D03*
X1395753Y1060565D03*
Y1079791D03*
X1384653Y1073383D03*
X1382804Y1070178D03*
X1380953Y1073383D03*
Y1066974D03*
X1395753Y1073383D03*
X1392053Y1066974D03*
X1386504Y1076587D03*
Y1070178D03*
X1382803Y1076587D03*
X1380953Y1079791D03*
X1388353D03*
X1393904Y1076587D03*
X1384653Y1066974D03*
X1388353Y1073383D03*
X1392053D03*
X1390204Y1070178D03*
X1393904D03*
X1388353Y1066974D03*
X1395753D03*
X1384653Y1079791D03*
X1393903Y1089404D03*
Y1082995D03*
X1392053Y1092608D03*
X1392054Y1086200D03*
X1388353Y1092608D03*
X1384653Y1086200D03*
X1386504Y1095813D03*
X1382804D03*
X1395754Y1099017D03*
X1390203Y1095813D03*
X1388353Y1086200D03*
X1386504Y1082995D03*
X1390204Y1089404D03*
X1382804D03*
X1390204Y1082995D03*
X1382804D03*
X1395753Y1086200D03*
Y1092608D03*
X1380953Y1086200D03*
X1386504Y1089404D03*
X1384653Y1092608D03*
X1380954Y1105426D03*
X1393904Y1102221D03*
X1392054Y1099017D03*
X1390204Y1108630D03*
X1388353Y1099017D03*
X1386504Y1102221D03*
X1382803Y1108630D03*
Y1102221D03*
X1380954Y1111834D03*
X1380953Y1118243D03*
X1393903Y1115039D03*
X1392053Y1118243D03*
X1390203Y1121447D03*
X1388353Y1124651D03*
Y1118243D03*
X1386503Y1115039D03*
X1384653Y1118243D03*
X1382803Y1115039D03*
X1386503Y1127856D03*
X1382803Y1121447D03*
X1390204Y1127856D03*
X1380953Y1131060D03*
X1390204Y1134264D03*
X1388354Y1131060D03*
X1386503Y1140973D03*
X1384653Y1131060D03*
X1388354Y1137469D03*
X1408269Y844971D03*
X1402721Y841467D03*
X1397171Y851380D03*
X1408271D03*
X1404571D03*
X1400871D03*
X1411971D03*
X1397171Y864197D03*
X1408271D03*
X1404571D03*
X1402721Y854584D03*
X1400871Y864197D03*
X1410121Y854584D03*
X1411971Y864197D03*
X1410121Y867401D03*
X1402721D03*
X1406420D03*
X1399020D03*
X1397171Y877014D03*
X1410121Y880219D03*
X1408271Y877014D03*
X1404571D03*
X1402721Y880219D03*
X1400871Y877014D03*
X1411971D03*
X1408271Y870606D03*
X1402720Y873810D03*
X1400871Y870606D03*
X1410121Y873810D03*
X1404571Y870606D03*
X1397171D03*
X1411971D03*
X1406420Y873810D03*
X1397171Y889832D03*
X1410121Y893036D03*
X1408271Y889832D03*
X1404571D03*
X1402721Y893036D03*
X1400871Y889832D03*
X1411971D03*
X1406420Y886627D03*
X1399020D03*
X1406420Y899445D03*
X1399020D03*
Y912262D03*
X1400871Y915466D03*
X1402720Y912262D03*
X1400871Y902649D03*
X1397171D03*
X1408271D03*
X1404571Y909057D03*
Y902649D03*
X1411971D03*
X1404571Y915466D03*
X1406420Y912262D03*
X1408271Y915466D03*
X1397171Y909057D03*
X1411971D03*
Y915466D03*
X1408270Y909057D03*
X1410120Y905853D03*
X1400870Y909057D03*
X1406420Y905853D03*
X1402720D03*
X1397171Y915466D03*
X1410121Y912262D03*
X1406420Y918670D03*
X1410121Y925079D03*
Y931488D03*
X1404571Y921875D03*
X1408271D03*
X1410121Y918670D03*
X1411971Y921875D03*
X1401528Y927155D03*
X1399028D03*
X1401817Y929464D03*
X1399317D03*
X1400871Y921875D03*
X1399020Y918670D03*
X1397171Y921875D03*
X1402720Y918670D03*
X1411971Y934691D03*
X1406420Y925079D03*
X1408271Y928283D03*
X1406420Y931488D03*
X1411971Y928283D03*
X1403016Y949498D03*
Y947198D03*
X1406420Y937896D03*
X1404016Y936469D03*
X1410120Y937896D03*
X1410121Y944304D03*
X1408271Y934691D03*
X1403046Y963634D03*
Y965934D03*
X1410121Y957122D03*
Y950713D03*
Y963530D03*
X1403046Y978035D03*
Y980335D03*
X1410121Y976347D03*
Y969939D03*
Y982756D03*
X1403046Y992421D03*
Y994721D03*
Y1009174D03*
Y1006874D03*
X1410553Y1009297D03*
Y1002888D03*
X1403046Y1021962D03*
Y1019662D03*
X1410553Y1028523D03*
Y1022114D03*
Y1015705D03*
X1405004Y1044544D03*
X1410553Y1034931D03*
X1406854Y1047749D03*
X1399453D03*
X1403153D03*
X1403154Y1041340D03*
X1399454D03*
X1401304Y1044544D03*
X1397604D03*
X1403153Y1054157D03*
X1406853D03*
X1408703Y1050952D03*
X1401304Y1057361D03*
X1410553Y1060565D03*
Y1054157D03*
X1397604Y1063770D03*
X1405003Y1057361D03*
X1408703D03*
Y1063770D03*
X1397604Y1057361D03*
X1401304Y1050952D03*
X1399453Y1054157D03*
X1405004Y1050952D03*
X1397604D03*
X1401304Y1063770D03*
X1399453Y1060565D03*
X1403153D03*
X1405003Y1063770D03*
X1406853Y1060565D03*
X1397604Y1076587D03*
X1408703D03*
X1406853Y1073383D03*
X1403153D03*
Y1066974D03*
X1401304Y1076587D03*
X1399453Y1066974D03*
X1410553Y1073383D03*
Y1066974D03*
X1403154Y1079791D03*
X1410553D03*
X1408702Y1070178D03*
X1399453Y1073383D03*
X1397604Y1070178D03*
X1401304D03*
X1405004D03*
X1406853Y1066974D03*
X1408703Y1089404D03*
Y1082995D03*
X1405003D03*
X1401304Y1089404D03*
X1397604Y1082995D03*
X1410553Y1092608D03*
Y1086200D03*
X1408703Y1095813D03*
X1405003D03*
X1397604D03*
X1401304Y1082995D03*
X1405003Y1089404D03*
X1399453Y1086200D03*
X1406853Y1092608D03*
X1399453D03*
X1397604Y1089404D03*
X1403154Y1086200D03*
X1406852D03*
X1403153Y1092608D03*
X1401304Y1095813D03*
X1403153Y1099017D03*
X1401303Y1102221D03*
X1399453Y1105426D03*
X1397604Y1108630D03*
X1410553Y1105426D03*
X1399453Y1111834D03*
X1410553D03*
X1399453Y1124651D03*
Y1118243D03*
X1397604Y1115039D03*
X1410553Y1124651D03*
Y1118243D03*
X1399454Y1137469D03*
X1399453Y1131060D03*
X1410554Y1137769D03*
X1410553Y1131060D03*
X1428620Y848176D03*
X1415669Y844971D03*
X1421220Y848176D03*
X1417520D03*
X1426771Y851380D03*
X1423070D03*
X1419370D03*
X1415671D03*
X1413822Y860993D03*
X1426771Y864197D03*
X1424921Y854584D03*
X1423071Y864197D03*
X1419371D03*
X1417521Y854584D03*
X1415671Y864197D03*
Y857789D03*
X1424921Y867401D03*
X1417521D03*
X1428620D03*
X1421220D03*
X1413820D03*
X1426771Y877014D03*
X1424921Y880219D03*
X1423071Y877014D03*
X1419371D03*
X1417521Y880219D03*
X1415671Y877014D03*
X1424921Y873810D03*
X1423071Y870606D03*
X1417520Y873810D03*
X1415671Y870606D03*
X1426771D03*
X1419371D03*
X1413821Y873810D03*
X1428621D03*
X1421220D03*
X1413820Y886627D03*
X1426771Y889832D03*
X1424921Y893036D03*
X1423071Y889832D03*
X1419371D03*
X1417521Y893036D03*
X1415671Y896240D03*
Y889832D03*
X1413821Y899445D03*
X1428620D03*
Y886627D03*
X1421220D03*
X1413820Y912262D03*
X1413821Y905853D03*
X1426771Y902649D03*
X1423071Y909057D03*
Y902649D03*
X1419371D03*
X1415670D03*
X1423071Y915466D03*
X1419371Y909057D03*
X1415671Y915466D03*
X1421221Y905853D03*
X1417521D03*
X1430471Y909057D03*
X1426772D03*
X1428621Y905853D03*
X1424921D03*
X1424922Y912262D03*
X1417522D03*
X1415671Y909057D03*
X1421222Y912262D03*
X1419371Y915466D03*
X1426771D03*
X1428620Y912262D03*
X1424921Y918670D03*
X1430471Y915466D03*
X1415671Y921875D03*
X1423071Y928283D03*
X1417520Y925079D03*
Y931488D03*
X1413820Y918670D03*
X1423071Y921875D03*
X1417520Y918670D03*
X1426771Y921875D03*
X1421220Y918670D03*
X1419371Y921875D03*
X1428620Y918670D03*
X1424921Y931488D03*
X1419371Y928283D03*
X1413820Y931488D03*
X1424921Y925079D03*
X1419371Y934691D03*
X1421220Y931488D03*
Y925079D03*
X1415671Y928283D03*
X1413820Y925079D03*
X1426771Y928283D03*
X1424920Y937896D03*
X1421220D03*
X1417520D03*
X1413820D03*
X1423070Y941100D03*
X1423071Y947509D03*
Y934691D03*
X1415671D03*
X1423071Y960326D03*
Y953917D03*
Y966735D03*
Y979552D03*
Y973143D03*
X1423503Y1006093D03*
Y999684D03*
Y1012501D03*
Y1025318D03*
Y1018910D03*
Y1031727D03*
X1429053Y1041340D03*
X1427203Y1044544D03*
X1423503Y1038136D03*
X1425353Y1047749D03*
X1429053D03*
Y1060565D03*
X1423503Y1057361D03*
Y1050952D03*
Y1063770D03*
X1425353Y1054157D03*
X1425355Y1060565D03*
X1427203Y1063770D03*
X1429053Y1054157D03*
X1427203Y1050952D03*
X1430903D03*
X1430904Y1057361D03*
X1427204D03*
X1425353Y1073383D03*
X1423503Y1076587D03*
Y1070178D03*
X1429053Y1079791D03*
X1425353D03*
X1429053Y1073383D03*
X1427203Y1076587D03*
X1429053Y1066974D03*
X1425353D03*
X1427204Y1070178D03*
X1429053Y1092608D03*
X1427204Y1089404D03*
X1425354Y1086200D03*
X1423503Y1082995D03*
X1427203Y1095812D03*
X1429053Y1086200D03*
X1427202Y1082995D03*
X1429053Y1099017D03*
X1423503Y1108630D03*
Y1102221D03*
Y1121447D03*
Y1115039D03*
Y1127856D03*
Y1134264D03*
X1437871Y851380D03*
X1434171D03*
X1430470D03*
X1432321Y841467D03*
X1439721D03*
X1445271Y851380D03*
X1441571D03*
X1439721Y854584D03*
X1432321D03*
X1437871Y864197D03*
X1434171D03*
X1430471D03*
X1445271D03*
X1441571D03*
X1432321Y867401D03*
X1439721D03*
X1443420D03*
X1436020D03*
X1437871Y877014D03*
X1434171D03*
X1432321Y880219D03*
X1430471Y877014D03*
X1445271D03*
X1441571D03*
X1439721Y880219D03*
X1445271Y870606D03*
X1439720Y873810D03*
X1437871Y870606D03*
X1432320Y873810D03*
X1430471Y870606D03*
X1441571D03*
X1434171D03*
X1437871Y889832D03*
X1434171D03*
X1432321Y893036D03*
X1430471Y889832D03*
X1445271Y896240D03*
X1439721Y893036D03*
X1445271Y889832D03*
X1441571D03*
X1447120Y899445D03*
X1437871Y902649D03*
X1434171D03*
X1432320Y912262D03*
Y905853D03*
X1430471Y902649D03*
X1441571D03*
Y909057D03*
Y915466D03*
X1445271Y902649D03*
X1434171Y909057D03*
X1437871Y915466D03*
X1443420Y912262D03*
X1445271Y915466D03*
X1437871Y909057D03*
X1434171Y915466D03*
X1436020Y918670D03*
X1439720Y912262D03*
X1436020D03*
Y905853D03*
X1439720D03*
X1443420D03*
X1445271Y909057D03*
X1430244Y931358D03*
Y933658D03*
X1437871Y921875D03*
X1432320Y918670D03*
X1430471Y921875D03*
X1443420Y918670D03*
X1439777Y928348D03*
X1437477D03*
X1435177D03*
X1444377D03*
X1442077D03*
X1445271Y921875D03*
X1439720Y918670D03*
X1441571Y921875D03*
X1434171D03*
X1438402Y942151D03*
X1440702D03*
X1443002D03*
X1430564Y949138D03*
X1445392Y942195D03*
X1440015Y956539D03*
X1430564Y951438D03*
X1442413Y956539D03*
X1430534Y963828D03*
Y966128D03*
X1440015Y971139D03*
X1442413Y971099D03*
X1430404Y981208D03*
Y978908D03*
X1440015Y985579D03*
X1430604Y995298D03*
Y992998D03*
X1442413Y985579D03*
X1440015Y1014539D03*
Y1000059D03*
X1430584Y1009408D03*
Y1007108D03*
X1442413Y1014539D03*
Y1000059D03*
X1430575Y1022185D03*
Y1019885D03*
X1434083Y1031908D03*
X1443541Y1036914D03*
X1436453Y1041340D03*
X1442003Y1044544D03*
X1432753Y1047749D03*
X1440153D03*
X1447553Y1041340D03*
X1443853D03*
X1436453Y1047750D03*
X1443853D03*
X1430904Y1044544D03*
Y1038136D03*
X1434083Y1034408D03*
X1434813Y1037069D03*
X1439413D03*
X1437113D03*
X1432753Y1041340D03*
X1440153D03*
X1438304Y1044544D03*
X1434604D03*
X1432753Y1060565D03*
X1438303Y1057361D03*
X1432753Y1054157D03*
X1442004Y1057361D03*
X1438304Y1050952D03*
X1434604Y1063770D03*
X1442004D03*
X1438303D03*
X1442002Y1050952D03*
X1440153Y1054157D03*
X1436454D03*
X1434604Y1057361D03*
X1430903Y1063770D03*
X1440154Y1060565D03*
X1434603Y1050952D03*
X1436453Y1060565D03*
X1432753Y1073383D03*
X1430903Y1076587D03*
X1430904Y1070178D03*
X1443853Y1073383D03*
Y1066974D03*
X1438304Y1070178D03*
X1432754Y1079791D03*
X1443853D03*
X1436453Y1073383D03*
X1434602Y1070178D03*
X1436453Y1066974D03*
X1440153D03*
X1442002Y1070178D03*
X1447553Y1066974D03*
X1440154Y1079791D03*
X1436454D03*
X1438304Y1076587D03*
X1432753Y1066974D03*
X1442004Y1076587D03*
X1440153Y1073383D03*
X1434604Y1076587D03*
X1434603Y1082995D03*
X1432753Y1086200D03*
X1436453Y1092608D03*
X1443854Y1086200D03*
X1440153D03*
X1443854Y1092608D03*
X1438303Y1095812D03*
X1434603D03*
X1442003Y1089403D03*
X1432754Y1092607D03*
X1430903Y1089403D03*
X1436454Y1086199D03*
X1430902Y1082995D03*
X1442003Y1095812D03*
X1440154Y1092607D03*
X1430903Y1095812D03*
X1434603Y1089403D03*
X1438303D03*
X1436454Y1105426D03*
X1434604Y1102221D03*
X1432753Y1099017D03*
X1442003Y1108630D03*
Y1102221D03*
X1440154Y1105426D03*
Y1099017D03*
X1438304Y1108630D03*
X1440154Y1111834D03*
X1443853Y1105426D03*
Y1111834D03*
X1436454Y1099016D03*
X1434604Y1121447D03*
Y1115039D03*
X1443854Y1124651D03*
X1443853Y1118243D03*
X1442004Y1121447D03*
Y1115039D03*
X1434604Y1127856D03*
Y1134264D03*
X1454521Y841467D03*
X1447121D03*
X1460071Y851380D03*
X1452671D03*
X1456371D03*
X1448971D03*
X1460071Y864197D03*
X1456371D03*
X1454521Y854584D03*
X1452671Y864197D03*
X1447121Y854584D03*
X1448971Y864197D03*
X1454521Y867401D03*
X1447121D03*
X1450820D03*
X1458220D03*
X1460071Y877014D03*
X1456371D03*
X1454521Y880219D03*
X1452671Y877014D03*
X1448971D03*
X1448970Y870606D03*
X1447121Y880219D03*
Y873810D03*
X1456371Y870606D03*
X1452671D03*
X1454520Y873810D03*
X1460071Y870606D03*
X1450820Y880219D03*
X1452671Y883423D03*
X1458220Y880219D03*
X1460071Y883423D03*
X1448971D03*
X1456371D03*
X1456370Y896240D03*
X1456371Y889832D03*
X1454521Y893036D03*
X1447121D03*
X1460071Y889832D03*
X1452671D03*
X1448971D03*
X1458220Y899445D03*
X1450820D03*
Y893036D03*
X1448971Y896240D03*
X1458220Y893036D03*
X1460071Y896240D03*
X1454520Y886627D03*
Y899445D03*
X1452671Y896240D03*
X1456371Y902649D03*
X1460071Y909057D03*
X1458221Y912262D03*
X1450820D03*
Y905853D03*
X1460070Y902649D03*
X1460071Y915466D03*
X1456371D03*
X1447122Y912262D03*
X1454521Y918670D03*
X1452671Y915466D03*
X1454522Y912262D03*
X1448971Y902649D03*
X1456370Y909057D03*
X1452671Y902649D03*
X1448970Y915466D03*
X1447120Y905853D03*
X1454520D03*
X1448971Y909057D03*
X1452671D03*
X1456371Y928283D03*
X1454522Y931488D03*
X1454520Y925079D03*
X1458220D03*
X1452426Y930125D03*
X1460071Y928283D03*
X1458220Y918670D03*
X1456371Y921875D03*
X1460070D03*
X1452670D03*
X1450820Y918670D03*
X1458220Y931488D03*
X1448971Y921875D03*
X1447120Y918670D03*
X1446677Y928348D03*
X1454520Y937896D03*
X1456371Y941100D03*
X1452426Y934725D03*
X1454520Y944304D03*
X1452321Y945354D03*
Y947654D03*
X1460070Y941100D03*
X1458221Y944304D03*
X1458220Y937896D03*
X1456371Y934691D03*
X1460070Y947509D03*
X1460071Y934691D03*
X1449992Y942195D03*
X1447692D03*
X1452426Y962325D03*
Y960025D03*
Y964625D03*
X1460070Y960326D03*
X1458220Y957122D03*
X1458221Y950713D03*
X1460071Y966735D03*
X1454520Y963530D03*
X1456371Y966735D03*
X1458220Y963529D03*
X1460071Y953917D03*
X1456370Y960326D03*
X1452426Y966925D03*
X1452333Y977669D03*
X1452476Y980736D03*
X1458221Y969939D03*
X1460070Y979552D03*
X1458220Y976347D03*
X1460071Y973143D03*
X1458220Y982756D03*
X1454521Y969939D03*
X1456371Y979552D03*
X1454520Y982756D03*
X1456371Y973143D03*
X1454520Y976347D03*
X1452426Y996825D03*
Y994525D03*
Y989925D03*
Y987625D03*
X1452436Y1010499D03*
X1452426Y1006025D03*
Y1003725D03*
Y1012925D03*
X1460503Y999684D03*
X1458654Y1009297D03*
X1458653Y1002888D03*
X1460504Y1012501D03*
X1456804Y999684D03*
X1454953Y1002888D03*
Y1009297D03*
X1456804Y1012501D03*
X1460504Y1006093D03*
X1452416Y1022635D03*
X1452426Y1017525D03*
X1458653Y1028523D03*
Y1022114D03*
X1460503Y1018910D03*
Y1031727D03*
X1460504Y1025318D03*
X1456804Y1031727D03*
Y1025318D03*
X1458653Y1015705D03*
X1447424Y1036526D03*
X1449649Y1035928D03*
X1458653Y1041340D03*
X1458654Y1034931D03*
X1451253Y1041340D03*
X1460503Y1038136D03*
X1458653Y1047749D03*
X1447553D03*
X1460504Y1044544D03*
X1451253Y1047749D03*
X1445704Y1044544D03*
X1454953Y1034931D03*
X1456804Y1038136D03*
X1454953Y1041340D03*
X1456804Y1044544D03*
X1449404D03*
X1460503Y1057361D03*
X1458653Y1060565D03*
X1456804Y1050952D03*
X1451253Y1060565D03*
X1447553Y1054157D03*
X1460504Y1050952D03*
Y1063770D03*
X1460503Y1076587D03*
X1451253Y1066974D03*
X1449404Y1070178D03*
X1460504D03*
X1458654Y1066974D03*
X1454953Y1073383D03*
X1458653Y1079791D03*
X1454954D03*
X1451253D03*
X1454953Y1066974D03*
X1445702Y1070178D03*
X1453104Y1076587D03*
X1456804D03*
Y1070178D03*
X1453104D03*
X1447553Y1073383D03*
X1449404Y1076587D03*
X1445704D03*
X1447553Y1079791D03*
X1451253Y1073383D03*
X1458653D03*
X1445703Y1089404D03*
X1458654Y1086200D03*
X1456804Y1082995D03*
X1453104Y1089404D03*
X1449404Y1082995D03*
X1460504Y1089404D03*
X1445704Y1095813D03*
X1460504D03*
X1456803D03*
X1460504Y1082995D03*
X1454954Y1092607D03*
X1451254D03*
X1449403Y1089403D03*
X1447554Y1086199D03*
X1453103Y1082994D03*
X1458654Y1092607D03*
X1453103Y1095812D03*
X1447554Y1092607D03*
X1451254Y1086199D03*
X1454954D03*
X1445704Y1102221D03*
X1458653Y1105426D03*
X1456804Y1108630D03*
X1454953Y1099017D03*
X1449404Y1108630D03*
X1453104Y1102221D03*
X1451254Y1099017D03*
X1447553D03*
X1458653Y1111834D03*
X1460504Y1108630D03*
X1451253Y1111834D03*
X1447553D03*
X1454953Y1105426D03*
X1445704Y1108630D03*
X1449404Y1102221D03*
X1458653Y1099017D03*
X1454953Y1111834D03*
X1453104Y1108630D03*
X1447553Y1105426D03*
X1451253D03*
X1460504Y1102221D03*
X1445703Y1115039D03*
X1458653Y1118243D03*
X1456803Y1115039D03*
X1454953Y1118243D03*
X1453103Y1115039D03*
X1451253Y1118243D03*
X1447553D03*
X1445704Y1127856D03*
X1460503D03*
X1453103D03*
X1460504Y1115039D03*
X1449404D03*
X1445703Y1140973D03*
X1458653Y1131060D03*
X1454953D03*
X1453103Y1140973D03*
X1451253Y1131060D03*
X1447554Y1137469D03*
Y1131060D03*
X1449403Y1134264D03*
X1460503Y1140973D03*
X1469321Y841467D03*
X1461921D03*
X1476721D03*
X1474871Y851380D03*
X1471171D03*
X1467471D03*
X1463771D03*
X1461921Y854584D03*
X1474871Y864197D03*
X1471171D03*
X1469321Y854584D03*
X1467471Y864197D03*
X1463771D03*
X1476721Y854584D03*
X1461921Y867401D03*
X1476721D03*
X1469321D03*
X1465620D03*
X1473020D03*
X1461921Y880219D03*
X1471171Y877014D03*
X1476721Y880219D03*
X1474871Y877014D03*
X1469321Y880219D03*
X1467471Y877014D03*
X1463771D03*
Y870606D03*
X1471171D03*
X1461920Y873810D03*
X1467471Y870606D03*
X1469320Y873810D03*
X1474871Y870606D03*
X1476720Y873810D03*
X1465620Y880219D03*
X1467471Y883423D03*
X1473020Y880219D03*
X1474871Y883423D03*
X1463771D03*
X1471171D03*
X1474871Y889832D03*
X1465621Y893036D03*
X1476721D03*
X1474871Y896240D03*
X1471171Y889832D03*
X1467471D03*
X1463771D03*
X1473021Y899445D03*
X1465620D03*
X1461920D03*
X1469320D03*
Y893036D03*
X1473020D03*
X1461920D03*
X1467471Y896240D03*
X1463771D03*
X1471171D03*
X1461920Y886627D03*
X1469320D03*
X1476720D03*
X1461920Y905853D03*
X1473020Y912262D03*
X1471171Y909057D03*
X1465620Y912262D03*
Y905853D03*
X1471171Y902649D03*
X1469321Y905853D03*
X1474870Y915466D03*
X1461920Y912262D03*
X1463771Y909057D03*
X1469320Y912262D03*
X1467471Y909057D03*
X1463771Y902649D03*
X1467471D03*
X1463771Y915466D03*
X1471171D03*
X1467471D03*
X1461920Y925079D03*
X1471170Y928283D03*
X1469321Y925079D03*
X1465620D03*
Y918670D03*
X1473021D03*
X1471171Y921875D03*
X1473020Y931488D03*
X1465620D03*
X1467471Y921875D03*
X1469320Y918670D03*
X1461920Y931488D03*
X1467471Y928283D03*
X1469320Y931488D03*
X1463771Y928283D03*
Y921875D03*
X1461920Y918670D03*
Y944304D03*
X1474871Y934691D03*
X1473021Y937896D03*
X1471171Y941100D03*
X1469321Y944304D03*
X1465620D03*
Y937896D03*
X1471170Y947509D03*
X1463771D03*
X1467471D03*
X1463771Y941100D03*
X1461920Y937896D03*
X1467471Y941100D03*
X1469320Y937896D03*
X1463771Y934691D03*
X1471171D03*
X1467471D03*
X1474871Y953917D03*
X1473021Y957122D03*
X1471171Y960326D03*
X1465620Y957122D03*
Y950713D03*
X1473020D03*
X1461920Y963530D03*
X1476721D03*
X1471170Y966735D03*
X1469321Y963530D03*
X1465620D03*
X1463771Y966735D03*
X1467471D03*
X1474871D03*
X1473020Y963530D03*
X1461920Y950713D03*
X1469320D03*
X1467471Y960326D03*
X1469320Y957122D03*
X1463771Y960326D03*
X1461920Y957122D03*
X1471171Y953917D03*
X1463771D03*
X1467471D03*
X1473021Y976347D03*
X1473020Y969939D03*
X1465620Y976347D03*
Y969939D03*
X1474870Y973143D03*
X1471171Y979552D03*
X1461920Y982756D03*
X1469321D03*
X1465620D03*
X1471171Y973143D03*
X1463771D03*
X1467471D03*
X1461920Y969939D03*
X1469320D03*
X1476720D03*
X1475303Y1006093D03*
X1473453Y1009297D03*
X1473454Y1002888D03*
X1471604Y999684D03*
X1466053Y1009297D03*
X1466054Y1002888D03*
X1467903Y1006093D03*
X1464204D03*
X1471603Y1012501D03*
X1471604Y1006093D03*
X1462353Y1002888D03*
X1469753D03*
X1464204Y999684D03*
X1467904D03*
X1467903Y1012501D03*
X1469753Y1009297D03*
X1464204Y1012501D03*
X1462353Y1009297D03*
Y1015705D03*
X1473453Y1028523D03*
X1466053D03*
Y1022114D03*
Y1015705D03*
X1477154D03*
X1475303Y1025318D03*
X1473453Y1022114D03*
X1471604Y1018910D03*
X1469754Y1015705D03*
X1471603Y1031727D03*
X1464204D03*
X1462353Y1028523D03*
X1467904Y1031727D03*
X1469753Y1028523D03*
X1462353Y1022114D03*
X1464204Y1018910D03*
X1469753Y1022114D03*
X1467904Y1018910D03*
X1464204Y1025318D03*
X1471604D03*
X1467904D03*
X1462353Y1034931D03*
X1473454Y1041340D03*
X1466053D03*
Y1034931D03*
X1475303Y1044544D03*
X1471604Y1038136D03*
X1469754Y1034931D03*
X1466053Y1047749D03*
X1473453D03*
X1462353D03*
X1469753D03*
X1462353Y1041340D03*
X1464204Y1038136D03*
X1469753Y1041340D03*
X1467904Y1038136D03*
X1464204Y1044544D03*
X1471604D03*
X1467904D03*
X1462353Y1054157D03*
X1473453Y1060565D03*
X1471604Y1057361D03*
X1466053Y1060565D03*
Y1054157D03*
X1471603Y1050952D03*
X1469753Y1054157D03*
X1475304Y1063770D03*
X1462353Y1060565D03*
X1464204Y1057361D03*
X1469753Y1060565D03*
X1467904Y1057361D03*
X1464204Y1050952D03*
X1467904D03*
X1464204Y1063770D03*
X1471604D03*
X1467904D03*
X1462353Y1073383D03*
X1471604Y1076587D03*
X1469754Y1073383D03*
X1466053Y1066974D03*
X1473453D03*
X1471603Y1070178D03*
X1466053Y1073383D03*
X1473454Y1079791D03*
X1466053D03*
X1462353D03*
X1464204Y1076587D03*
X1469753Y1079791D03*
X1467904Y1076587D03*
X1464204Y1070178D03*
X1462353Y1066974D03*
X1467904Y1070178D03*
X1469753Y1066974D03*
X1462353Y1092608D03*
X1475303Y1082995D03*
X1473453Y1086200D03*
X1469754Y1092608D03*
X1466053D03*
Y1086200D03*
X1471603Y1089404D03*
X1475304Y1095813D03*
X1471604D03*
X1467904D03*
Y1089404D03*
X1469753Y1086200D03*
X1464204Y1089404D03*
X1462353Y1086200D03*
X1471604Y1082995D03*
X1464204D03*
X1467904D03*
X1462353Y1105426D03*
X1462354Y1099017D03*
X1475303Y1108630D03*
Y1102221D03*
X1473454Y1105426D03*
X1469753D03*
X1467904Y1102221D03*
X1464203D03*
X1473454Y1111834D03*
X1466053D03*
Y1099017D03*
X1471604Y1102221D03*
X1477153Y1099017D03*
X1469753D03*
X1473453D03*
X1471604Y1108630D03*
X1466053Y1105426D03*
X1462353Y1111834D03*
X1469753D03*
X1467904Y1108630D03*
X1464204D03*
X1477154Y1105426D03*
Y1111833D03*
X1462353Y1118243D03*
X1477153D03*
X1475303Y1115039D03*
X1473453Y1118243D03*
X1471604Y1121447D03*
X1469754Y1118243D03*
X1466053D03*
X1475303Y1127856D03*
X1467903D03*
X1467904Y1115039D03*
X1471604D03*
X1462353Y1131060D03*
X1477153D03*
X1475303Y1140973D03*
X1473453Y1131060D03*
X1469753D03*
X1466053D03*
X1467903Y1140973D03*
X1491521Y841467D03*
X1484121D03*
X1478571Y851380D03*
X1482271D03*
X1489671D03*
X1485971D03*
X1493371D03*
X1478571Y864197D03*
X1491521Y854584D03*
X1489671Y864197D03*
X1485971D03*
X1482271D03*
X1493371D03*
X1491521Y867401D03*
X1484121D03*
Y854584D03*
X1487820Y867401D03*
X1480420D03*
X1478571Y877014D03*
X1491521Y880219D03*
X1485971Y877014D03*
X1484121Y880219D03*
X1489671Y877014D03*
X1482271D03*
X1493371D03*
Y870606D03*
X1478571D03*
X1485971D03*
X1489671D03*
X1491520Y873810D03*
X1482271Y870606D03*
X1484120Y873810D03*
X1487820Y880219D03*
X1489671Y883423D03*
X1480420Y880219D03*
X1482271Y883423D03*
X1485971D03*
X1493371D03*
X1478571D03*
X1478570Y896240D03*
X1478571Y889832D03*
X1491521Y893036D03*
X1482271Y889832D03*
X1489671D03*
X1485971D03*
X1482270Y896240D03*
X1480421Y893036D03*
X1493371Y889832D03*
X1491520Y899445D03*
X1484120D03*
X1491520Y886627D03*
X1484120D03*
X1478571Y909057D03*
Y902649D03*
X1491520Y912262D03*
X1487820Y905853D03*
X1485971Y909057D03*
X1484121Y912262D03*
X1491520Y905853D03*
X1485970Y902649D03*
X1478571Y915466D03*
X1482271D03*
X1478571Y928283D03*
Y921875D03*
X1491520Y925079D03*
Y918670D03*
X1487820Y925079D03*
X1485971Y928283D03*
X1485970Y921875D03*
X1484120Y918670D03*
X1491520Y931488D03*
X1484121D03*
X1478571Y941100D03*
Y934691D03*
X1491520Y944304D03*
Y937896D03*
X1487820Y944304D03*
X1485970Y941100D03*
X1484120Y937896D03*
X1482271Y934691D03*
X1478571Y947509D03*
X1485971D03*
X1478571Y960326D03*
Y953917D03*
X1491520Y957122D03*
Y950713D03*
X1485970Y960326D03*
X1484120Y957122D03*
X1482271Y953917D03*
X1484121Y950713D03*
X1478570Y966735D03*
X1491520Y963530D03*
X1485971Y966735D03*
X1487820Y963530D03*
X1480420D03*
X1482271Y966735D03*
X1484120Y963530D03*
X1478571Y979552D03*
Y973143D03*
X1491521Y976347D03*
X1491520Y969939D03*
X1484120Y976347D03*
X1484121Y969939D03*
X1489671Y973143D03*
X1485970Y979552D03*
X1482271Y973143D03*
X1493370D03*
X1491520Y982756D03*
X1487820D03*
X1480420Y969939D03*
X1479004Y999684D03*
X1486403D03*
X1484553Y1002888D03*
X1482704Y1006093D03*
X1479003Y1012501D03*
X1486404D03*
X1491953Y1009297D03*
Y1002888D03*
X1484554Y1009297D03*
X1479004Y1006093D03*
Y1025318D03*
Y1018910D03*
X1491953Y1028523D03*
Y1022114D03*
X1484553Y1028523D03*
X1486403Y1018910D03*
X1484553Y1022114D03*
X1482704Y1025318D03*
X1480853Y1015705D03*
X1479004Y1031727D03*
X1486404D03*
X1488253Y1015705D03*
X1491953D03*
X1479004Y1044544D03*
Y1038136D03*
X1491953Y1034931D03*
Y1041340D03*
X1488253Y1034931D03*
X1486403Y1038136D03*
X1484553Y1041340D03*
X1482704Y1044544D03*
X1491953Y1047749D03*
X1484553D03*
X1479004Y1057361D03*
Y1050952D03*
X1491953Y1054157D03*
X1486404Y1057361D03*
X1484553Y1060565D03*
X1488253Y1054157D03*
X1486404Y1050952D03*
X1491953Y1060565D03*
X1479004Y1063770D03*
X1482704D03*
X1479004Y1076587D03*
Y1070178D03*
X1486404Y1076587D03*
Y1070178D03*
X1488253Y1073383D03*
X1484553Y1066974D03*
X1491953Y1073383D03*
Y1066974D03*
X1484553Y1079791D03*
X1491953D03*
X1479004Y1089404D03*
Y1082995D03*
X1488254Y1092608D03*
X1486404Y1089404D03*
X1484554Y1086200D03*
X1482704Y1082995D03*
X1491954Y1092608D03*
X1491953Y1086200D03*
X1479004Y1095813D03*
X1490103D03*
X1493804D03*
X1479004Y1102221D03*
X1490104Y1108630D03*
Y1102221D03*
X1488254Y1099017D03*
X1484553D03*
X1482704Y1108630D03*
X1480853Y1099017D03*
X1491953Y1105426D03*
Y1111834D03*
X1493804Y1108630D03*
X1479003Y1108629D03*
X1488254Y1105426D03*
X1484554Y1111833D03*
X1482703Y1102220D03*
X1480854Y1111833D03*
Y1105426D03*
X1486403Y1108630D03*
X1488254Y1111833D03*
X1484554Y1105426D03*
X1490103Y1115039D03*
X1488253Y1118243D03*
X1484553D03*
X1480853D03*
X1486403Y1115039D03*
X1491953Y1118243D03*
X1490103Y1127856D03*
X1482703D03*
X1493804Y1115039D03*
X1482703Y1115038D03*
X1490103Y1140973D03*
X1488253Y1131060D03*
X1484553D03*
X1480853D03*
X1482703Y1140973D03*
X1491953Y1131060D03*
X1504471Y844671D03*
X1498921Y841467D03*
X1508171Y851380D03*
X1504471D03*
X1500771D03*
X1497071D03*
X1504471Y864197D03*
X1500771D03*
X1508170Y857789D03*
X1497071Y864197D03*
X1506321Y860993D03*
Y854584D03*
X1498921D03*
X1510021Y860993D03*
X1506320Y867401D03*
X1498921D03*
X1510021D03*
X1495220D03*
X1502621D03*
X1504471Y877014D03*
X1498921Y880219D03*
X1508171Y877014D03*
X1497071D03*
X1506321Y880219D03*
X1500771Y877014D03*
X1510021Y880219D03*
Y873810D03*
X1508170Y883423D03*
X1500771Y870606D03*
X1508171D03*
X1497071D03*
X1498920Y873810D03*
X1504471Y870606D03*
X1506321Y873810D03*
X1495220Y880219D03*
X1497071Y883423D03*
X1502621Y880219D03*
X1504471Y883423D03*
X1500771D03*
X1508171Y889832D03*
X1504471Y896240D03*
Y889832D03*
X1500771D03*
X1508171Y896240D03*
X1502621Y893036D03*
X1500771Y896240D03*
X1497071Y889832D03*
X1510021Y893036D03*
X1498921Y899445D03*
X1510021D03*
X1506320Y893036D03*
X1498920Y886627D03*
X1506321D03*
X1495221Y905853D03*
X1504471Y902649D03*
X1498920Y912262D03*
X1497070Y909057D03*
X1497071Y902649D03*
X1508171Y915466D03*
X1504471D03*
X1500770D03*
X1504471Y909057D03*
X1510021Y912262D03*
X1495221Y925079D03*
X1504471Y921875D03*
X1497070Y928283D03*
X1498921Y918670D03*
X1497071Y921875D03*
X1498920Y931488D03*
X1504471Y928283D03*
X1510021Y918670D03*
X1510020Y931488D03*
X1495221Y944304D03*
X1504471Y941100D03*
Y934691D03*
X1500770D03*
X1498921Y937896D03*
X1497071Y941100D03*
X1497070Y947509D03*
X1508171Y934691D03*
X1510021Y937896D03*
X1504471Y947509D03*
Y960326D03*
Y953917D03*
X1500771D03*
X1498921Y957122D03*
X1497071Y960326D03*
X1498920Y950713D03*
X1495221Y963530D03*
X1497070Y966735D03*
X1502621Y963530D03*
X1510021Y957122D03*
X1508171Y953917D03*
X1510021Y950713D03*
X1506320Y963530D03*
X1504471Y966735D03*
Y979552D03*
Y973143D03*
X1498921Y976347D03*
X1498920Y969939D03*
X1500770Y973143D03*
X1497071Y979552D03*
X1510021Y976347D03*
X1495221Y982756D03*
X1510043Y980606D03*
X1510021Y969939D03*
X1508171Y973143D03*
X1497503Y1012501D03*
Y999684D03*
X1504904Y1006093D03*
Y999684D03*
X1501203Y1006093D03*
X1499353Y1009297D03*
X1499354Y1002888D03*
X1510453Y1009297D03*
Y1002888D03*
X1508603Y1006093D03*
X1504903Y1012501D03*
X1504904Y1025318D03*
X1499353Y1028523D03*
X1501203Y1025318D03*
X1504904Y1031727D03*
X1497503D03*
X1495654Y1015705D03*
X1497504Y1018910D03*
X1499353Y1022114D03*
X1503054Y1015705D03*
X1504904Y1018910D03*
X1506753Y1015705D03*
X1510453Y1028523D03*
X1510452Y1022114D03*
X1508603Y1025318D03*
X1504904Y1044544D03*
X1501203D03*
X1499354Y1041340D03*
X1497504Y1038136D03*
X1495654Y1034931D03*
X1508604Y1044544D03*
X1499353Y1047749D03*
X1504904Y1038136D03*
X1510453Y1041340D03*
Y1047749D03*
X1504904Y1057361D03*
Y1050952D03*
X1499354Y1060565D03*
X1497504Y1057361D03*
X1497503Y1050952D03*
X1495654Y1054157D03*
X1504904Y1063770D03*
X1501203D03*
X1510453Y1060565D03*
X1508604Y1063770D03*
X1504904Y1076587D03*
Y1070178D03*
X1497504Y1076587D03*
X1497503Y1070178D03*
X1495654Y1073383D03*
X1499353Y1066974D03*
X1499354Y1079791D03*
X1510453Y1066974D03*
Y1079791D03*
X1499353Y1086200D03*
X1497503Y1089404D03*
X1495653Y1092608D03*
X1504904Y1089404D03*
Y1082995D03*
X1501203D03*
X1508604Y1082996D03*
X1510453Y1086200D03*
X1504903Y1095813D03*
X1503053Y1105426D03*
X1497503Y1102221D03*
X1495653Y1105426D03*
X1495654Y1099017D03*
X1508603Y1108630D03*
X1506754Y1111834D03*
X1499353D03*
X1503053Y1099017D03*
X1510453D03*
X1508602Y1102221D03*
X1497504Y1108630D03*
X1501204D03*
X1510453Y1111834D03*
X1499353Y1105426D03*
X1510453D03*
X1504904Y1108630D03*
X1495653Y1111834D03*
X1503053D03*
X1506753Y1124651D03*
Y1118243D03*
X1504904Y1121447D03*
X1499353Y1118243D03*
X1497503Y1115039D03*
X1495653Y1118243D03*
X1508603Y1115039D03*
X1504904Y1127856D03*
X1497503D03*
X1501204Y1115039D03*
X1504904D03*
X1508603Y1121446D03*
X1510453Y1124650D03*
X1508603Y1127855D03*
X1506754Y1137469D03*
X1506753Y1131060D03*
X1503053D03*
X1499353D03*
X1495653D03*
X1504904Y1134264D03*
X1497503Y1140973D03*
X1510453Y1131060D03*
X1511871Y844671D03*
X1513722Y848176D03*
X1511871Y851380D03*
X1521121Y860993D03*
Y854584D03*
X1515570Y864197D03*
X1513721Y854584D03*
Y860993D03*
X1521121Y867401D03*
X1517421D03*
X1513721D03*
X1511871Y870606D03*
X1522971D03*
X1517421Y873810D03*
X1511871Y883423D03*
X1517421Y880219D03*
X1522971Y883423D03*
X1511871Y889832D03*
X1513721Y893036D03*
X1517421Y886627D03*
X1521121D03*
X1513721D03*
X1526671Y889832D03*
X1513721Y899445D03*
X1524821Y912262D03*
X1511871Y909057D03*
Y902649D03*
X1513721Y912262D03*
X1515571Y909057D03*
X1524821Y905853D03*
X1513721D03*
X1519271Y909057D03*
X1511871Y928283D03*
Y921875D03*
X1519271Y928283D03*
X1515571D03*
X1513721Y918670D03*
X1524820Y925079D03*
X1513720D03*
X1524820Y931488D03*
X1513720D03*
X1511871Y941100D03*
X1513721Y937896D03*
X1524820Y944304D03*
X1513720D03*
X1511871Y947509D03*
X1525420Y949619D03*
X1519271Y947509D03*
X1515571D03*
X1525861Y962436D03*
X1511871Y960326D03*
X1513721Y957122D03*
Y950713D03*
X1511871Y966735D03*
X1524288Y965640D03*
X1513721Y963530D03*
X1515571Y979552D03*
X1513721Y982756D03*
X1511871Y973143D03*
X1517421Y969939D03*
X1515571Y973143D03*
X1519871Y984866D03*
X1516004Y1006092D03*
X1516003Y999684D03*
X1512303D03*
Y1006093D03*
X1519705Y1006092D03*
X1525396Y1000648D03*
X1512303Y1012501D03*
Y1025318D03*
X1516003Y1018910D03*
X1517854Y1015705D03*
X1525254D03*
X1521554D03*
X1514154D03*
X1512303Y1018910D03*
Y1031727D03*
X1525254Y1034931D03*
X1521554D03*
X1516004Y1044544D03*
X1516003Y1038136D03*
X1517853Y1034931D03*
X1514153D03*
X1512303Y1038136D03*
X1517853Y1054157D03*
X1514153D03*
X1512303Y1057361D03*
X1521553Y1054157D03*
X1514153Y1060565D03*
X1512303Y1050952D03*
X1525564Y1064850D03*
X1523404Y1070178D03*
X1514153Y1066974D03*
X1517853Y1073383D03*
X1521553Y1066974D03*
X1516003Y1076587D03*
X1512303D03*
X1512304Y1070178D03*
X1514153Y1073383D03*
X1523404Y1082996D03*
X1512304D03*
X1514153Y1092608D03*
X1512303Y1089404D03*
X1521553Y1092608D03*
X1523403Y1095813D03*
X1519703D03*
X1512303D03*
X1521554Y1105426D03*
X1517853D03*
X1516003Y1108630D03*
Y1102221D03*
X1512303D03*
X1517853Y1111834D03*
X1521553D03*
X1514153Y1105426D03*
X1512303Y1108630D03*
X1514153Y1111834D03*
X1519703Y1108630D03*
X1521553Y1124651D03*
Y1118243D03*
X1519704Y1115039D03*
X1516004D03*
X1514153Y1124651D03*
X1512303Y1115039D03*
X1519703Y1121446D03*
X1516003Y1127855D03*
X1512303D03*
Y1121446D03*
X1516003D03*
X1517853Y1124650D03*
X1519703Y1127855D03*
X1517854Y1131560D03*
X1512304Y1134264D03*
X1514154Y1131059D03*
X1527571Y979057D03*
X1526843Y972608D03*
X1527103Y1031726D03*
X1611475Y1259227D03*
X1714440Y1255381D03*
X1821083Y1252034D03*
G54D47*
X707677Y1714961D03*
X1155708D03*
G54D55*
X900196Y175197D03*
X944684Y155216D03*
G54D35*
X238780Y1681456D03*
X230906Y1677519D03*
Y1682244D03*
X238780Y1686180D03*
Y1709803D03*
Y1714527D03*
X230906Y1705866D03*
Y1710590D03*
X254528Y1681456D03*
X246654Y1677519D03*
Y1682244D03*
X254528Y1686180D03*
Y1709803D03*
Y1714527D03*
X246654Y1705866D03*
Y1710590D03*
X270276Y1681456D03*
X262402Y1677519D03*
Y1682244D03*
X270276Y1686180D03*
Y1709803D03*
Y1714527D03*
X262402Y1705866D03*
Y1710590D03*
X286024Y1681456D03*
X278150Y1677519D03*
Y1682244D03*
X286024Y1686180D03*
Y1709803D03*
Y1714527D03*
X278150Y1705866D03*
Y1710590D03*
X297835Y1677519D03*
Y1682244D03*
X305709Y1681456D03*
Y1686180D03*
X297835Y1705866D03*
Y1710590D03*
X305709Y1709803D03*
Y1714527D03*
X313583Y1677519D03*
Y1682244D03*
X321457Y1681456D03*
Y1686180D03*
X313583Y1705866D03*
Y1710590D03*
X321457Y1709803D03*
Y1714527D03*
X329331Y1677519D03*
Y1682244D03*
X337205Y1681456D03*
Y1686180D03*
X329331Y1705866D03*
Y1710590D03*
X337205Y1709803D03*
Y1714527D03*
X345079Y1677519D03*
Y1682244D03*
X352953Y1681456D03*
Y1686180D03*
X345079Y1705866D03*
Y1710590D03*
X352953Y1709803D03*
Y1714527D03*
X495079Y1691692D03*
Y1696417D03*
Y1720039D03*
Y1724763D03*
X510827Y1691692D03*
X502953Y1695629D03*
X510827Y1696417D03*
X502953Y1700354D03*
X510827Y1720039D03*
X502953Y1723976D03*
X510827Y1724763D03*
X502953Y1728700D03*
X526575Y1691692D03*
X518701Y1695629D03*
X526575Y1696417D03*
X534449Y1695629D03*
X518701Y1700354D03*
X534449D03*
X526575Y1720039D03*
X518701Y1723976D03*
X526575Y1724763D03*
X534449Y1723976D03*
X518701Y1728700D03*
X534449D03*
X542323Y1691692D03*
Y1696417D03*
X550197Y1695629D03*
Y1700354D03*
X542323Y1720039D03*
Y1724763D03*
X550197Y1723976D03*
Y1728700D03*
X562008Y1691692D03*
Y1696417D03*
Y1720039D03*
Y1724763D03*
X577756Y1691692D03*
X569882Y1695629D03*
X577756Y1696417D03*
X569882Y1700354D03*
X577756Y1720039D03*
X569882Y1723976D03*
X577756Y1724763D03*
X569882Y1728700D03*
X593504Y1691692D03*
X585630Y1695629D03*
X593504Y1696417D03*
X585630Y1700354D03*
X593504Y1720039D03*
X585630Y1723976D03*
X593504Y1724763D03*
X585630Y1728700D03*
X609252Y1691692D03*
X601378Y1695629D03*
X609252Y1696417D03*
X601378Y1700354D03*
X609252Y1720039D03*
X601378Y1723976D03*
X609252Y1724763D03*
X601378Y1728700D03*
X617126Y1695629D03*
Y1700354D03*
Y1723976D03*
Y1728700D03*
X1238780Y1677519D03*
Y1682244D03*
X1246654Y1681456D03*
Y1686180D03*
X1238780Y1705866D03*
Y1710590D03*
X1246654Y1709803D03*
Y1714527D03*
X1254528Y1677519D03*
Y1682244D03*
X1262402Y1681456D03*
Y1686180D03*
X1254528Y1705866D03*
Y1710590D03*
X1262402Y1709803D03*
Y1714527D03*
X1270276Y1677519D03*
Y1682244D03*
X1278150Y1681456D03*
Y1686180D03*
X1270276Y1705866D03*
Y1710590D03*
X1278150Y1709803D03*
Y1714527D03*
X1286024Y1677519D03*
Y1682244D03*
X1293898Y1681456D03*
Y1686180D03*
X1286024Y1705866D03*
Y1710590D03*
X1293898Y1709803D03*
Y1714527D03*
X1305709Y1677519D03*
Y1682244D03*
X1313583Y1681456D03*
Y1686180D03*
X1305709Y1705866D03*
Y1710590D03*
X1313583Y1709803D03*
Y1714527D03*
X1321457Y1677519D03*
Y1682244D03*
X1329331Y1681456D03*
Y1686180D03*
X1321457Y1705866D03*
Y1710590D03*
X1329331Y1709803D03*
Y1714527D03*
X1337205Y1677519D03*
Y1682244D03*
X1345079Y1681456D03*
Y1686180D03*
X1337205Y1705866D03*
Y1710590D03*
X1345079Y1709803D03*
Y1714527D03*
X1352953Y1677519D03*
Y1682244D03*
X1360827Y1681456D03*
Y1686180D03*
X1352953Y1705866D03*
Y1710590D03*
X1360827Y1709803D03*
Y1714527D03*
X1502953Y1691692D03*
Y1696417D03*
X1510827Y1695629D03*
Y1700354D03*
X1502953Y1720039D03*
Y1724763D03*
X1510827Y1723976D03*
Y1728700D03*
X1518701Y1691692D03*
Y1696417D03*
X1526575Y1695629D03*
Y1700354D03*
X1518701Y1720039D03*
Y1724763D03*
X1526575Y1723976D03*
Y1728700D03*
X1534449Y1691692D03*
Y1696417D03*
X1542323Y1695629D03*
Y1700354D03*
X1534449Y1720039D03*
Y1724763D03*
X1542323Y1723976D03*
Y1728700D03*
X1550197Y1691692D03*
Y1696417D03*
X1558071Y1695629D03*
Y1700354D03*
X1550197Y1720039D03*
Y1724763D03*
X1558071Y1723976D03*
Y1728700D03*
X1569882Y1691692D03*
Y1696417D03*
Y1720039D03*
Y1724763D03*
X1585630Y1691692D03*
X1577756Y1695629D03*
X1585630Y1696417D03*
X1577756Y1700354D03*
X1585630Y1720039D03*
X1577756Y1723976D03*
X1585630Y1724763D03*
X1577756Y1728700D03*
X1601378Y1691692D03*
X1593504Y1695629D03*
X1601378Y1696417D03*
X1593504Y1700354D03*
X1601378Y1720039D03*
X1593504Y1723976D03*
X1601378Y1724763D03*
X1593504Y1728700D03*
X1617126Y1691692D03*
X1609252Y1695629D03*
X1617126Y1696417D03*
X1609252Y1700354D03*
X1617126Y1720039D03*
X1609252Y1723976D03*
X1617126Y1724763D03*
X1609252Y1728700D03*
X1625000Y1695629D03*
Y1700354D03*
Y1723976D03*
Y1728700D03*
G54D42*
X383224Y1354446D03*
X412990D03*
X443326D03*
X458600Y1379662D03*
X472700Y1353962D03*
X1359365Y1353946D03*
X1389131D03*
X1419467D03*
X1434200Y1379362D03*
X1449233Y1353946D03*
G54D60*
X1099970Y1702570D03*
G54D61*
X1133779Y1653543D03*
G54D33*
X238780Y1648385D03*
X230906Y1644448D03*
X238780Y1662558D03*
X230906Y1658621D03*
X238780Y1676732D03*
X230906Y1672795D03*
X238780Y1690905D03*
X230906Y1686968D03*
X238780Y1705078D03*
X230906Y1701141D03*
Y1715314D03*
X238780Y1719251D03*
X230906Y1729488D03*
X238780Y1733425D03*
X254528Y1648385D03*
X246654Y1644448D03*
X254528Y1662558D03*
X246654Y1658621D03*
X254528Y1676732D03*
X246654Y1672795D03*
X254528Y1690905D03*
X246654Y1686968D03*
X254528Y1705078D03*
X246654Y1701141D03*
Y1715314D03*
X254528Y1719251D03*
X246654Y1729488D03*
X254528Y1733425D03*
X270276Y1648385D03*
X262402Y1644448D03*
X270276Y1662558D03*
X262402Y1658621D03*
X270276Y1676732D03*
X262402Y1672795D03*
X270276Y1690905D03*
X262402Y1686968D03*
X270276Y1705078D03*
X262402Y1701141D03*
Y1715314D03*
X270276Y1719251D03*
X262402Y1729488D03*
X270276Y1733425D03*
X286024Y1648385D03*
X278150Y1644448D03*
X286024Y1662558D03*
X278150Y1658621D03*
X286024Y1676732D03*
X278150Y1672795D03*
X286024Y1690905D03*
X278150Y1686968D03*
X286024Y1705078D03*
X278150Y1701141D03*
Y1715314D03*
X286024Y1719251D03*
X278150Y1729488D03*
X286024Y1733425D03*
X297835Y1672795D03*
X305709Y1676732D03*
X297835Y1686968D03*
X305709Y1690905D03*
X297835Y1701141D03*
X305709Y1705078D03*
X297835Y1715314D03*
X305709Y1719251D03*
X297835Y1729488D03*
X305709Y1733425D03*
X313583Y1672795D03*
X321457Y1676732D03*
X313583Y1686968D03*
X321457Y1690905D03*
X313583Y1701141D03*
X321457Y1705078D03*
X313583Y1715314D03*
X321457Y1719251D03*
X313583Y1729488D03*
X321457Y1733425D03*
X329331Y1672795D03*
X337205Y1676732D03*
X329331Y1686968D03*
X337205Y1690905D03*
X329331Y1701141D03*
X337205Y1705078D03*
X329331Y1715314D03*
X337205Y1719251D03*
X329331Y1729488D03*
X337205Y1733425D03*
X345079Y1672795D03*
X352953Y1676732D03*
X345079Y1686968D03*
X352953Y1690905D03*
X345079Y1701141D03*
X352953Y1705078D03*
X345079Y1715314D03*
X352953Y1719251D03*
X345079Y1729488D03*
X352953Y1733425D03*
X495079Y1672795D03*
Y1686968D03*
Y1701141D03*
Y1715314D03*
Y1729488D03*
X510827Y1672795D03*
X502953Y1676732D03*
X518701D03*
X510827Y1686968D03*
X502953Y1690905D03*
X518701D03*
X510827Y1701141D03*
X502953Y1705078D03*
X518701D03*
X510827Y1715314D03*
X502953Y1719251D03*
X518701D03*
X510827Y1729488D03*
X502953Y1733425D03*
X518701D03*
X526575Y1672795D03*
X534449Y1676732D03*
X526575Y1686968D03*
X534449Y1690905D03*
X526575Y1701141D03*
X534449Y1705078D03*
X526575Y1715314D03*
X534449Y1719251D03*
X526575Y1729488D03*
X534449Y1733425D03*
X542323Y1672795D03*
X550197Y1676732D03*
X542323Y1686968D03*
X550197Y1690905D03*
X542323Y1701141D03*
X550197Y1705078D03*
X542323Y1715314D03*
X550197Y1719251D03*
X542323Y1729488D03*
X550197Y1733425D03*
X562008Y1672795D03*
Y1686968D03*
Y1701141D03*
Y1715314D03*
Y1729488D03*
X577756Y1672795D03*
X569882Y1676732D03*
X577756Y1686968D03*
X569882Y1690905D03*
X577756Y1701141D03*
X569882Y1705078D03*
X577756Y1715314D03*
X569882Y1719251D03*
X577756Y1729488D03*
X569882Y1733425D03*
X593504Y1672795D03*
X585630Y1676732D03*
X593504Y1686968D03*
X585630Y1690905D03*
X593504Y1701141D03*
X585630Y1705078D03*
X593504Y1715314D03*
X585630Y1719251D03*
X593504Y1729488D03*
X585630Y1733425D03*
X609252Y1672795D03*
X601378Y1676732D03*
X609252Y1686968D03*
X601378Y1690905D03*
X609252Y1701141D03*
X601378Y1705078D03*
X609252Y1715314D03*
X601378Y1719251D03*
X609252Y1729488D03*
X601378Y1733425D03*
X617126Y1676732D03*
Y1690905D03*
Y1705078D03*
Y1719251D03*
Y1733425D03*
X1238780Y1672795D03*
X1246654Y1676732D03*
X1238780Y1686968D03*
X1246654Y1690905D03*
X1238780Y1701141D03*
X1246654Y1705078D03*
X1238780Y1715314D03*
X1246654Y1719251D03*
X1238780Y1729488D03*
X1246654Y1733425D03*
X1254528Y1672795D03*
X1262402Y1676732D03*
X1254528Y1686968D03*
X1262402Y1690905D03*
X1254528Y1701141D03*
X1262402Y1705078D03*
X1254528Y1715314D03*
X1262402Y1719251D03*
X1254528Y1729488D03*
X1262402Y1733425D03*
X1270276Y1672795D03*
X1278150Y1676732D03*
X1270276Y1686968D03*
X1278150Y1690905D03*
X1270276Y1701141D03*
X1278150Y1705078D03*
X1270276Y1715314D03*
X1278150Y1719251D03*
X1270276Y1729488D03*
X1278150Y1733425D03*
X1286024Y1672795D03*
X1293898Y1676732D03*
X1286024Y1686968D03*
X1293898Y1690905D03*
X1286024Y1701141D03*
X1293898Y1705078D03*
X1286024Y1715314D03*
X1293898Y1719251D03*
X1286024Y1729488D03*
X1293898Y1733425D03*
X1305709Y1672795D03*
X1313583Y1676732D03*
X1305709Y1686968D03*
X1313583Y1690905D03*
X1305709Y1701141D03*
X1313583Y1705078D03*
X1305709Y1715314D03*
X1313583Y1719251D03*
X1305709Y1729488D03*
X1313583Y1733425D03*
X1321457Y1672795D03*
X1329331Y1676732D03*
X1321457Y1686968D03*
X1329331Y1690905D03*
X1321457Y1701141D03*
X1329331Y1705078D03*
X1321457Y1715314D03*
X1329331Y1719251D03*
X1321457Y1729488D03*
X1329331Y1733425D03*
X1337205Y1672795D03*
X1345079Y1676732D03*
X1337205Y1686968D03*
X1345079Y1690905D03*
X1337205Y1701141D03*
X1345079Y1705078D03*
X1337205Y1715314D03*
X1345079Y1719251D03*
X1337205Y1729488D03*
X1345079Y1733425D03*
X1352953Y1672795D03*
X1360827Y1676732D03*
X1352953Y1686968D03*
X1360827Y1690905D03*
X1352953Y1701141D03*
X1360827Y1705078D03*
X1352953Y1715314D03*
X1360827Y1719251D03*
X1352953Y1729488D03*
X1360827Y1733425D03*
X1502953Y1672795D03*
X1510827Y1676732D03*
X1502953Y1686968D03*
X1510827Y1690905D03*
X1502953Y1701141D03*
X1510827Y1705078D03*
X1502953Y1715314D03*
X1510827Y1719251D03*
X1502953Y1729488D03*
X1510827Y1733425D03*
X1518701Y1672795D03*
X1526575Y1676732D03*
X1518701Y1686968D03*
X1526575Y1690905D03*
X1518701Y1701141D03*
X1526575Y1705078D03*
X1518701Y1715314D03*
X1526575Y1719251D03*
X1518701Y1729488D03*
X1526575Y1733425D03*
X1534449Y1672795D03*
X1542323Y1676732D03*
X1534449Y1686968D03*
X1542323Y1690905D03*
X1534449Y1701141D03*
X1542323Y1705078D03*
X1534449Y1715314D03*
X1542323Y1719251D03*
X1534449Y1729488D03*
X1542323Y1733425D03*
X1550197Y1672795D03*
X1558071Y1676732D03*
X1550197Y1686968D03*
X1558071Y1690905D03*
X1550197Y1701141D03*
X1558071Y1705078D03*
X1550197Y1715314D03*
X1558071Y1719251D03*
X1550197Y1729488D03*
X1558071Y1733425D03*
X1569882Y1672795D03*
Y1686968D03*
Y1701141D03*
Y1715314D03*
Y1729488D03*
X1585630Y1672795D03*
X1577756Y1676732D03*
X1585630Y1686968D03*
X1577756Y1690905D03*
X1585630Y1701141D03*
X1577756Y1705078D03*
X1585630Y1715314D03*
X1577756Y1719251D03*
X1585630Y1729488D03*
X1577756Y1733425D03*
X1601378Y1672795D03*
X1593504Y1676732D03*
X1601378Y1686968D03*
X1593504Y1690905D03*
X1601378Y1701141D03*
X1593504Y1705078D03*
X1601378Y1715314D03*
X1593504Y1719251D03*
X1601378Y1729488D03*
X1593504Y1733425D03*
X1617126Y1672795D03*
X1609252Y1676732D03*
X1625000D03*
X1617126Y1686968D03*
X1609252Y1690905D03*
X1625000D03*
X1617126Y1701141D03*
X1609252Y1705078D03*
X1625000D03*
X1617126Y1715314D03*
X1609252Y1719251D03*
X1625000D03*
X1617126Y1729488D03*
X1609252Y1733425D03*
X1625000D03*
G54D37*
X270252Y676260D03*
Y700414D03*
X387897Y1242785D03*
X412297D03*
X436619D03*
X461019D03*
X485419D03*
X1364038D03*
X1388438D03*
X1412760D03*
X1437160D03*
X1461560D03*
G54D29*
X159474Y1328627D03*
X183847Y1328652D03*
X208247D03*
X275289Y583576D03*
Y607735D03*
Y631889D03*
Y656043D03*
X673093Y1328652D03*
X697466Y1328677D03*
X721866D03*
X1100800Y259362D03*
X1100700Y283662D03*
X1131100Y1364962D03*
X1155500D03*
X1179900D03*
X1577000Y599762D03*
Y624262D03*
Y648762D03*
Y673162D03*
Y697662D03*
Y722162D03*
X1634259Y1362248D03*
X1658632Y1362273D03*
X1683032D03*
G54D71*
X1902608Y988322D03*
X1902682Y1351295D03*
X1951178Y1349597D03*
X1993618Y1349897D03*
G54D68*
X1881720Y988279D03*
X1881211Y1350983D03*
X1930200Y1349548D03*
X1972697Y1349606D03*
G54D18*
X40120Y744554D03*
Y1000853D03*
X69820Y744554D03*
Y1000853D03*
X99520Y744554D03*
Y1000853D03*
X129220Y744554D03*
X158920D03*
X188620D03*
X218320D03*
X722420Y1000853D03*
X752120D03*
X781820D03*
X811520D03*
X841220D03*
X1016262D03*
X1045962D03*
X1075662D03*
X1105362D03*
X1639162Y744554D03*
X1668862D03*
X1698562D03*
Y1000853D03*
X1728262Y744554D03*
Y1000853D03*
G54D57*
X928739Y321653D03*
G54D10*
X27559Y87795D03*
X40708Y631890D03*
Y1368897D03*
X51181Y1714961D03*
X373622Y87795D03*
X395670Y1714961D03*
X661023Y631890D03*
X800787Y87795D03*
X931692Y757874D03*
Y1072834D03*
Y1387795D03*
X1045865Y87795D03*
X1271260Y631890D03*
X1461805Y1714961D03*
X1499606Y87795D03*
X1816771Y631890D03*
Y1368897D03*
X1806299Y1714961D03*
X1829921Y87795D03*
G54D32*
X250326Y185236D03*
X368437D03*
G54D62*
X1247638Y269488D03*
X1405118Y112008D03*
X1766929Y1714960D03*
G54D12*
X19685Y-29134D03*
Y1803261D03*
X1837795Y-29134D03*
Y1803261D03*
X2081889Y-29134D03*
Y1803261D03*
G54D36*
X277098Y185236D03*
X395208D03*
G54D15*
X38346Y1420330D03*
X117932Y605380D03*
X763601Y605413D03*
X1094074Y605380D03*
X1739706Y605455D03*
X1819208Y1420330D03*
G54D16*
X49280Y337402D03*
X41870Y1511291D03*
X441043Y1672205D03*
Y1718465D03*
X1416437Y1672204D03*
Y1718464D03*
X1808192Y1569255D03*
X1812980Y502472D03*
G54D39*
X322500Y1391830D03*
X537477Y1395413D03*
X1298642Y1391830D03*
X1513618Y1395413D03*
G54D38*
X306772Y991220D03*
X350099Y811121D03*
X356063Y1171318D03*
X531240Y811121D03*
X525276Y1171318D03*
X574567Y991220D03*
X1282914D03*
X1326240Y811121D03*
X1332205Y1171318D03*
X1507382Y811121D03*
X1501418Y1171318D03*
X1550709Y991220D03*
G54D50*
X791280Y1704890D03*
X1066280D03*
G54D43*
X441043Y1698268D03*
X1416437Y1698267D03*
G54D52*
X805690Y204724D03*
X1057658D03*
G54D26*
X72485Y1304152D03*
X75485D03*
X78485D03*
X72485Y1307152D03*
X75485D03*
X69485Y1304152D03*
Y1307152D03*
X75485Y1316152D03*
X72485Y1313152D03*
Y1310152D03*
X75485Y1313152D03*
Y1310152D03*
X69485D03*
X93485Y1304152D03*
X87485D03*
X90485D03*
X93485Y1307152D03*
X84485Y1304152D03*
X81485D03*
X93485Y1318152D03*
Y1315652D03*
Y1310152D03*
Y1313152D03*
X108465Y1304292D03*
Y1307292D03*
X105475Y1304222D03*
Y1307222D03*
X102485Y1304152D03*
X99485D03*
X96485D03*
X102485Y1307152D03*
X99485D03*
X96485D03*
X108465Y1318292D03*
Y1310292D03*
Y1313292D03*
Y1315792D03*
X105475Y1318222D03*
Y1310222D03*
Y1313222D03*
Y1315722D03*
X99485Y1318152D03*
X96485D03*
Y1315652D03*
Y1310152D03*
Y1313152D03*
X99485Y1310152D03*
Y1313152D03*
Y1315652D03*
X102485Y1318152D03*
Y1310152D03*
Y1313152D03*
Y1315652D03*
X189800Y705062D03*
X208312Y576125D03*
X196526Y567825D03*
X208312Y581085D03*
Y578605D03*
X197423Y601496D03*
X208312Y615085D03*
Y610125D03*
Y612605D03*
X194059Y638901D03*
X197423Y635496D03*
X208312Y649085D03*
Y644125D03*
Y646605D03*
X213912Y576125D03*
X220668Y574131D03*
X223775D03*
X224064Y568113D03*
X221464D03*
X213912Y578605D03*
Y581085D03*
X217556Y590575D03*
X217561Y582131D03*
Y579531D03*
X223775Y587731D03*
X223759Y590675D03*
X220652D03*
X223775Y584531D03*
X220668Y576731D03*
Y579331D03*
X223775Y581931D03*
Y579331D03*
Y576731D03*
X220668Y581931D03*
Y608131D03*
X223775D03*
X224064Y602113D03*
X221464D03*
X223403Y596820D03*
Y594220D03*
X213912Y612605D03*
Y615085D03*
Y610125D03*
X217561Y616131D03*
Y613531D03*
X217556Y624575D03*
X223759Y624675D03*
X220652D03*
X223775Y618531D03*
X220668Y610731D03*
Y613331D03*
X223775Y615931D03*
Y613331D03*
Y610731D03*
X220668Y615931D03*
X223775Y621731D03*
X223403Y630820D03*
Y628220D03*
X224064Y636113D03*
X221464D03*
X213912Y646605D03*
Y649085D03*
Y644125D03*
X217561Y650131D03*
Y647531D03*
X223775Y655731D03*
Y652531D03*
X220668Y644731D03*
Y647331D03*
Y642131D03*
X223775Y649931D03*
Y647331D03*
Y644731D03*
Y642131D03*
X220668Y649931D03*
X217556Y658575D03*
X223403Y664820D03*
X223759Y658675D03*
X220652D03*
X217510Y668712D03*
X225167Y672006D03*
X222567D03*
X219967D03*
X217367D03*
X211348Y688087D03*
Y685287D03*
X214100Y687376D03*
Y690376D03*
Y684376D03*
Y681376D03*
Y678376D03*
X211348Y690787D03*
Y693587D03*
X214100Y693576D03*
X224506Y698138D03*
Y700738D03*
X221906Y698138D03*
Y700738D03*
X219306D03*
Y698138D03*
X231864Y568113D03*
X229264D03*
X226664D03*
X238393Y570490D03*
X229264Y602113D03*
X226664D03*
X226003Y594220D03*
Y596820D03*
X228603Y594220D03*
Y596820D03*
X231864Y602113D03*
X233803Y594220D03*
Y596820D03*
X231203Y594220D03*
Y596820D03*
X238393Y604490D03*
Y596820D03*
Y594220D03*
X226003Y628220D03*
Y630820D03*
X228603Y628220D03*
Y630820D03*
X231864Y636113D03*
X233803Y628220D03*
Y630820D03*
X231203Y628220D03*
Y630820D03*
X229264Y636113D03*
X226664D03*
X238393Y638490D03*
Y630820D03*
Y628220D03*
X228603Y664820D03*
X233803D03*
X231203D03*
X226003D03*
X230367Y672006D03*
X227767D03*
X227106Y698138D03*
Y700738D03*
X264055Y566935D03*
X263995Y569485D03*
X261495D03*
X261555Y566935D03*
X266495Y569485D03*
X266555Y566935D03*
X268995Y569485D03*
X269055Y566935D03*
X320245Y1357401D03*
X322575Y1358151D03*
X324905Y1357401D03*
X327235Y1358151D03*
X352373Y1334603D03*
X354703Y1335353D03*
X357033Y1334603D03*
X359363Y1335353D03*
X384501Y1321177D03*
X386831Y1321927D03*
X389161Y1321177D03*
X391491Y1321927D03*
X416629Y1321177D03*
X418959Y1321927D03*
X421289Y1321177D03*
X423619Y1321927D03*
X448757Y1321177D03*
X451087Y1321927D03*
X453417Y1321177D03*
X455747Y1321927D03*
X480885Y1321177D03*
X485545D03*
X483215Y1321927D03*
X487875D03*
X513013Y1334603D03*
X517673D03*
X515343Y1335353D03*
X520003D03*
X545141Y1357401D03*
X549801D03*
X547471Y1358151D03*
X552131D03*
X762345Y1284542D03*
Y1287542D03*
Y1290542D03*
X762205Y1293272D03*
X758830Y1674823D03*
X765345Y1284542D03*
X768335Y1284612D03*
X765345Y1287542D03*
Y1290542D03*
X768335Y1287612D03*
Y1290612D03*
X765205Y1293272D03*
X768195Y1293342D03*
X778005Y1294092D03*
X792045Y1284542D03*
Y1290542D03*
Y1287542D03*
X791905Y1293272D03*
X798035Y1284612D03*
X795045Y1284542D03*
X798035Y1290612D03*
Y1287612D03*
X795045Y1290542D03*
Y1287542D03*
X797895Y1293342D03*
X794905Y1293272D03*
X956022Y1620730D03*
X953022D03*
Y1632730D03*
X956022D03*
Y1629730D03*
X953022D03*
X956022Y1626730D03*
X953022D03*
Y1623730D03*
X956022D03*
X966852Y1585920D03*
X969852D03*
X960852D03*
X963852D03*
X957852D03*
X962022Y1620730D03*
X959022D03*
Y1632730D03*
X962022D03*
Y1629730D03*
X959022D03*
X962022Y1626730D03*
X959022D03*
Y1623730D03*
X962022D03*
X978403Y-9022D03*
Y-13978D03*
Y-19022D03*
Y-23978D03*
Y6022D03*
Y10978D03*
Y20978D03*
Y16022D03*
X987662Y1620870D03*
Y1629870D03*
Y1626870D03*
Y1623870D03*
Y1632870D03*
X1002782Y1585920D03*
X999782D03*
X996782D03*
X990782D03*
X993782D03*
X990662Y1620870D03*
X993662D03*
Y1629870D03*
X990662D03*
X993662Y1626870D03*
X990662D03*
Y1623870D03*
X993662D03*
X990662Y1632870D03*
X993662D03*
X1001810Y1662700D03*
Y1665200D03*
X1021942Y1586090D03*
X1019252Y1620870D03*
X1022252D03*
Y1623870D03*
Y1626870D03*
X1019252Y1623870D03*
Y1626870D03*
X1019910Y1662700D03*
Y1665200D03*
X1030942Y1586090D03*
X1033942D03*
X1024942D03*
X1027942D03*
X1025252Y1620870D03*
Y1623870D03*
Y1626870D03*
X1023580Y1662700D03*
Y1665200D03*
X1027370Y1662700D03*
Y1665200D03*
X1053612Y1586010D03*
X1050721Y1633043D03*
X1053721D03*
Y1624043D03*
Y1627043D03*
Y1630043D03*
X1050721Y1624043D03*
Y1627043D03*
Y1630043D03*
X1053721Y1621043D03*
X1050721D03*
X1044850Y1665050D03*
Y1662550D03*
X1071179Y1294669D03*
X1062612Y1586010D03*
X1065612D03*
X1056612D03*
X1059612D03*
X1056721Y1633043D03*
Y1624043D03*
Y1627043D03*
Y1630043D03*
Y1621043D03*
X1077634Y1294869D03*
X1074387Y1294652D03*
X1092302Y1585650D03*
X1089302D03*
X1098302D03*
X1095302D03*
X1095900Y1646935D03*
X1095649Y1638875D03*
X1099457D03*
X1104457Y1675490D03*
X1159930Y1645632D03*
X1164830D03*
X1161613Y1669112D03*
X1173100Y186962D03*
X1172925Y202174D03*
X1172835Y218174D03*
X1181500Y211962D03*
Y218462D03*
Y215962D03*
X1181930Y1645632D03*
X1186830D03*
X1175830D03*
X1170930D03*
X1183613Y1669112D03*
X1172613D03*
X1188300Y189062D03*
X1187300Y217862D03*
X1192500Y1645942D03*
X1197400D03*
X1194183Y1669422D03*
X1192340Y1691422D03*
X1197240D03*
X1194023Y1714902D03*
X1214693Y174962D03*
X1214134Y180972D03*
X1210457Y1658415D03*
X1218810Y1691732D03*
X1213910D03*
X1203110Y1691467D03*
X1208010D03*
X1215593Y1715212D03*
X1204793Y1714947D03*
X1243184Y182422D03*
X1239874Y182322D03*
X1236220Y189362D03*
X1245514Y224302D03*
X1264584Y226592D03*
X1256593Y221462D03*
X1267289Y192167D03*
X1269904Y192692D03*
X1287795Y-29033D03*
Y-33989D03*
Y-9033D03*
Y-13989D03*
Y-19033D03*
Y-23989D03*
Y967D03*
Y-3989D03*
X1291071Y275543D03*
Y278543D03*
X1298836Y1358387D03*
X1296506Y1357637D03*
X1303496Y1358387D03*
X1301166Y1357637D03*
X1328514Y1334603D03*
X1330844Y1335353D03*
X1333174Y1334603D03*
X1335504Y1335353D03*
X1360593Y1321872D03*
X1363098Y1320951D03*
X1365376Y1321938D03*
X1367635Y1320904D03*
X1392770Y1321177D03*
X1395100Y1321927D03*
X1397430Y1321177D03*
X1399760Y1321927D03*
X1424898Y1321177D03*
X1427228Y1321927D03*
X1429558Y1321177D03*
X1431888Y1321927D03*
X1457026Y1321177D03*
X1461686D03*
X1459356Y1321927D03*
X1464016D03*
X1480154Y-29033D03*
Y-33989D03*
Y-9033D03*
Y-13989D03*
Y-19033D03*
Y-23989D03*
Y967D03*
Y-3989D03*
X1489154Y1334603D03*
X1493814D03*
X1491484Y1335353D03*
X1496144D03*
X1521282Y1357401D03*
X1525942D03*
X1523612Y1358151D03*
X1528272D03*
X1545668Y305266D03*
X1545768Y302766D03*
X1543858Y310056D03*
X1704223Y209707D03*
X1698566Y214904D03*
X1696066D03*
X1693725Y217409D03*
X1698566Y212404D03*
X1696066D03*
X1704264Y217458D03*
X1701264D03*
X1704264Y214958D03*
X1701264D03*
X1698566Y209704D03*
X1696066D03*
X1693466Y209504D03*
Y214704D03*
Y212204D03*
X1693725Y219909D03*
X1704185Y222710D03*
X1692883Y703943D03*
X1707159Y217580D03*
Y215080D03*
Y222580D03*
Y225080D03*
Y220080D03*
X1749450Y293862D03*
X1761936Y310709D03*
X1769165Y1301422D03*
X1766165D03*
X1763165D03*
X1759987Y1325375D03*
Y1328275D03*
X1766829Y1343348D03*
X1769829Y1346248D03*
Y1343348D03*
Y1349148D03*
Y1351858D03*
X1778165Y1301422D03*
X1775165D03*
X1772165D03*
X1784165Y1304422D03*
X1781165D03*
X1784165Y1301422D03*
X1781165D03*
X1781829Y1346248D03*
Y1343348D03*
Y1349148D03*
Y1351858D03*
Y1354758D03*
X1772829Y1346248D03*
X1775829D03*
X1778829D03*
X1772829Y1343348D03*
X1775829D03*
X1778829D03*
X1772829Y1349148D03*
X1775829D03*
X1778829D03*
X1772829Y1351858D03*
X1775829D03*
X1778829D03*
X1772829Y1354758D03*
X1775829D03*
X1778829D03*
X1829695Y226333D03*
X1832295D03*
X1827095D03*
X1824095D03*
X1834895D03*
Y223733D03*
X1824095D03*
X1827095D03*
X1832295D03*
X1829695D03*
X1832295Y233933D03*
X1829695D03*
X1827095D03*
X1824095D03*
X1829695Y231433D03*
X1832295D03*
X1829695Y228933D03*
X1832295D03*
X1827095Y231433D03*
X1824095D03*
X1827095Y228933D03*
X1824095D03*
X1834895Y233933D03*
Y231433D03*
Y228933D03*
X1837895Y226333D03*
Y223733D03*
Y233933D03*
Y231433D03*
Y228933D03*
G54D23*
X58658Y754145D03*
X72981Y466385D03*
X74340Y663422D03*
X76365Y699244D03*
X76565Y717949D03*
X72315Y717414D03*
X64325Y715674D03*
X80460Y655672D03*
X83100Y649762D03*
X82735Y717949D03*
X87865Y714394D03*
X85165D03*
X81225Y715854D03*
X79635Y717949D03*
X85835Y718049D03*
X93295Y762019D03*
X107419Y487807D03*
X98134Y722501D03*
X130057Y636103D03*
X129600Y669400D03*
X132967Y760525D03*
X147141Y698811D03*
X147435Y690807D03*
X149861Y698831D03*
X150155Y690807D03*
X156685Y706836D03*
X153965Y706816D03*
X153879Y721660D03*
X156469D03*
X147031Y706835D03*
X149621D03*
X149669Y721660D03*
X147079D03*
X156477Y1339183D03*
Y1346883D03*
Y1349383D03*
X176077Y1333783D03*
X173477D03*
X176077Y1336383D03*
X173477D03*
X176107Y1339233D03*
X173507D03*
X176077Y1341883D03*
X173477D03*
Y1349383D03*
Y1346883D03*
Y1344383D03*
X176077D03*
Y1346883D03*
Y1349383D03*
X170877D03*
Y1346883D03*
Y1344383D03*
X187371Y425383D03*
X190977Y669718D03*
X191976Y684326D03*
X191977Y1333783D03*
X195888Y581071D03*
X194515Y583433D03*
X195888Y615071D03*
X194515Y617433D03*
Y651433D03*
X195888Y649071D03*
X205320Y667562D03*
X207856Y686443D03*
X203043Y686483D03*
X207824Y681560D03*
X203044Y684036D03*
X207834Y684006D03*
X203237Y681549D03*
X199720Y732862D03*
X206720Y731862D03*
X199220Y739362D03*
X207602Y756855D03*
X199602D03*
X194577Y1333783D03*
Y1349383D03*
Y1346883D03*
X208977Y1344383D03*
Y1346883D03*
Y1349383D03*
X211220Y740362D03*
X214177Y1336383D03*
X211577D03*
X214177Y1333783D03*
X211577D03*
X214207Y1339263D03*
X211607D03*
X214177Y1341883D03*
X211577D03*
X214177Y1349383D03*
Y1346883D03*
Y1344383D03*
X211577D03*
Y1346883D03*
Y1349383D03*
X248097Y92143D03*
X247897Y100543D03*
X243892Y140912D03*
X253819Y675567D03*
X253849Y678077D03*
X256419Y675567D03*
X256449Y678077D03*
X251219Y675567D03*
X251249Y678077D03*
X248649D03*
X248989Y698827D03*
X249019Y693767D03*
X251589Y698827D03*
X251649Y696277D03*
X254189Y698827D03*
X251619Y693767D03*
X256849Y696277D03*
X256789Y698827D03*
X256819Y693767D03*
X254249Y696277D03*
X254219Y693767D03*
X248300Y703862D03*
X272529Y111053D03*
X265442D03*
X261899D03*
Y108553D03*
X265442D03*
X268985Y111053D03*
Y108553D03*
X272529D03*
X259049Y678077D03*
X259019Y675567D03*
X259419Y693767D03*
X259389Y698827D03*
X259449Y696277D03*
X292942Y71499D03*
X298587Y508074D03*
X303647Y1307981D03*
X303807Y1342225D03*
X303831Y1344866D03*
X304047Y1368565D03*
X313357Y89503D03*
X313457Y96803D03*
X312301Y1345539D03*
Y1342432D03*
X309701Y1345539D03*
Y1342432D03*
X316655Y1352295D03*
X314175D03*
X311695D03*
X320101Y1342432D03*
X317701Y1348646D03*
X315101D03*
X314901Y1345539D03*
X317501D03*
X314901Y1342432D03*
X317501D03*
X316655Y1357895D03*
X311695D03*
X314175D03*
X317979Y1371248D03*
X315221Y1372445D03*
X341295Y290239D03*
X331515Y1337104D03*
Y1331904D03*
Y1329304D03*
Y1334504D03*
X328915Y1339704D03*
X326145Y1348651D03*
X326245Y1345555D03*
Y1342448D03*
X323301Y1342432D03*
X338917Y1349488D03*
X336347Y1348353D03*
X332475Y1357945D03*
X327875Y1363945D03*
Y1361045D03*
X330041Y1362315D03*
X329941Y1359315D03*
X332475Y1363345D03*
Y1360445D03*
X344264Y1272455D03*
X341754Y1272485D03*
X344252Y1269948D03*
X341742Y1269978D03*
X341754Y1274985D03*
X344264Y1274955D03*
Y1277455D03*
X341754Y1277485D03*
X344429Y1322741D03*
X347029D03*
X341829D03*
X347029Y1319634D03*
X344429D03*
X341829D03*
X349629Y1322741D03*
Y1319634D03*
X352229D03*
X355429D03*
X346303Y1335097D03*
X343823D03*
Y1329497D03*
X346303D03*
X347229Y1325848D03*
X348783Y1329497D03*
X349829Y1325848D03*
X348783Y1335097D03*
X348804Y1346877D03*
X350470Y1349030D03*
X354850Y1371908D03*
X351850D03*
X349260Y1373418D03*
X351850Y1375408D03*
X354850D03*
X351850Y1378408D03*
X354850D03*
X351850Y1381408D03*
X354850D03*
X349260Y1376918D03*
Y1379918D03*
X367939Y1305919D03*
Y1308519D03*
X358373Y1322757D03*
Y1319650D03*
X361043Y1316906D03*
X362393Y1319406D03*
X363643Y1316906D03*
Y1314306D03*
Y1309106D03*
Y1311706D03*
X358273Y1325853D03*
X370874Y1335876D03*
X367490Y1332568D03*
X362147Y1336553D03*
X360003Y1338247D03*
X364269Y1338017D03*
X364073Y1334903D03*
X360003Y1341147D03*
X362147Y1339653D03*
X364347Y1340853D03*
X364647Y1371990D03*
X361647D03*
X358647D03*
X367647D03*
X370552Y1372073D03*
X364647Y1375490D03*
X361647D03*
X358647D03*
Y1378490D03*
X370552Y1375573D03*
X367647Y1375490D03*
X373823Y1256896D03*
X376333Y1256866D03*
X373835Y1259403D03*
X376345Y1259373D03*
X373835Y1261903D03*
Y1264403D03*
X376345Y1261873D03*
Y1264373D03*
X373957Y1306208D03*
X381757D03*
X379157D03*
X376557D03*
X384357D03*
X387557D03*
X375951Y1321671D03*
X380911Y1316071D03*
X378431D03*
Y1321671D03*
X380911D03*
X373957Y1309315D03*
X381957Y1312422D03*
X381757Y1309315D03*
X379357Y1312422D03*
X379157Y1309315D03*
X376557D03*
X375951Y1316071D03*
X380842Y1334095D03*
X383549Y1333998D03*
X373552Y1372073D03*
X377025Y1371990D03*
X380025D03*
X373532Y1378598D03*
X373552Y1375573D03*
X380025Y1378490D03*
X377025D03*
X380025Y1375490D03*
X377025D03*
Y1381490D03*
X398796Y1161570D03*
Y1153070D03*
Y1170070D03*
X394521Y1305980D03*
X390501Y1306224D03*
X400067Y1305919D03*
Y1308519D03*
X390401Y1312427D03*
X390501Y1309331D03*
X392131Y1324821D03*
X396397Y1324591D03*
X394197Y1323091D03*
X396397Y1321691D03*
X399673Y1332653D03*
X403130Y1335963D03*
X394297Y1326091D03*
X392131Y1327721D03*
X396397Y1327491D03*
X419460Y1161570D03*
Y1153370D03*
Y1169597D03*
X408511Y1256866D03*
X406001Y1256896D03*
X408523Y1259373D03*
X406013Y1259403D03*
X408523Y1264373D03*
X406013Y1264403D03*
Y1261903D03*
X408523Y1261873D03*
X416485Y1306208D03*
X419685D03*
X413885D03*
X406085D03*
X411285D03*
X408685D03*
X414085Y1312422D03*
X413885Y1309315D03*
X411485Y1312422D03*
X408685Y1309315D03*
X406085D03*
X411285D03*
X413039Y1316071D03*
X408079D03*
X410559D03*
X413039Y1321671D03*
X408079D03*
X410559D03*
X416099Y1335568D03*
X414617Y1333473D03*
X421960Y1161570D03*
Y1153370D03*
Y1169597D03*
X422629Y1306224D03*
X432195Y1305919D03*
X426649Y1305980D03*
X432195Y1308519D03*
X422529Y1312427D03*
X422629Y1309331D03*
X428525Y1321691D03*
X426325Y1323091D03*
X424259Y1324821D03*
X428525Y1324591D03*
X434983Y1335924D03*
X431578Y1332560D03*
X424259Y1327721D03*
X426425Y1326091D03*
X428525Y1327491D03*
X448276Y1161570D03*
X445776D03*
X443276D03*
X445776Y1153370D03*
X448276D03*
X443276D03*
X440858Y1256866D03*
X438348Y1256896D03*
X440870Y1259373D03*
X438360Y1259403D03*
Y1261903D03*
X440870Y1261873D03*
Y1264373D03*
X438360Y1264403D03*
X448613Y1306208D03*
X446013D03*
X443413D03*
X440813D03*
X438213D03*
X451813D03*
X443613Y1312422D03*
X443413Y1309315D03*
X440813D03*
X438213D03*
X446213Y1312422D03*
X446013Y1309315D03*
X440207Y1316071D03*
X445167D03*
X442687D03*
X440207Y1321671D03*
X445167D03*
X442687D03*
X446944Y1335928D03*
X445153Y1334095D03*
X467211Y371902D03*
X455720Y404762D03*
X464427Y1305380D03*
X454757Y1306224D03*
X460927Y1306580D03*
X458327D03*
X464423Y1308519D03*
X454657Y1312427D03*
X454757Y1309331D03*
X458453Y1323091D03*
X460653Y1321691D03*
Y1324591D03*
X456387Y1324821D03*
X464738Y1333085D03*
X467644Y1335981D03*
X458553Y1326091D03*
X460653Y1327491D03*
X456387Y1327721D03*
X482720Y360862D03*
X473698Y1161570D03*
X471198D03*
X473698Y1153370D03*
X471198D03*
X473698Y1170070D03*
X471198D03*
X473035Y1256866D03*
X470525Y1256896D03*
X473047Y1259373D03*
X470537Y1259403D03*
Y1261903D03*
X473047Y1261873D03*
Y1264373D03*
X470537Y1264403D03*
X480741Y1306208D03*
X478141D03*
X475541D03*
X472941D03*
X470341D03*
X483941D03*
X472941Y1309315D03*
X478141D03*
X470341D03*
X478341Y1312422D03*
X475741D03*
X475541Y1309315D03*
X472335Y1316071D03*
X477295D03*
X474815D03*
X472335Y1321671D03*
X477295D03*
X474815D03*
X477162Y1334095D03*
X478909Y1336038D03*
X500150Y1278104D03*
X486885Y1306224D03*
X496451Y1306345D03*
X490905Y1305980D03*
X486785Y1312427D03*
X486885Y1309331D03*
X496220Y1322440D03*
X496451Y1316745D03*
Y1308945D03*
Y1314145D03*
Y1311545D03*
X492878Y1322618D03*
X490678Y1324018D03*
X488539Y1325772D03*
X492878Y1325518D03*
X488539Y1328672D03*
X490778Y1327018D03*
X492878Y1328418D03*
X499458Y1349468D03*
X514720Y360862D03*
X502720D03*
X513720Y390362D03*
X505220Y1280054D03*
X502680D03*
X515960D03*
X516069Y1319634D03*
X502469D03*
Y1322741D03*
X512869Y1319634D03*
X510269D03*
X507669D03*
X505069D03*
X507669Y1322741D03*
X505069D03*
X510269D03*
X504463Y1329497D03*
Y1335097D03*
X509423Y1329497D03*
X506943D03*
X509423Y1335097D03*
X506943D03*
X510469Y1325848D03*
X507869D03*
X509382Y1347521D03*
X511149Y1349468D03*
X529720Y390362D03*
X518500Y1280054D03*
X530450Y1297014D03*
X532570Y1298434D03*
X523033Y1319406D03*
X519013Y1319650D03*
Y1322757D03*
X527645Y1326076D03*
X528579Y1329143D03*
X528377Y1335982D03*
X518913Y1325853D03*
X525008Y1336287D03*
X520643Y1338247D03*
X522809Y1339517D03*
X522783Y1334882D03*
X520643Y1341147D03*
X528579Y1342143D03*
Y1344743D03*
X528975Y1369724D03*
X535720Y360862D03*
X543660Y1302934D03*
X541100D03*
X538560D03*
X535110Y1298464D03*
X537650D03*
X540210D03*
X536020Y1302904D03*
X539071Y1352295D03*
X536591D03*
X541551D03*
Y1357895D03*
X542256Y1369935D03*
X536591Y1357895D03*
X539071D03*
X559300Y414112D03*
X554837Y1359315D03*
X557037Y1363715D03*
Y1357915D03*
Y1360815D03*
X554937Y1362315D03*
X552771Y1361045D03*
Y1363945D03*
X574491Y376549D03*
X611381Y209878D03*
X612407Y769485D03*
X628730Y216472D03*
X631730D03*
X628730Y220472D03*
Y224472D03*
X631730Y220472D03*
Y224472D03*
X663043Y1647557D03*
X663118Y1659557D03*
X663145Y1664862D03*
Y1676862D03*
X676648Y1657380D03*
X671620Y1670862D03*
X674195Y1708362D03*
X669120Y1718862D03*
X674195Y1732362D03*
X681053Y104668D03*
X695055Y112678D03*
Y115178D03*
X684555Y1338896D03*
X689605Y1336396D03*
Y1338896D03*
X687105Y1336396D03*
X684555D03*
X687105Y1338896D03*
X689605Y1333896D03*
X687105D03*
X684555D03*
Y1341396D03*
Y1343896D03*
X689605Y1341396D03*
Y1343896D03*
X687105Y1341396D03*
Y1343896D03*
X689128Y1652262D03*
X692595Y1670862D03*
X698598Y115178D03*
X705685D03*
X702141D03*
X698598Y112678D03*
X705685D03*
X702141D03*
X704497Y1598927D03*
X697595Y1658862D03*
X704433Y1657964D03*
X697770Y1680810D03*
X714015Y-27612D03*
X720308Y-26403D03*
X714015Y-21457D03*
Y-17583D03*
X714030Y-15068D03*
X714015Y-11428D03*
X714030Y-25097D03*
X720308Y-16374D03*
X714015Y-7554D03*
X714030Y-5039D03*
X720308Y-6345D03*
X727518Y90984D03*
X723054Y1333896D03*
X725604D03*
X728104D03*
X725604Y1338896D03*
X723054Y1336396D03*
X725604D03*
X728104Y1338896D03*
Y1336396D03*
X723054Y1338896D03*
X725604Y1343896D03*
Y1341396D03*
X728104Y1343896D03*
Y1341396D03*
X723054Y1343896D03*
Y1341396D03*
X721345Y1647300D03*
X716140Y1649895D03*
X726830Y1655380D03*
X724500Y1676500D03*
X737299Y766887D03*
X733336Y1568341D03*
Y1565341D03*
Y1559341D03*
Y1562341D03*
X730336Y1559341D03*
Y1562341D03*
X745336D03*
Y1559341D03*
Y1565341D03*
Y1568341D03*
X742336Y1562341D03*
Y1559341D03*
Y1565341D03*
Y1568341D03*
X739336Y1562341D03*
Y1559341D03*
Y1565341D03*
Y1568341D03*
X736336D03*
Y1565341D03*
Y1559341D03*
Y1562341D03*
X733336Y1574341D03*
Y1571341D03*
X745336Y1574341D03*
Y1571341D03*
X742336Y1574341D03*
Y1571341D03*
X739336Y1574341D03*
Y1571341D03*
X736336D03*
Y1574341D03*
X741382Y1590691D03*
X748033Y116288D03*
X747230Y108572D03*
X756642Y496522D03*
X753137Y766625D03*
X748336Y1562341D03*
Y1559341D03*
Y1565341D03*
Y1568341D03*
X751336D03*
Y1565341D03*
Y1559341D03*
Y1562341D03*
X748336Y1574341D03*
Y1571341D03*
X761770Y1695347D03*
X775317Y764025D03*
X763747Y764335D03*
X783450Y522462D03*
X784352Y1568293D03*
Y1565293D03*
Y1559293D03*
Y1562293D03*
X781352Y1568293D03*
Y1565293D03*
Y1559293D03*
Y1562293D03*
X793352D03*
Y1559293D03*
Y1565293D03*
Y1568293D03*
X790352Y1562293D03*
Y1559293D03*
Y1565293D03*
Y1568293D03*
X787352D03*
Y1565293D03*
Y1559293D03*
Y1562293D03*
X784352Y1574293D03*
Y1571293D03*
X781352Y1574293D03*
Y1571293D03*
X793352Y1574293D03*
Y1571293D03*
X790352Y1574293D03*
Y1571293D03*
X787352D03*
Y1574293D03*
X799637Y763625D03*
X799352Y1562293D03*
Y1559293D03*
Y1565293D03*
Y1568293D03*
X796352Y1562293D03*
Y1559293D03*
Y1565293D03*
Y1568293D03*
X799352Y1574293D03*
Y1571293D03*
X796352Y1574293D03*
Y1571293D03*
X815650Y516807D03*
X821720Y515082D03*
X814800Y760922D03*
X822442Y762369D03*
X823352Y1565293D03*
Y1562293D03*
Y1559293D03*
Y1568293D03*
X826352Y1565293D03*
Y1562293D03*
Y1559293D03*
Y1568293D03*
X823352Y1571293D03*
Y1574293D03*
X826352Y1571293D03*
Y1574293D03*
X830975Y2388D03*
X830990Y4903D03*
X837268Y3597D03*
X830975Y22446D03*
Y8543D03*
Y12417D03*
X830990Y14932D03*
X830975Y18572D03*
X837268Y13626D03*
X830990Y24961D03*
X837268Y23655D03*
X836847Y762495D03*
X829352Y1565293D03*
Y1562293D03*
Y1559293D03*
Y1568293D03*
X832352D03*
Y1565293D03*
Y1559293D03*
Y1562293D03*
X835352Y1568293D03*
Y1565293D03*
Y1559293D03*
Y1562293D03*
X838352Y1568293D03*
Y1565293D03*
Y1559293D03*
Y1562293D03*
X841352Y1568293D03*
Y1565293D03*
Y1559293D03*
Y1562293D03*
X829352Y1574293D03*
Y1571293D03*
X832352D03*
Y1574293D03*
X835352Y1571293D03*
Y1574293D03*
X838352Y1571293D03*
Y1574293D03*
X841352Y1571293D03*
Y1574293D03*
X868352Y1568293D03*
Y1565293D03*
Y1559293D03*
Y1562293D03*
X865352Y1568293D03*
Y1565293D03*
Y1559293D03*
Y1562293D03*
X874352D03*
Y1559293D03*
Y1565293D03*
Y1568293D03*
X871352D03*
Y1565293D03*
Y1559293D03*
Y1562293D03*
X868352Y1574293D03*
Y1571293D03*
X865352Y1574293D03*
Y1571293D03*
X874352Y1574293D03*
Y1571293D03*
X871352D03*
Y1574293D03*
X887338Y296760D03*
X889453Y458926D03*
X883352Y1562293D03*
Y1559293D03*
Y1565293D03*
Y1568293D03*
X880352Y1562293D03*
Y1559293D03*
Y1565293D03*
Y1568293D03*
X877352Y1562293D03*
Y1559293D03*
Y1565293D03*
Y1568293D03*
X883352Y1574293D03*
Y1571293D03*
X880352Y1574293D03*
Y1571293D03*
X877352Y1574293D03*
Y1571293D03*
X907352Y1568293D03*
Y1565293D03*
Y1559293D03*
Y1562293D03*
Y1574293D03*
Y1571293D03*
X910352Y1568293D03*
Y1565293D03*
Y1559293D03*
Y1562293D03*
X922352D03*
Y1559293D03*
Y1565293D03*
Y1568293D03*
X919352Y1562293D03*
Y1559293D03*
Y1565293D03*
Y1568293D03*
X916352Y1562293D03*
Y1559293D03*
Y1565293D03*
Y1568293D03*
X913352D03*
Y1565293D03*
Y1559293D03*
Y1562293D03*
X910352Y1574293D03*
Y1571293D03*
X922352Y1574293D03*
Y1571293D03*
X919352Y1574293D03*
Y1571293D03*
X916352Y1574293D03*
Y1571293D03*
X913352D03*
Y1574293D03*
X922320Y1660953D03*
X925352Y1562293D03*
Y1559293D03*
Y1565293D03*
Y1568293D03*
Y1574293D03*
Y1571293D03*
X927122Y1661380D03*
X938220Y1661062D03*
X956980Y1536260D03*
X953980D03*
X950980D03*
X947980D03*
X944980D03*
Y1551260D03*
X947980D03*
X950980D03*
X953980D03*
X956980D03*
X944980Y1548260D03*
X947980D03*
X950980D03*
X953980D03*
X956980D03*
X944980Y1545260D03*
X947980D03*
X950980D03*
X953980D03*
X956980D03*
X944980Y1542260D03*
X947980D03*
X950980D03*
X953980D03*
X956980D03*
Y1539260D03*
X953980D03*
X950980D03*
X947980D03*
X944980D03*
Y1554260D03*
X947980D03*
X950980D03*
X953980D03*
X956980D03*
X946100Y1661100D03*
X969000Y1536262D03*
X971700D03*
X969000Y1548262D03*
X971700D03*
X969000Y1545262D03*
X971700D03*
X969000Y1551262D03*
X971700D03*
Y1542262D03*
X969000D03*
X971700Y1539262D03*
X969000D03*
X971700Y1554262D03*
X965622Y1579240D03*
Y1576240D03*
Y1573240D03*
X974700Y1536262D03*
X980400D03*
X977700D03*
X974700Y1548262D03*
Y1545262D03*
Y1551262D03*
X980400Y1548262D03*
X977700D03*
X980400Y1545262D03*
X977700D03*
X980400Y1551262D03*
X977700D03*
Y1542262D03*
X980400D03*
X974700D03*
X977700Y1539262D03*
X980400D03*
X974700D03*
Y1554262D03*
X980400D03*
X977700D03*
X988988Y1579240D03*
Y1573240D03*
Y1576240D03*
X1006220Y160799D03*
X1002720D03*
X999220Y185299D03*
X1002720D03*
X1006220D03*
X998205Y195735D03*
Y192191D03*
X1000705Y195735D03*
Y192191D03*
X998205Y199278D03*
X1000705D03*
X998205Y202821D03*
X1000705D03*
X995066Y1536262D03*
X992466D03*
X1001066D03*
X1003766D03*
X998066D03*
X995066Y1551262D03*
X992466D03*
X995066Y1545262D03*
X992466D03*
X995066Y1548262D03*
X992466D03*
X1001066Y1551262D03*
X1003766D03*
X1001066Y1545262D03*
X1003766D03*
X1001066Y1548262D03*
X1003766D03*
X998066Y1551262D03*
Y1545262D03*
Y1548262D03*
Y1542262D03*
X1003766D03*
X1001066D03*
X992466D03*
X995066D03*
X998066Y1539262D03*
X1003766D03*
X1001066D03*
X992466D03*
X995066D03*
Y1554262D03*
X1001066D03*
X1003766D03*
X998066D03*
X1009720Y160799D03*
X1013220D03*
X1012000Y185299D03*
X1014900D03*
X1017800D03*
X1017200Y175699D03*
X1014300D03*
X1019900Y175799D03*
X1018092Y520212D03*
X1021612Y1536262D03*
X1016012D03*
X1018612D03*
Y1551262D03*
X1016012D03*
X1018612Y1545262D03*
X1016012D03*
X1018612Y1548262D03*
X1016012D03*
X1021612Y1551262D03*
Y1545262D03*
Y1548262D03*
X1018612Y1542262D03*
X1016012D03*
X1021612D03*
Y1539262D03*
X1016012D03*
X1018612D03*
Y1554262D03*
X1021612D03*
X1012354Y1579240D03*
Y1573240D03*
Y1576240D03*
X1023407Y-27681D03*
X1029700Y-26472D03*
X1023407Y-32055D03*
X1029700Y-37001D03*
X1023407Y-17652D03*
X1023422Y-15137D03*
X1023407Y-11497D03*
X1029700Y-16443D03*
X1023422Y-25166D03*
X1023407Y-21526D03*
X1029700Y3615D03*
X1023422Y4921D03*
X1023407Y2406D03*
X1023422Y-5108D03*
X1023407Y-7623D03*
Y-1468D03*
X1029700Y-6414D03*
X1023407Y22464D03*
Y18590D03*
Y8561D03*
X1023422Y14950D03*
X1023407Y12435D03*
X1029700Y13644D03*
Y23673D03*
X1023422Y24979D03*
X1022800Y175799D03*
X1027212Y1536262D03*
X1024612D03*
Y1551262D03*
X1027212D03*
X1024612Y1545262D03*
X1027212D03*
X1024612Y1548262D03*
X1027212D03*
X1024612Y1542262D03*
X1027212D03*
Y1539262D03*
X1024612D03*
Y1554262D03*
X1027212D03*
X1035720Y1579240D03*
Y1573240D03*
Y1576240D03*
X1041444Y506504D03*
X1053354Y1286714D03*
Y1291714D03*
X1039510Y1296655D03*
X1049510D03*
X1044510D03*
X1039510Y1293155D03*
X1049510D03*
X1044510D03*
X1053354Y1296714D03*
X1041798Y1536262D03*
X1047798D03*
X1050498D03*
X1044798D03*
X1039298D03*
X1041798Y1551262D03*
X1039298D03*
X1041798Y1545262D03*
X1039298D03*
X1041798Y1548262D03*
X1039298D03*
X1047798Y1551262D03*
X1050498D03*
X1047798Y1545262D03*
X1050498D03*
X1047798Y1548262D03*
X1050498D03*
X1044798Y1551262D03*
Y1545262D03*
Y1548262D03*
X1039298Y1542262D03*
X1044798D03*
X1050498D03*
X1047798D03*
X1041798D03*
X1044798Y1539262D03*
X1050498D03*
X1047798D03*
X1039298D03*
X1041798D03*
Y1554262D03*
X1047798D03*
X1050498D03*
X1044798D03*
X1063354Y1286714D03*
X1058354D03*
X1063354Y1291714D03*
X1058354D03*
X1063354Y1296714D03*
X1058290Y1296302D03*
X1065164Y1536262D03*
X1062464D03*
X1071164D03*
X1068164D03*
X1065164Y1551262D03*
X1062464D03*
X1065164Y1545262D03*
X1062464D03*
X1065164Y1548262D03*
X1062464D03*
X1071164Y1551262D03*
Y1545262D03*
Y1548262D03*
X1068164Y1551262D03*
Y1545262D03*
Y1548262D03*
Y1542262D03*
X1071164D03*
X1062464D03*
X1065164D03*
X1068164Y1539262D03*
X1071164D03*
X1062464D03*
X1065164D03*
Y1554262D03*
X1071164D03*
X1068164D03*
X1059086Y1579240D03*
Y1573240D03*
Y1576240D03*
X1075462Y386723D03*
X1083714Y1285144D03*
Y1288144D03*
Y1291144D03*
X1073864Y1536262D03*
X1085830D03*
X1073864Y1551262D03*
Y1545262D03*
Y1548262D03*
X1085830Y1551262D03*
Y1545262D03*
Y1548262D03*
Y1542262D03*
X1073864D03*
X1085830Y1539262D03*
X1073864D03*
Y1554262D03*
X1090279Y126524D03*
X1089714Y1285144D03*
X1088530Y1536262D03*
X1091530D03*
X1088530Y1551262D03*
Y1545262D03*
Y1548262D03*
X1094530Y1551262D03*
X1097230D03*
X1094530Y1545262D03*
X1097230D03*
X1094530Y1548262D03*
X1097230D03*
X1091530Y1551262D03*
Y1545262D03*
Y1548262D03*
Y1542262D03*
X1097230D03*
X1094530D03*
X1088530D03*
X1091530Y1539262D03*
X1094530D03*
X1088530D03*
Y1554262D03*
X1094530D03*
X1097230D03*
X1091530D03*
X1102930Y1668690D03*
X1116338Y1711380D03*
X1113055Y1718338D03*
X1130841Y1462953D03*
X1128341Y1465453D03*
Y1462953D03*
X1130841Y1465453D03*
X1133841Y1462953D03*
Y1465453D03*
X1128341Y1468453D03*
X1130841D03*
X1133841D03*
X1128341Y1460453D03*
X1130841D03*
X1133841D03*
Y1471453D03*
X1130841D03*
X1128341D03*
X1144247Y1372700D03*
Y1370200D03*
X1146797Y1372700D03*
X1149297D03*
X1146797Y1370200D03*
X1149297D03*
X1144247Y1375200D03*
X1146797D03*
X1149297D03*
X1144247Y1377700D03*
Y1380200D03*
Y1382700D03*
X1146797D03*
X1149297D03*
X1146797Y1380200D03*
Y1377700D03*
X1149297Y1380200D03*
Y1377700D03*
X1170595Y170056D03*
X1181476Y172247D03*
X1181369Y199234D03*
X1182747Y1372700D03*
X1185297D03*
X1182747Y1370200D03*
X1185297D03*
X1182747Y1375200D03*
X1185297D03*
X1182747Y1380200D03*
Y1377700D03*
Y1382700D03*
X1185297D03*
Y1377700D03*
Y1380200D03*
X1186340Y204492D03*
X1188500Y205772D03*
X1187797Y1372700D03*
Y1370200D03*
Y1375200D03*
Y1382700D03*
Y1377700D03*
Y1380200D03*
X1213980Y1676500D03*
X1246878Y248615D03*
X1255150Y306211D03*
X1271150Y305792D03*
X1280135Y1345202D03*
Y1342602D03*
X1280312Y1365689D03*
X1290005Y290268D03*
X1291205Y1345875D03*
X1286005Y1342768D03*
Y1345875D03*
X1296405Y1342768D03*
X1293805D03*
X1288605D03*
X1291205D03*
X1288605Y1345875D03*
X1293805D03*
X1291405Y1348982D03*
X1294005D03*
X1292916Y1352531D03*
X1290436D03*
X1287956D03*
X1292916Y1358131D03*
X1290436D03*
X1287956D03*
X1283280Y1372301D03*
X1293887Y1370043D03*
X1294477Y1372651D03*
X1311952Y1321945D03*
X1307656Y1337104D03*
Y1334504D03*
Y1329304D03*
Y1331904D03*
X1305056Y1339704D03*
X1312488Y1348353D03*
X1299605Y1342768D03*
X1302549Y1345891D03*
X1302520Y1348762D03*
X1315058Y1349488D03*
X1302549Y1342784D03*
X1308616Y1363345D03*
Y1360445D03*
X1306082Y1359315D03*
X1306182Y1362315D03*
X1304016Y1363945D03*
Y1361045D03*
X1308616Y1357945D03*
X1317883Y1269978D03*
X1317895Y1272485D03*
X1320393Y1269948D03*
X1320405Y1272455D03*
X1317895Y1274985D03*
X1320405Y1274955D03*
X1317895Y1277485D03*
X1320405Y1277455D03*
X1317970Y1322741D03*
Y1319634D03*
X1325770Y1322741D03*
X1323170D03*
X1331570Y1319634D03*
X1323170D03*
X1325770D03*
X1328370D03*
X1320570Y1322741D03*
Y1319634D03*
X1322444Y1329497D03*
X1324924D03*
X1319964D03*
X1322444Y1335097D03*
X1324924D03*
X1319964D03*
X1323370Y1325848D03*
X1325970D03*
X1324945Y1346877D03*
X1327196Y1349068D03*
X1331288Y1372440D03*
X1327491Y1372358D03*
X1324491Y1372658D03*
X1327491Y1375858D03*
X1331288Y1375940D03*
X1324491Y1375858D03*
X1327491Y1381478D03*
Y1378478D03*
X1331288Y1378560D03*
X1324491Y1381478D03*
Y1378478D03*
X1322270Y1422454D03*
X1331428Y1422584D03*
X1328050D03*
X1325126Y1422630D03*
X1332726Y-27681D03*
X1339019Y-26472D03*
X1332726Y-32055D03*
X1339019Y-37001D03*
X1332726Y-11497D03*
X1339019Y-16443D03*
X1332741Y-15137D03*
X1332726Y-17652D03*
Y-21526D03*
X1332741Y-25166D03*
X1332726Y2406D03*
X1332741Y4921D03*
X1339019Y3615D03*
X1332726Y-1468D03*
X1339019Y-6414D03*
X1332726Y-7623D03*
X1332741Y-5108D03*
X1332726Y18590D03*
Y22464D03*
X1339019Y13644D03*
X1332726Y12435D03*
X1332741Y14950D03*
X1332726Y8561D03*
X1332741Y24979D03*
X1339019Y23673D03*
X1344080Y1305919D03*
Y1308519D03*
X1334514Y1322757D03*
Y1319650D03*
X1339784Y1309106D03*
X1338534Y1319406D03*
X1339784Y1316906D03*
Y1314306D03*
Y1311706D03*
X1337184Y1316906D03*
X1334414Y1325853D03*
X1347015Y1335876D03*
X1343631Y1332568D03*
X1336144Y1341147D03*
X1338288Y1339653D03*
X1340488Y1340853D03*
X1336144Y1338247D03*
X1340214Y1334853D03*
X1340410Y1338017D03*
X1338288Y1336553D03*
X1334288Y1372440D03*
X1340288D03*
X1346193Y1372523D03*
X1343193D03*
X1337288Y1372440D03*
Y1375940D03*
X1334288D03*
X1343193Y1376023D03*
X1346193D03*
X1340288Y1375940D03*
X1352474Y1256866D03*
X1349964Y1256896D03*
X1352486Y1259373D03*
X1349976Y1259403D03*
Y1261903D03*
X1352486Y1261873D03*
Y1264373D03*
X1349976Y1264403D03*
X1350098Y1306208D03*
X1352698D03*
X1355298D03*
X1360498D03*
X1363698D03*
X1357898D03*
X1352698Y1309315D03*
X1350098D03*
X1355498Y1312422D03*
X1358098D03*
X1355298Y1309315D03*
X1357898D03*
X1352092Y1316071D03*
Y1321671D03*
X1357052Y1316071D03*
X1354572D03*
X1357052Y1321671D03*
X1354572D03*
X1356983Y1334095D03*
X1359516Y1334058D03*
X1352666Y1378560D03*
X1349666D03*
X1352666Y1381560D03*
X1349666D03*
X1352666Y1375940D03*
X1349666D03*
X1352126Y1401986D03*
Y1404986D03*
X1352166Y1420456D03*
Y1414456D03*
Y1411456D03*
Y1408456D03*
Y1417456D03*
X1374938Y1161569D03*
Y1170069D03*
X1370662Y1305980D03*
X1376208Y1305919D03*
X1366642Y1306224D03*
X1376208Y1308519D03*
X1366542Y1312427D03*
X1366642Y1309331D03*
X1368272Y1324821D03*
X1372538Y1324591D03*
X1370338Y1323091D03*
X1372538Y1321691D03*
X1379271Y1335963D03*
X1375814Y1332653D03*
X1368272Y1327721D03*
X1370438Y1326091D03*
X1372538Y1327491D03*
X1396081Y1161569D03*
Y1170069D03*
X1384652Y1256866D03*
X1382142Y1256896D03*
X1384664Y1259373D03*
X1382154Y1259403D03*
Y1261903D03*
X1384664Y1261873D03*
Y1264373D03*
X1382154Y1264403D03*
X1382226Y1306208D03*
X1384826D03*
X1387426D03*
X1390026D03*
X1392626D03*
X1395826D03*
X1386700Y1321671D03*
X1389180D03*
X1382226Y1309315D03*
X1384826D03*
X1390226Y1312422D03*
X1387626D03*
X1390026Y1309315D03*
X1387426D03*
X1384220Y1316071D03*
Y1321671D03*
X1389180Y1316071D03*
X1386700D03*
X1390758Y1333473D03*
X1392076Y1335658D03*
X1398831Y1161569D03*
Y1170069D03*
X1398770Y1306224D03*
X1408336Y1305919D03*
X1402790Y1305980D03*
X1408336Y1308519D03*
X1398670Y1312427D03*
X1398770Y1309331D03*
X1400400Y1324821D03*
X1404666Y1324591D03*
X1402466Y1323091D03*
X1404666Y1321691D03*
X1411124Y1335924D03*
X1407719Y1332560D03*
X1402566Y1326091D03*
X1400400Y1327721D03*
X1404666Y1327491D03*
X1416999Y1256866D03*
X1414489Y1256896D03*
X1417011Y1259373D03*
X1414501Y1259403D03*
Y1261903D03*
X1417011Y1261873D03*
Y1264373D03*
X1414501Y1264403D03*
X1414354Y1306208D03*
X1416954D03*
X1419554D03*
X1422154D03*
X1424754D03*
X1427954D03*
X1418828Y1316071D03*
X1416348D03*
X1418828Y1321671D03*
X1416348D03*
X1421308Y1316071D03*
Y1321671D03*
X1414354Y1309315D03*
X1416954D03*
X1419554D03*
X1422354Y1312422D03*
X1419754D03*
X1422154Y1309315D03*
X1421294Y1334095D03*
X1423656Y1335468D03*
X1430898Y1306224D03*
X1434582Y1306791D03*
X1440507Y1305430D03*
X1440464Y1308519D03*
X1437182Y1306791D03*
X1430798Y1312427D03*
X1430898Y1309331D03*
X1432528Y1324821D03*
X1436794Y1324591D03*
X1434594Y1323091D03*
X1436794Y1321691D03*
X1443785Y1335981D03*
X1440879Y1333085D03*
X1434694Y1326091D03*
X1432528Y1327721D03*
X1436794Y1327491D03*
X1447149Y1161569D03*
X1449649D03*
X1447149Y1170069D03*
X1449649D03*
X1449176Y1256866D03*
X1446666Y1256896D03*
X1449188Y1259373D03*
X1446678Y1259403D03*
Y1261903D03*
X1449188Y1261873D03*
Y1264373D03*
X1446678Y1264403D03*
X1446482Y1306208D03*
X1449082D03*
X1451682D03*
X1456882D03*
X1460082D03*
X1454282D03*
X1450956Y1321671D03*
X1448476D03*
X1453436Y1316071D03*
Y1321671D03*
X1446482Y1309315D03*
X1451882Y1312422D03*
X1449082Y1309315D03*
X1451682D03*
X1454482Y1312422D03*
X1454282Y1309315D03*
X1450956Y1316071D03*
X1448476D03*
X1453303Y1334095D03*
X1455436Y1335598D03*
X1476291Y1278104D03*
X1472592Y1306345D03*
X1463026Y1306224D03*
X1467046Y1305980D03*
X1472361Y1322440D03*
X1472592Y1308945D03*
Y1316745D03*
Y1314145D03*
Y1311545D03*
X1462926Y1312427D03*
X1463026Y1309331D03*
X1466819Y1324018D03*
X1469019Y1322618D03*
Y1325518D03*
X1464680Y1325772D03*
X1469019Y1328418D03*
X1466919Y1327018D03*
X1464680Y1328672D03*
X1475599Y1349468D03*
X1481361Y1280054D03*
X1492101D03*
X1478821D03*
X1486410Y1322741D03*
X1483810D03*
X1486410Y1319634D03*
X1483810D03*
X1481210Y1322741D03*
Y1319634D03*
X1492210D03*
X1489010D03*
X1478610Y1322741D03*
Y1319634D03*
X1484010Y1325848D03*
X1486610D03*
X1485564Y1335097D03*
X1483084D03*
X1485564Y1329497D03*
X1483084D03*
X1480604Y1335097D03*
Y1329497D03*
X1485523Y1347521D03*
X1487386Y1349258D03*
X1494641Y1280054D03*
X1506591Y1297014D03*
X1508711Y1298434D03*
X1495154Y1322757D03*
Y1319650D03*
X1499048Y1319946D03*
X1504720Y1329143D03*
X1495054Y1325853D03*
X1503786Y1326076D03*
X1504518Y1335982D03*
X1496784Y1341147D03*
X1498924Y1334882D03*
X1498950Y1339517D03*
X1501149Y1336287D03*
X1496784Y1338247D03*
X1504720Y1342143D03*
Y1344743D03*
X1505116Y1369724D03*
X1513791Y1298464D03*
X1516351D03*
X1511251D03*
X1515212Y1352295D03*
X1512732D03*
X1517692D03*
X1515212Y1357895D03*
X1512732D03*
X1517692D03*
X1518451Y1369919D03*
X1540958Y307756D03*
X1541211Y646178D03*
X1533178Y1360815D03*
X1530978Y1359315D03*
X1528912Y1361045D03*
X1531078Y1362315D03*
X1533178Y1363715D03*
X1528912Y1363945D03*
X1533178Y1357915D03*
X1543958Y307556D03*
X1546458Y307856D03*
X1591368Y628727D03*
X1591428Y626177D03*
X1588928D03*
X1588868Y628727D03*
X1591398Y631237D03*
X1588898D03*
X1591368Y650877D03*
X1591338Y648367D03*
X1591398Y645817D03*
X1588868Y650877D03*
X1588838Y648367D03*
X1588898Y645817D03*
X1591368Y653377D03*
X1588868D03*
X1591448Y657677D03*
X1588948D03*
Y660177D03*
X1591448D03*
X1588968Y665237D03*
X1591468D03*
X1588938Y662727D03*
X1591438D03*
X1588938Y679807D03*
X1588878Y682357D03*
X1588908Y684867D03*
X1591438Y679807D03*
X1591378Y682357D03*
X1591408Y684867D03*
X1591328Y696727D03*
X1591388Y694177D03*
X1588888D03*
X1588828Y696727D03*
X1591358Y699277D03*
X1588858D03*
X1591358Y718837D03*
X1591328Y716327D03*
X1591388Y713777D03*
X1588858Y718837D03*
X1588828Y716327D03*
X1588888Y713777D03*
X1601830Y590685D03*
X1604430D03*
X1601830Y615201D03*
X1604430D03*
X1598868Y628727D03*
X1598928Y626177D03*
X1593868Y628727D03*
X1593928Y626177D03*
X1596428D03*
X1596368Y628727D03*
X1598898Y631237D03*
X1593898D03*
X1596398D03*
X1598868Y650877D03*
X1598838Y648367D03*
X1596368Y650877D03*
X1593868D03*
X1596338Y648367D03*
X1593838D03*
X1598898Y645817D03*
X1596398D03*
X1593898D03*
X1598868Y653377D03*
X1596368D03*
X1593868D03*
X1598948Y657677D03*
X1593948D03*
X1596448D03*
Y660177D03*
X1593948D03*
X1598948D03*
X1596468Y665237D03*
X1593968D03*
X1598968D03*
X1596438Y662727D03*
X1593938D03*
X1598938D03*
X1593938Y679807D03*
X1596438D03*
X1593878Y682357D03*
X1596378D03*
X1593908Y684867D03*
X1596408D03*
X1598878Y682357D03*
X1598908Y684867D03*
X1598938Y679807D03*
X1596288Y688902D03*
X1598888D03*
X1598828Y696727D03*
X1593828D03*
X1593888Y694177D03*
X1596388D03*
X1596328Y696727D03*
X1593858Y699277D03*
X1596358D03*
X1598888Y694177D03*
X1596288Y691502D03*
X1598858Y699277D03*
X1598888Y691502D03*
X1598858Y718837D03*
X1598828Y716327D03*
X1596358Y718837D03*
X1593858D03*
X1596328Y716327D03*
X1593828D03*
X1596388Y713777D03*
X1593888D03*
X1598888D03*
X1596250Y721452D03*
X1598850D03*
X1599010Y724002D03*
X1631203Y1367492D03*
X1628653D03*
X1626153D03*
X1628653Y1372492D03*
X1631203D03*
X1626153D03*
X1631203Y1369992D03*
X1628653D03*
X1626153D03*
X1628653Y1379992D03*
Y1382492D03*
Y1377492D03*
Y1374992D03*
X1631203Y1377492D03*
Y1374992D03*
Y1379992D03*
Y1382492D03*
X1626153Y1379992D03*
Y1382492D03*
Y1374992D03*
Y1377492D03*
X1651851Y532057D03*
X1649220Y620662D03*
X1650771Y1367492D03*
X1648271D03*
X1645721D03*
X1648271Y1372492D03*
X1650771D03*
X1645721D03*
X1650771Y1369992D03*
X1648271D03*
X1645721D03*
X1648271Y1379992D03*
Y1382492D03*
X1650771Y1379992D03*
Y1382492D03*
X1648271Y1377492D03*
Y1374992D03*
X1650771Y1377492D03*
Y1374992D03*
X1645721Y1377492D03*
Y1374992D03*
Y1379992D03*
Y1382492D03*
X1669303Y1372492D03*
X1664253D03*
X1666753D03*
X1669303Y1367492D03*
Y1369992D03*
X1666753Y1367492D03*
X1664253D03*
Y1369992D03*
X1666753D03*
X1669303Y1379992D03*
Y1382492D03*
Y1377492D03*
Y1374992D03*
X1666753Y1379992D03*
X1664253D03*
X1666753Y1382492D03*
X1664253D03*
X1666753Y1377492D03*
X1664253D03*
Y1374992D03*
X1666753D03*
X1688301Y722158D03*
X1683121D03*
X1680401D03*
X1688912Y1372492D03*
X1686362D03*
Y1367492D03*
Y1369992D03*
X1688912Y1367492D03*
Y1369992D03*
Y1377492D03*
Y1374992D03*
Y1382492D03*
Y1379992D03*
X1686362D03*
Y1382492D03*
Y1374992D03*
Y1377492D03*
X1704223Y212207D03*
X1701164Y209758D03*
Y212258D03*
X1704264Y219958D03*
X1701264D03*
X1703452Y639381D03*
X1700852Y655141D03*
X1703452Y647341D03*
Y649941D03*
Y652541D03*
Y644741D03*
X1698232Y655200D03*
X1703452Y641981D03*
X1700922Y657781D03*
X1698302Y657840D03*
X1698920Y698562D03*
X1695227Y722325D03*
X1699307Y722465D03*
X1698137Y718345D03*
X1701087Y719055D03*
X1695367Y719345D03*
X1691021Y722158D03*
X1698537Y766015D03*
X1714490Y142920D03*
X1706720Y703762D03*
X1709107Y728449D03*
X1723018Y101667D03*
X1723218Y93267D03*
X1737020Y112177D03*
Y109677D03*
X1738014Y1287344D03*
X1747650Y109677D03*
Y112177D03*
X1744106Y109677D03*
Y112177D03*
X1740563Y109677D03*
Y112177D03*
X1747814Y1287344D03*
X1742714Y1287244D03*
X1754165Y1304422D03*
Y1307422D03*
Y1301422D03*
Y1295422D03*
Y1298422D03*
Y1310422D03*
X1758063Y72623D03*
X1757165Y1304422D03*
X1760165D03*
Y1307422D03*
X1757165D03*
Y1301422D03*
X1760165D03*
X1769165Y1295422D03*
X1766165D03*
X1763165D03*
X1760165D03*
X1757165D03*
X1760165Y1298422D03*
X1757165D03*
X1763165D03*
X1766165D03*
X1769165D03*
X1757165Y1310422D03*
X1760165D03*
X1778578Y97927D03*
X1778478Y90627D03*
X1778165Y1295422D03*
X1775165D03*
X1772165D03*
Y1298422D03*
X1775165D03*
X1778165D03*
X1784165Y1295422D03*
Y1298422D03*
X1781165Y1295422D03*
Y1298422D03*
X1778165Y1312922D03*
X1784165D03*
X1781165D03*
G54D53*
X828780Y1694890D03*
Y1684890D03*
X818780Y1694890D03*
Y1684890D03*
X828780Y1704890D03*
X818780D03*
X828780Y1714890D03*
X818780D03*
X853780Y1694890D03*
Y1684890D03*
Y1704890D03*
Y1714890D03*
X863780Y1694890D03*
Y1684890D03*
Y1704890D03*
Y1714890D03*
X888780Y1684890D03*
Y1694890D03*
Y1704890D03*
Y1714890D03*
X898780Y1684890D03*
Y1694890D03*
Y1704890D03*
Y1714890D03*
X918780Y1704890D03*
X958780Y1694890D03*
Y1684890D03*
Y1704890D03*
Y1714890D03*
X968780Y1694890D03*
Y1684890D03*
Y1704890D03*
Y1714890D03*
X993780Y1684890D03*
Y1694890D03*
X1003780Y1684890D03*
Y1694890D03*
X993780Y1704890D03*
Y1714890D03*
X1003780Y1704890D03*
Y1714890D03*
X1028780Y1684890D03*
Y1694890D03*
X1038780Y1684890D03*
Y1694890D03*
X1028780Y1704890D03*
Y1714890D03*
X1038780Y1704890D03*
Y1714890D03*
G54D67*
X1879155Y592848D03*
Y840748D03*
X1889155Y592848D03*
Y840748D03*
X1900275Y964708D03*
X1910275D03*
X1931395Y592868D03*
X1921395D03*
X1952395Y1205248D03*
X1942395D03*
X1963362Y593010D03*
X1973362D03*
X1984482Y1205220D03*
X1994482D03*
X2015452Y593020D03*
X2005452D03*
X2026452Y1205400D03*
X2047419Y593162D03*
X2036452Y1205400D03*
X2057419Y593162D03*
X2078539Y1205372D03*
X2068539D03*
G54D13*
X27699Y770144D03*
Y783530D03*
Y776837D03*
Y800263D03*
Y793570D03*
Y820341D03*
Y813648D03*
Y806955D03*
Y830381D03*
Y850459D03*
Y843766D03*
Y837074D03*
Y867192D03*
Y857152D03*
Y880577D03*
Y873885D03*
Y893963D03*
Y887270D03*
Y917389D03*
Y910696D03*
Y904003D03*
Y930774D03*
Y924081D03*
Y947507D03*
Y940814D03*
Y964239D03*
Y954200D03*
Y977625D03*
Y970932D03*
Y991011D03*
Y984318D03*
Y1031168D03*
Y1024475D03*
Y1017782D03*
Y1044554D03*
Y1037861D03*
Y1057940D03*
Y1051247D03*
Y1078018D03*
Y1071326D03*
Y1064633D03*
Y1094751D03*
Y1088058D03*
Y1108137D03*
Y1101444D03*
Y1124869D03*
Y1114829D03*
Y1144948D03*
Y1138255D03*
Y1131562D03*
Y1161680D03*
Y1151641D03*
Y1175066D03*
Y1168373D03*
Y1188452D03*
Y1181759D03*
Y1205184D03*
Y1198491D03*
Y1225263D03*
Y1218570D03*
Y1211877D03*
Y1241995D03*
Y1235302D03*
Y1248688D03*
Y1265420D03*
X43841Y766798D03*
X36399Y770144D03*
X43841Y780184D03*
Y773491D03*
X36399Y783530D03*
Y776837D03*
X43841Y803609D03*
Y796916D03*
Y790223D03*
X36399Y800263D03*
Y793570D03*
X43841Y816995D03*
Y810302D03*
X36399Y820341D03*
Y813648D03*
Y806955D03*
X43841Y833727D03*
Y827034D03*
X36399Y830381D03*
X43841Y847113D03*
Y840420D03*
X36399Y850459D03*
Y843766D03*
Y837074D03*
X43841Y863845D03*
Y853806D03*
X36399Y867192D03*
Y857152D03*
X43841Y883924D03*
Y877231D03*
Y870538D03*
X36399Y880577D03*
Y873885D03*
X43841Y900656D03*
Y890617D03*
X36399Y893963D03*
Y887270D03*
X43841Y914042D03*
Y907349D03*
X36399Y917389D03*
Y910696D03*
Y904003D03*
X43841Y927428D03*
Y920735D03*
X36399Y930774D03*
Y924081D03*
X43841Y944160D03*
Y937467D03*
X36399Y947507D03*
Y940814D03*
X43841Y960892D03*
Y950853D03*
X36399Y964239D03*
Y954200D03*
X43841Y980971D03*
Y974278D03*
Y967585D03*
X36399Y977625D03*
Y970932D03*
X43841Y987664D03*
X36399Y991011D03*
Y984318D03*
X43841Y1027822D03*
Y1017782D03*
X36399Y1031168D03*
Y1024475D03*
Y1017782D03*
X43841Y1047900D03*
Y1041207D03*
Y1034515D03*
X36399Y1044554D03*
Y1037861D03*
X43841Y1061286D03*
Y1054593D03*
X36399Y1057940D03*
Y1051247D03*
X43841Y1074672D03*
Y1067979D03*
X36399Y1078018D03*
Y1071326D03*
Y1064633D03*
X43841Y1091404D03*
Y1084711D03*
X36399Y1094751D03*
Y1088058D03*
X43841Y1111483D03*
Y1104790D03*
Y1098097D03*
X36399Y1108137D03*
Y1101444D03*
X43841Y1128215D03*
Y1121522D03*
X36399Y1124869D03*
Y1114829D03*
X43841Y1141601D03*
Y1134908D03*
X36399Y1144948D03*
Y1138255D03*
Y1131562D03*
X43841Y1158333D03*
Y1148294D03*
X36399Y1161680D03*
Y1151641D03*
X43841Y1171719D03*
Y1165026D03*
X36399Y1175066D03*
Y1168373D03*
X43841Y1185105D03*
Y1178412D03*
X36399Y1188452D03*
Y1181759D03*
X43841Y1208530D03*
Y1201837D03*
Y1195144D03*
X36399Y1205184D03*
Y1198491D03*
X43841Y1221916D03*
Y1215223D03*
X36399Y1225263D03*
Y1218570D03*
Y1211877D03*
X43841Y1238648D03*
Y1231955D03*
X36399Y1241995D03*
Y1235302D03*
X43841Y1245341D03*
X36399Y1248688D03*
X43841Y1262074D03*
Y1265420D03*
X57399Y770144D03*
X52541Y766798D03*
X57399Y783530D03*
Y776837D03*
X52541Y780184D03*
Y773491D03*
X57399Y800263D03*
Y793570D03*
X52541Y803609D03*
Y796916D03*
Y790223D03*
X57399Y820341D03*
Y813648D03*
Y806955D03*
X52541Y816995D03*
Y810302D03*
X57399Y830381D03*
X52541Y833727D03*
Y827034D03*
X57399Y850459D03*
Y843766D03*
Y837074D03*
X52541Y847113D03*
Y840420D03*
X57399Y867192D03*
Y857152D03*
X52541Y863845D03*
Y853806D03*
X57399Y880577D03*
Y873885D03*
X52541Y883924D03*
Y877231D03*
Y870538D03*
X57399Y893963D03*
Y887270D03*
X52541Y900656D03*
Y890617D03*
X57399Y917389D03*
Y910696D03*
Y904003D03*
X52541Y914042D03*
Y907349D03*
X57399Y930774D03*
Y924081D03*
X52541Y927428D03*
Y920735D03*
X57399Y947507D03*
Y940814D03*
X52541Y944160D03*
Y937467D03*
X57399Y964239D03*
Y954200D03*
X52541Y960892D03*
Y950853D03*
X57399Y977625D03*
Y970932D03*
X52541Y980971D03*
Y974278D03*
Y967585D03*
X57399Y991011D03*
Y984318D03*
X52541Y987664D03*
X57399Y1031168D03*
Y1024475D03*
Y1017782D03*
X52541Y1027822D03*
Y1017782D03*
X57399Y1044554D03*
Y1037861D03*
X52541Y1047900D03*
Y1041207D03*
Y1034515D03*
X57399Y1057940D03*
Y1051247D03*
X52541Y1061286D03*
Y1054593D03*
X57399Y1078018D03*
Y1071326D03*
Y1064633D03*
X52541Y1074672D03*
Y1067979D03*
X57399Y1094751D03*
Y1088058D03*
X52541Y1091404D03*
Y1084711D03*
X57399Y1108137D03*
Y1101444D03*
X52541Y1111483D03*
Y1104790D03*
Y1098097D03*
X57399Y1124869D03*
Y1114829D03*
X52541Y1128215D03*
Y1121522D03*
X57399Y1144948D03*
Y1138255D03*
Y1131562D03*
X52541Y1141601D03*
Y1134908D03*
X57399Y1161680D03*
Y1151641D03*
X52541Y1158333D03*
Y1148294D03*
X57399Y1175066D03*
Y1168373D03*
X52541Y1171719D03*
Y1165026D03*
X57399Y1188452D03*
Y1181759D03*
X52541Y1185105D03*
Y1178412D03*
X57399Y1205184D03*
Y1198491D03*
X52541Y1208530D03*
Y1201837D03*
Y1195144D03*
X57399Y1225263D03*
Y1218570D03*
Y1211877D03*
X52541Y1221916D03*
Y1215223D03*
X57399Y1241995D03*
Y1235302D03*
X52541Y1238648D03*
Y1231955D03*
Y1248688D03*
X57399D03*
X52541Y1245341D03*
X57399Y1265420D03*
X73541Y766798D03*
X66099Y770144D03*
X73541Y780184D03*
Y773491D03*
X66099Y783530D03*
Y776837D03*
X73541Y803609D03*
Y796916D03*
Y790223D03*
X66099Y800263D03*
Y793570D03*
X73541Y816995D03*
Y810302D03*
X66099Y820341D03*
Y813648D03*
Y806955D03*
X73541Y833727D03*
Y827034D03*
X66099Y830381D03*
X73541Y847113D03*
Y840420D03*
X66099Y850459D03*
Y843766D03*
Y837074D03*
X73541Y863845D03*
Y853806D03*
X66099Y867192D03*
Y857152D03*
X73541Y883924D03*
Y877231D03*
Y870538D03*
X66099Y880577D03*
Y873885D03*
X73541Y900656D03*
Y890617D03*
X66099Y893963D03*
Y887270D03*
X73541Y914042D03*
Y907349D03*
X66099Y917389D03*
Y910696D03*
Y904003D03*
X73541Y927428D03*
Y920735D03*
X66099Y930774D03*
Y924081D03*
X73541Y944160D03*
Y937467D03*
X66099Y947507D03*
Y940814D03*
X73541Y960892D03*
Y950853D03*
X66099Y964239D03*
Y954200D03*
X73541Y980971D03*
Y974278D03*
Y967585D03*
X66099Y977625D03*
Y970932D03*
X73541Y987664D03*
X66099Y991011D03*
Y984318D03*
X73541Y1027822D03*
Y1017782D03*
X66099Y1031168D03*
Y1024475D03*
Y1017782D03*
X73541Y1047900D03*
Y1041207D03*
Y1034515D03*
X66099Y1044554D03*
Y1037861D03*
X73541Y1061286D03*
Y1054593D03*
X66099Y1057940D03*
Y1051247D03*
X73541Y1074672D03*
Y1067979D03*
X66099Y1078018D03*
Y1071326D03*
Y1064633D03*
X73541Y1091404D03*
Y1084711D03*
X66099Y1094751D03*
Y1088058D03*
X73541Y1111483D03*
Y1104790D03*
Y1098097D03*
X66099Y1108137D03*
Y1101444D03*
X73541Y1128215D03*
Y1121522D03*
X66099Y1124869D03*
Y1114829D03*
X73541Y1141601D03*
Y1134908D03*
X66099Y1144948D03*
Y1138255D03*
Y1131562D03*
X73541Y1158333D03*
Y1148294D03*
X66099Y1161680D03*
Y1151641D03*
X73541Y1171719D03*
Y1165026D03*
X66099Y1175066D03*
Y1168373D03*
X73541Y1185105D03*
Y1178412D03*
X66099Y1188452D03*
Y1181759D03*
X73541Y1208530D03*
Y1201837D03*
Y1195144D03*
X66099Y1205184D03*
Y1198491D03*
X73541Y1221916D03*
Y1215223D03*
X66099Y1225263D03*
Y1218570D03*
Y1211877D03*
X73541Y1238648D03*
Y1231955D03*
X66099Y1241995D03*
Y1235302D03*
X73541Y1245341D03*
X66099Y1248688D03*
X73541Y1265420D03*
Y1262074D03*
X87099Y770144D03*
X82241Y766798D03*
X87099Y783530D03*
Y776837D03*
X82241Y780184D03*
Y773491D03*
X87099Y800263D03*
Y793570D03*
X82241Y803609D03*
Y796916D03*
Y790223D03*
X87099Y820341D03*
Y813648D03*
Y806955D03*
X82241Y816995D03*
Y810302D03*
X87099Y830381D03*
X82241Y833727D03*
Y827034D03*
X87099Y850459D03*
Y843766D03*
Y837074D03*
X82241Y847113D03*
Y840420D03*
X87099Y867192D03*
Y857152D03*
X82241Y863845D03*
Y853806D03*
X87099Y880577D03*
Y873885D03*
X82241Y883924D03*
Y877231D03*
Y870538D03*
X87099Y893963D03*
Y887270D03*
X82241Y900656D03*
Y890617D03*
X87099Y917389D03*
Y910696D03*
Y904003D03*
X82241Y914042D03*
Y907349D03*
X87099Y930774D03*
Y924081D03*
X82241Y927428D03*
Y920735D03*
X87099Y947507D03*
Y940814D03*
X82241Y944160D03*
Y937467D03*
X87099Y964239D03*
Y954200D03*
X82241Y960892D03*
Y950853D03*
X87099Y977625D03*
Y970932D03*
X82241Y980971D03*
Y974278D03*
Y967585D03*
X87099Y991011D03*
Y984318D03*
X82241Y987664D03*
X87099Y1031168D03*
Y1024475D03*
Y1017782D03*
X82241Y1027822D03*
Y1017782D03*
X87099Y1044554D03*
Y1037861D03*
X82241Y1047900D03*
Y1041207D03*
Y1034515D03*
X87099Y1057940D03*
Y1051247D03*
X82241Y1061286D03*
Y1054593D03*
X87099Y1078018D03*
Y1071326D03*
Y1064633D03*
X82241Y1074672D03*
Y1067979D03*
X87099Y1094751D03*
Y1088058D03*
X82241Y1091404D03*
Y1084711D03*
X87099Y1108137D03*
Y1101444D03*
X82241Y1111483D03*
Y1104790D03*
Y1098097D03*
X87099Y1124869D03*
Y1114829D03*
X82241Y1128215D03*
Y1121522D03*
X87099Y1144948D03*
Y1138255D03*
Y1131562D03*
X82241Y1141601D03*
Y1134908D03*
X87099Y1161680D03*
Y1151641D03*
X82241Y1158333D03*
Y1148294D03*
X87099Y1175066D03*
Y1168373D03*
X82241Y1171719D03*
Y1165026D03*
X87099Y1188452D03*
Y1181759D03*
X82241Y1185105D03*
Y1178412D03*
X87099Y1205184D03*
Y1198491D03*
X82241Y1208530D03*
Y1201837D03*
Y1195144D03*
X87099Y1225263D03*
Y1218570D03*
Y1211877D03*
X82241Y1221916D03*
Y1215223D03*
X87099Y1241995D03*
Y1235302D03*
X82241Y1238648D03*
Y1231955D03*
X87099Y1248688D03*
X82241Y1245341D03*
X87099Y1265420D03*
X103241Y766798D03*
X95799Y770144D03*
X103241Y780184D03*
Y773491D03*
X95799Y783530D03*
Y776837D03*
X103241Y803609D03*
Y796916D03*
Y790223D03*
X95799Y800263D03*
Y793570D03*
X103241Y816995D03*
Y810302D03*
X95799Y820341D03*
Y813648D03*
Y806955D03*
X103241Y833727D03*
Y827034D03*
X95799Y830381D03*
X103241Y847113D03*
Y840420D03*
X95799Y850459D03*
Y843766D03*
Y837074D03*
X103241Y863845D03*
Y853806D03*
X95799Y867192D03*
Y857152D03*
X103241Y883924D03*
Y877231D03*
Y870538D03*
X95799Y880577D03*
Y873885D03*
X103241Y900656D03*
Y890617D03*
X95799Y893963D03*
Y887270D03*
X103241Y914042D03*
Y907349D03*
X95799Y917389D03*
Y910696D03*
Y904003D03*
X103241Y927428D03*
Y920735D03*
X95799Y930774D03*
Y924081D03*
X103241Y944160D03*
Y937467D03*
X95799Y947507D03*
Y940814D03*
X103241Y960892D03*
Y950853D03*
X95799Y964239D03*
Y954200D03*
X103241Y980971D03*
Y974278D03*
Y967585D03*
X95799Y977625D03*
Y970932D03*
X103241Y987664D03*
X95799Y991011D03*
Y984318D03*
X103241Y1027822D03*
Y1017782D03*
X95799Y1031168D03*
Y1024475D03*
Y1017782D03*
X103241Y1047900D03*
Y1041207D03*
Y1034515D03*
X95799Y1044554D03*
Y1037861D03*
X103241Y1061286D03*
Y1054593D03*
X95799Y1057940D03*
Y1051247D03*
X103241Y1074672D03*
Y1067979D03*
X95799Y1078018D03*
Y1071326D03*
Y1064633D03*
X103241Y1091404D03*
Y1084711D03*
X95799Y1094751D03*
Y1088058D03*
X103241Y1111483D03*
Y1104790D03*
Y1098097D03*
X95799Y1108137D03*
Y1101444D03*
X103241Y1128215D03*
Y1121522D03*
X95799Y1124869D03*
Y1114829D03*
X103241Y1141601D03*
Y1134908D03*
X95799Y1144948D03*
Y1138255D03*
Y1131562D03*
X103241Y1158333D03*
Y1148294D03*
X95799Y1161680D03*
Y1151641D03*
X103241Y1171719D03*
Y1165026D03*
X95799Y1175066D03*
Y1168373D03*
X103241Y1185105D03*
Y1178412D03*
X95799Y1188452D03*
Y1181759D03*
X103241Y1208530D03*
Y1201837D03*
Y1195144D03*
X95799Y1205184D03*
Y1198491D03*
X103241Y1221916D03*
Y1215223D03*
X95799Y1225263D03*
Y1218570D03*
Y1211877D03*
X103241Y1238648D03*
Y1231955D03*
X95799Y1241995D03*
Y1235302D03*
X103241Y1245341D03*
X95799Y1248688D03*
X103241Y1265420D03*
Y1262074D03*
X125499Y770144D03*
X116799D03*
X111941Y766798D03*
X125499Y783530D03*
X116799D03*
X125499Y776837D03*
X116799D03*
X111941Y780184D03*
Y773491D03*
X125499Y800263D03*
X116799D03*
X125499Y793570D03*
X116799D03*
X111941Y803609D03*
Y796916D03*
Y790223D03*
X125499Y820341D03*
X116799D03*
X125499Y813648D03*
X116799D03*
X125499Y806955D03*
X116799D03*
X111941Y816995D03*
Y810302D03*
X125499Y830381D03*
X116799D03*
X111941Y833727D03*
Y827034D03*
X125499Y850459D03*
X116799D03*
X125499Y843766D03*
X116799D03*
X125499Y837074D03*
X116799D03*
X111941Y847113D03*
Y840420D03*
X116799Y867192D03*
X125499Y857152D03*
X116799D03*
X111941Y863845D03*
Y853806D03*
X116799Y880577D03*
Y873885D03*
X111941Y883924D03*
Y877231D03*
Y870538D03*
X116799Y893963D03*
Y887270D03*
X111941Y900656D03*
Y890617D03*
X116799Y917389D03*
Y910696D03*
Y904003D03*
X111941Y914042D03*
Y907349D03*
X116799Y930774D03*
Y924081D03*
X111941Y927428D03*
Y920735D03*
X116799Y947507D03*
Y940814D03*
X111941Y944160D03*
Y937467D03*
X116799Y964239D03*
Y954200D03*
X111941Y960892D03*
Y950853D03*
X116799Y977625D03*
Y970932D03*
X111941Y980971D03*
Y974278D03*
Y967585D03*
X116799Y991011D03*
Y984318D03*
X111941Y987664D03*
X116799Y1031168D03*
Y1024475D03*
Y1017782D03*
X111941Y1027822D03*
Y1017782D03*
X116799Y1044554D03*
Y1037861D03*
X111941Y1047900D03*
Y1041207D03*
Y1034515D03*
X116799Y1057940D03*
Y1051247D03*
X111941Y1061286D03*
Y1054593D03*
X116799Y1078018D03*
Y1071326D03*
Y1064633D03*
X111941Y1074672D03*
Y1067979D03*
X116799Y1094751D03*
Y1088058D03*
X111941Y1091404D03*
Y1084711D03*
X116799Y1108137D03*
Y1101444D03*
X111941Y1111483D03*
Y1104790D03*
Y1098097D03*
X116799Y1124869D03*
Y1114829D03*
X111941Y1128215D03*
Y1121522D03*
X116799Y1144948D03*
Y1138255D03*
Y1131562D03*
X111941Y1141601D03*
Y1134908D03*
X116799Y1161680D03*
Y1151641D03*
X111941Y1158333D03*
Y1148294D03*
X116799Y1175066D03*
Y1168373D03*
X111941Y1171719D03*
Y1165026D03*
X116799Y1188452D03*
Y1181759D03*
X111941Y1185105D03*
Y1178412D03*
X116799Y1205184D03*
Y1198491D03*
X111941Y1208530D03*
Y1201837D03*
Y1195144D03*
X116799Y1225263D03*
Y1218570D03*
Y1211877D03*
X111941Y1221916D03*
Y1215223D03*
X116799Y1241995D03*
Y1235302D03*
X111941Y1238648D03*
Y1231955D03*
X116799Y1248688D03*
X111941Y1245341D03*
X116799Y1265420D03*
X141641Y766798D03*
X132941D03*
X141641Y773491D03*
X132941D03*
X141641Y780184D03*
X132941D03*
X141641Y803609D03*
X132941D03*
X141641Y790223D03*
X132941D03*
X141641Y796916D03*
X132941D03*
X141641Y816995D03*
X132941D03*
X141641Y810302D03*
X132941D03*
X141641Y833727D03*
X132941D03*
X141641Y827034D03*
X132941D03*
X141641Y840420D03*
X132941D03*
X141641Y847113D03*
X132941D03*
X141641Y853806D03*
X132941D03*
Y1265420D03*
X146499Y770144D03*
X155199D03*
X146499Y783530D03*
X155199D03*
X146499Y776837D03*
X155199D03*
X146499Y800263D03*
X155199D03*
X146499Y793570D03*
X155199D03*
X146499Y820341D03*
X155199D03*
X146499Y813648D03*
X155199D03*
X146499Y806955D03*
X155199D03*
X146499Y830381D03*
X155199D03*
X146499Y850459D03*
X155199D03*
X146499Y843766D03*
X155199D03*
X146499Y837074D03*
X155199D03*
X146499Y857152D03*
X155199D03*
X176199Y770144D03*
X162641Y766798D03*
X171341D03*
X176199Y783530D03*
Y776837D03*
X162641Y780184D03*
X171341D03*
Y773491D03*
X162641D03*
X176199Y800263D03*
X162641Y803609D03*
X171341D03*
X176199Y793570D03*
X162641Y796916D03*
X171341D03*
X162641Y790223D03*
X171341D03*
X176199Y820341D03*
X162641Y816995D03*
X171341D03*
X176199Y813648D03*
Y806955D03*
X162641Y810302D03*
X171341D03*
X162641Y833727D03*
X171341D03*
X176199Y830381D03*
X162641Y827034D03*
X171341D03*
X176199Y850459D03*
Y843766D03*
Y837074D03*
X162641Y847113D03*
X171341D03*
X162641Y840420D03*
X171341D03*
X176199Y857152D03*
X162641Y853806D03*
X171341D03*
X192341Y766798D03*
X184899Y770144D03*
X192341Y780184D03*
Y773491D03*
X184899Y783530D03*
Y776837D03*
X192341Y803609D03*
Y796916D03*
Y790223D03*
X184899Y800263D03*
Y793570D03*
X192341Y816995D03*
Y810302D03*
X184899Y820341D03*
Y813648D03*
Y806955D03*
X192341Y833727D03*
X191491Y827034D03*
X184899Y830381D03*
X192341Y847113D03*
Y840420D03*
X184899Y850459D03*
Y843766D03*
Y837074D03*
X192341Y853806D03*
X184899Y857152D03*
X205899Y770144D03*
X201041Y766798D03*
X205899Y783530D03*
Y776837D03*
X201041Y780184D03*
Y773491D03*
X205899Y800263D03*
Y793570D03*
X201041Y803609D03*
Y796916D03*
Y790223D03*
X205899Y813648D03*
Y806955D03*
X205049Y820341D03*
X201041Y816995D03*
Y810302D03*
X205049Y830381D03*
X201041Y833727D03*
Y827034D03*
X205899Y850459D03*
Y837074D03*
Y843766D03*
X201041Y847113D03*
Y840420D03*
X205049Y857152D03*
X201041Y853806D03*
X222041Y766798D03*
X214599Y770144D03*
X222041Y780184D03*
Y773491D03*
X214599Y783530D03*
Y776837D03*
X222041Y803609D03*
Y796916D03*
Y790223D03*
X214599Y800263D03*
Y793570D03*
X222041Y810302D03*
X221191Y816995D03*
X214599Y813648D03*
Y806955D03*
X215449Y820341D03*
X222041Y833727D03*
X221191Y827034D03*
X215449Y830381D03*
X222041Y847113D03*
Y840420D03*
X214599Y850459D03*
Y837074D03*
Y843766D03*
X222041Y853806D03*
X215449Y857152D03*
X235599Y770144D03*
X230741Y766798D03*
X235599Y783530D03*
Y776837D03*
X230741Y780184D03*
Y773491D03*
X235599Y800263D03*
Y793570D03*
X230741Y803609D03*
Y796916D03*
Y790223D03*
X234749Y820341D03*
Y813648D03*
X235599Y806955D03*
X230741Y810302D03*
X231006Y817554D03*
X235599Y830381D03*
X230741Y833727D03*
X231591Y827034D03*
X235599Y850459D03*
Y837074D03*
Y843766D03*
X230741Y847113D03*
Y840420D03*
X234749Y857152D03*
X230741Y853806D03*
X236391Y1002557D03*
X240521Y1000395D03*
X237841Y1000437D03*
X233891Y1002557D03*
X231391D03*
X228891D03*
X254881Y999650D03*
X257561Y999608D03*
X348879Y873810D03*
X393278Y848176D03*
X415185Y956620D03*
X411685D03*
X409385D03*
X417685D03*
X412365Y985610D03*
X410065D03*
X420145Y985550D03*
X409385Y1014540D03*
X407085D03*
X411685D03*
X420405Y1014470D03*
X414461Y1028855D03*
X411961D03*
X416961D03*
X419461D03*
X432130Y941101D03*
X435830D03*
Y947510D03*
X422685Y956620D03*
X425185D03*
X422685Y985580D03*
X423015Y1014470D03*
X421961Y1028855D03*
X437680Y944305D03*
X441380D03*
X443230Y941101D03*
X445079Y944305D03*
X439530Y941101D03*
X439529Y947510D03*
X467278Y899445D03*
X453585Y942238D03*
Y939938D03*
Y944538D03*
X453403Y956999D03*
X461424Y956620D03*
X458404D03*
X453403Y959299D03*
X468904Y956620D03*
Y971100D03*
X458404D03*
X461424Y971140D03*
X453403Y973099D03*
Y970799D03*
Y986899D03*
X461424Y985580D03*
X458404D03*
X453403Y984599D03*
X468904Y985580D03*
X453403Y998399D03*
Y1012199D03*
X458404Y1000080D03*
X461424D03*
X453403Y1000699D03*
X468904Y1000080D03*
X458404Y1014540D03*
X461295Y1014510D03*
X453403Y1014499D03*
X465680Y1028855D03*
X463180D03*
X460680D03*
X458180D03*
X471404Y956620D03*
Y971100D03*
X473904D03*
X471404Y985580D03*
Y1000080D03*
X629599Y770144D03*
X620899D03*
X629599Y783530D03*
X620899D03*
X629599Y776837D03*
X620899D03*
X620846Y800263D03*
X629599D03*
Y793570D03*
X620899D03*
Y820341D03*
X629599D03*
X620076Y813648D03*
X630593D03*
X619632Y806955D03*
X630792D03*
X620899Y830381D03*
X629599D03*
X620899Y843766D03*
X629599D03*
Y837074D03*
X620899D03*
X623347Y999665D03*
X625780Y1000198D03*
X637041Y766798D03*
X645741D03*
Y773491D03*
X637041D03*
X645741Y780184D03*
X637041D03*
Y803609D03*
X645741D03*
X637041Y796916D03*
X645741D03*
Y790223D03*
X637041D03*
X636221Y810302D03*
X646844D03*
X646774Y816995D03*
X637041D03*
X645741Y833727D03*
X637041D03*
Y827034D03*
X645741D03*
X637041Y840420D03*
X645741D03*
X644347Y1003135D03*
X640327D03*
X640467Y1000735D03*
X647447Y1002865D03*
X647397Y1000135D03*
X650599Y770144D03*
X659299D03*
X650599Y783530D03*
X659299D03*
X650599Y776837D03*
X659299D03*
Y800263D03*
X650599D03*
Y793570D03*
X659299D03*
Y806955D03*
X650599D03*
X660432Y813648D03*
X650599D03*
X660199Y820341D03*
X650599D03*
X659299Y830381D03*
X650599D03*
X659299Y843766D03*
X650599D03*
Y837074D03*
X659299D03*
X650107Y1002825D03*
X680299Y770144D03*
X675441Y766798D03*
X666741D03*
X680299Y783530D03*
Y776837D03*
X666741Y773491D03*
X675441D03*
X666741Y780184D03*
X675441D03*
Y803609D03*
X666741D03*
X680299Y800263D03*
Y793570D03*
X666741Y796916D03*
X675441D03*
X666741Y790223D03*
X675441D03*
X676403Y816995D03*
X665803D03*
X675441Y810302D03*
X666741D03*
X680299Y820341D03*
Y813648D03*
Y806955D03*
X675441Y833727D03*
X666741D03*
X676625Y827034D03*
X665876D03*
X680299Y830381D03*
Y843766D03*
Y837074D03*
X666741Y840420D03*
X675441D03*
X696441Y766798D03*
X688999Y770144D03*
X696441Y773491D03*
Y780184D03*
X688999Y783530D03*
Y776837D03*
X696441Y803609D03*
Y796916D03*
Y790223D03*
X688999Y800263D03*
Y793570D03*
X696441Y816995D03*
Y810302D03*
X689888Y820341D03*
X688999Y813648D03*
Y806955D03*
X696441Y833727D03*
Y827034D03*
X688999Y830381D03*
X696441Y840420D03*
X688999Y843766D03*
Y837074D03*
X709999Y770144D03*
X705141Y766798D03*
X709999Y783530D03*
Y776837D03*
X705141Y773491D03*
Y780184D03*
X709999Y800263D03*
Y793570D03*
X705141Y803609D03*
Y796916D03*
Y790223D03*
X709999Y820341D03*
Y813648D03*
Y806955D03*
X705141Y816995D03*
Y810302D03*
X709999Y830381D03*
X705141Y833727D03*
Y827034D03*
X709999Y843766D03*
Y837074D03*
X705141Y840420D03*
X726141Y766798D03*
X718699Y770144D03*
X726141Y773491D03*
Y780184D03*
X718699Y783530D03*
Y776837D03*
X726141Y803609D03*
Y796916D03*
Y790223D03*
X718699Y800263D03*
Y793570D03*
X726141Y816995D03*
Y810302D03*
X718699Y820341D03*
Y813648D03*
Y806955D03*
X726141Y833727D03*
Y827034D03*
X718699Y830381D03*
X726141Y847113D03*
Y840420D03*
X718699Y850459D03*
Y843766D03*
Y837074D03*
X726141Y863845D03*
Y853806D03*
X718699Y867192D03*
Y857152D03*
X726141Y883924D03*
Y877231D03*
Y870538D03*
X718699Y880577D03*
Y873885D03*
X726141Y900656D03*
Y890617D03*
X718699Y893963D03*
Y887270D03*
X726141Y914042D03*
Y907349D03*
X718699Y917389D03*
Y910696D03*
Y904003D03*
X726141Y927428D03*
Y920735D03*
X718699Y930774D03*
Y924081D03*
X726141Y944160D03*
Y937467D03*
X718699Y947507D03*
Y940814D03*
X726141Y960892D03*
Y950853D03*
X718699Y964239D03*
Y954200D03*
X726141Y980971D03*
Y974278D03*
Y967585D03*
X718699Y977625D03*
Y970932D03*
X726141Y987664D03*
X718699Y991011D03*
Y984318D03*
X726141Y1027822D03*
Y1017782D03*
X718699Y1031168D03*
Y1024475D03*
Y1017782D03*
X726141Y1047900D03*
Y1041207D03*
Y1034515D03*
X718699Y1044554D03*
Y1037861D03*
X726141Y1061286D03*
Y1054593D03*
X718699Y1057940D03*
Y1051247D03*
X726141Y1074672D03*
Y1067979D03*
X718699Y1078018D03*
Y1071326D03*
Y1064633D03*
X726141Y1091404D03*
Y1084711D03*
X718699Y1094751D03*
Y1088058D03*
X726141Y1111483D03*
Y1104790D03*
Y1098097D03*
X718699Y1108137D03*
Y1101444D03*
X726141Y1128215D03*
Y1121522D03*
X718699Y1124869D03*
Y1114829D03*
X726141Y1141601D03*
Y1134908D03*
X718699Y1144948D03*
Y1138255D03*
Y1131562D03*
X726141Y1158333D03*
Y1148294D03*
X718699Y1161680D03*
Y1151641D03*
X726141Y1171719D03*
Y1165026D03*
X718699Y1175066D03*
Y1168373D03*
X726141Y1185105D03*
Y1178412D03*
X718699Y1188452D03*
Y1181759D03*
X726141Y1208530D03*
Y1201837D03*
Y1195144D03*
X718699Y1205184D03*
Y1198491D03*
X726141Y1221916D03*
Y1215223D03*
X718699Y1225263D03*
Y1218570D03*
Y1211877D03*
X726141Y1238648D03*
Y1231955D03*
X718699Y1241995D03*
Y1235302D03*
X726141Y1245341D03*
X719046Y1257064D03*
X718699Y1248688D03*
X726141Y1262074D03*
X726107Y1265420D03*
X739699Y770144D03*
X734841Y766798D03*
X739699Y783530D03*
Y776837D03*
X734841Y773491D03*
Y780184D03*
X739699Y800263D03*
Y793570D03*
X734841Y803609D03*
Y796916D03*
Y790223D03*
X739699Y820341D03*
Y813648D03*
Y806955D03*
X734841Y816995D03*
Y810302D03*
X739699Y830381D03*
X734841Y833727D03*
Y827034D03*
X739699Y850459D03*
Y843766D03*
Y837074D03*
X734841Y847113D03*
Y840420D03*
X739699Y867192D03*
Y857152D03*
X734841Y863845D03*
Y853806D03*
X739699Y880577D03*
Y873885D03*
X734841Y883924D03*
Y877231D03*
Y870538D03*
X739699Y893963D03*
Y887270D03*
X734841Y900656D03*
Y890617D03*
X739699Y917389D03*
Y910696D03*
Y904003D03*
X734841Y914042D03*
Y907349D03*
X739699Y930774D03*
Y924081D03*
X734841Y927428D03*
Y920735D03*
X739699Y947507D03*
Y940814D03*
X734841Y944160D03*
Y937467D03*
X739699Y964239D03*
Y954200D03*
X734841Y960892D03*
Y950853D03*
X739699Y977625D03*
Y970932D03*
X734841Y980971D03*
Y974278D03*
Y967585D03*
X739699Y991011D03*
Y984318D03*
X734841Y987664D03*
X739699Y1031168D03*
Y1024475D03*
Y1017782D03*
X734841Y1027822D03*
Y1017782D03*
X739699Y1044554D03*
Y1037861D03*
X734841Y1047900D03*
Y1041207D03*
Y1034515D03*
X739699Y1057940D03*
Y1051247D03*
X734841Y1061286D03*
Y1054593D03*
X739699Y1078018D03*
Y1071326D03*
Y1064633D03*
X734841Y1074672D03*
Y1067979D03*
X739699Y1094751D03*
Y1088058D03*
X734841Y1091404D03*
Y1084711D03*
X739699Y1108137D03*
Y1101444D03*
X734841Y1111483D03*
Y1104790D03*
Y1098097D03*
X739699Y1124869D03*
Y1114829D03*
X734841Y1128215D03*
Y1121522D03*
X739699Y1144948D03*
Y1138255D03*
Y1131562D03*
X734841Y1141601D03*
Y1134908D03*
X739699Y1161680D03*
Y1151641D03*
X734841Y1158333D03*
Y1148294D03*
X739699Y1175066D03*
Y1168373D03*
X734841Y1171719D03*
Y1165026D03*
X739699Y1188452D03*
Y1181759D03*
X734841Y1185105D03*
Y1178412D03*
X739699Y1205184D03*
Y1198491D03*
X734841Y1208530D03*
Y1201837D03*
Y1195144D03*
X739699Y1225263D03*
Y1218570D03*
Y1211877D03*
X734841Y1221916D03*
Y1215223D03*
X739699Y1241995D03*
Y1235302D03*
X734841Y1238648D03*
Y1231955D03*
X739699Y1248688D03*
X734841Y1245341D03*
X739697Y1265420D03*
X755841Y766798D03*
X748399Y770144D03*
X755841Y780184D03*
Y773491D03*
X748399Y783530D03*
Y776837D03*
X755841Y803609D03*
Y796916D03*
Y790223D03*
X748399Y800263D03*
Y793570D03*
X755841Y816995D03*
Y810302D03*
X748399Y820341D03*
Y813648D03*
Y806955D03*
X755841Y833727D03*
Y827034D03*
X748399Y830381D03*
X755841Y847113D03*
Y840420D03*
X748399Y850459D03*
Y843766D03*
Y837074D03*
X755841Y863845D03*
Y853806D03*
X748399Y867192D03*
Y857152D03*
X755841Y883924D03*
Y877231D03*
Y870538D03*
X748399Y880577D03*
Y873885D03*
X755841Y900656D03*
Y890617D03*
X748399Y893963D03*
Y887270D03*
X755841Y914042D03*
Y907349D03*
X748399Y917389D03*
Y910696D03*
Y904003D03*
X755841Y927428D03*
Y920735D03*
X748399Y930774D03*
Y924081D03*
X755841Y944160D03*
Y937467D03*
X748399Y947507D03*
Y940814D03*
X755841Y960892D03*
Y950853D03*
X748399Y964239D03*
Y954200D03*
X755841Y980971D03*
Y974278D03*
Y967585D03*
X748399Y977625D03*
Y970932D03*
X755841Y987664D03*
X748399Y991011D03*
Y984318D03*
X755841Y1027822D03*
Y1017782D03*
X748399Y1031168D03*
Y1024475D03*
Y1017782D03*
X755841Y1047900D03*
Y1041207D03*
Y1034515D03*
X748399Y1044554D03*
Y1037861D03*
X755841Y1054593D03*
Y1061286D03*
X748399Y1057940D03*
X755841Y1067979D03*
Y1074672D03*
X748399Y1078018D03*
Y1071326D03*
Y1064633D03*
X755841Y1084711D03*
Y1091404D03*
X748399Y1094751D03*
Y1088058D03*
X755841Y1111483D03*
Y1104790D03*
Y1098097D03*
X748399Y1108137D03*
Y1101444D03*
X755841Y1128215D03*
Y1121522D03*
X748399Y1124869D03*
Y1114829D03*
X755841Y1141601D03*
Y1134908D03*
X748399Y1144948D03*
Y1138255D03*
Y1131562D03*
X755841Y1158333D03*
Y1148294D03*
X748399Y1161680D03*
Y1151641D03*
X755841Y1171719D03*
Y1165026D03*
X748399Y1175066D03*
Y1168373D03*
X755841Y1185105D03*
Y1178412D03*
X748399Y1188452D03*
Y1181759D03*
X755841Y1208530D03*
Y1201837D03*
Y1195144D03*
X748399Y1205184D03*
Y1198491D03*
X755841Y1221916D03*
Y1215223D03*
X748399Y1225263D03*
Y1218570D03*
Y1211877D03*
X755841Y1238648D03*
Y1231955D03*
X748399Y1241995D03*
Y1235302D03*
X755841Y1245341D03*
X748283Y1256964D03*
X748399Y1248688D03*
X755841Y1262074D03*
X755797Y1265420D03*
X769399Y770144D03*
X778099D03*
X764541Y766798D03*
X769399Y783530D03*
X778099D03*
X769399Y776837D03*
X778099D03*
X764541Y780184D03*
Y773491D03*
X769399Y800263D03*
X778099D03*
X769399Y793570D03*
X778099D03*
X764541Y803609D03*
Y796916D03*
Y790223D03*
X769399Y820341D03*
X778099D03*
X769399Y813648D03*
X778099D03*
X769399Y806955D03*
X778099D03*
X764541Y816995D03*
Y810302D03*
X769399Y830381D03*
X778099D03*
X764541Y833727D03*
Y827034D03*
X769399Y850459D03*
X778099D03*
Y843766D03*
X769399D03*
Y837074D03*
X778099D03*
X764541Y847113D03*
Y840420D03*
X778099Y867192D03*
X769399D03*
Y857152D03*
X778099D03*
X764541Y863845D03*
Y853806D03*
X769399Y880577D03*
X778099D03*
X769399Y873885D03*
X778099D03*
X764541Y883924D03*
Y877231D03*
Y870538D03*
X778099Y893963D03*
X769399D03*
Y887270D03*
X778099D03*
X764541Y900656D03*
Y890617D03*
X769399Y917389D03*
X778099D03*
X769399Y910696D03*
X778099D03*
X769399Y904003D03*
X778099D03*
X764541Y914042D03*
Y907349D03*
X769399Y930774D03*
X778099D03*
X769399Y924081D03*
X778099D03*
X764541Y927428D03*
Y920735D03*
X769399Y947507D03*
X778099D03*
X769399Y940814D03*
X778099D03*
X764541Y944160D03*
Y937467D03*
X769399Y964239D03*
X778099D03*
X769399Y954200D03*
X778099D03*
X764541Y960892D03*
Y950853D03*
X769399Y977625D03*
X778099D03*
X769399Y970932D03*
X778099D03*
X764541Y980971D03*
Y974278D03*
Y967585D03*
X769399Y991011D03*
X778099D03*
X769399Y984318D03*
X778099D03*
X764541Y987664D03*
X769399Y1031168D03*
X778099D03*
X769399Y1024475D03*
X778099D03*
X769399Y1017782D03*
X778099D03*
X764541Y1027822D03*
Y1017782D03*
X778099Y1044554D03*
X769399D03*
Y1037861D03*
X778099D03*
X764541Y1047900D03*
Y1041207D03*
Y1034515D03*
X769399Y1057940D03*
X778099D03*
X769399Y1051247D03*
X778099D03*
X764541Y1054593D03*
Y1061286D03*
X778099Y1078018D03*
X769399D03*
X778099Y1071326D03*
X769399D03*
Y1064633D03*
X778099D03*
X764541Y1067979D03*
Y1074672D03*
X778099Y1094751D03*
X769399D03*
X778099Y1088058D03*
X769399D03*
X764541Y1084711D03*
Y1091404D03*
X778099Y1108137D03*
X769399D03*
X778099Y1101444D03*
X769399D03*
X764541Y1111483D03*
Y1104790D03*
Y1098097D03*
X778099Y1124869D03*
X769399D03*
X778099Y1114829D03*
X769399D03*
X764541Y1128215D03*
Y1121522D03*
X778099Y1144948D03*
X769399D03*
X778099Y1138255D03*
X769399D03*
X778099Y1131562D03*
X769399D03*
X764541Y1141601D03*
Y1134908D03*
X778099Y1161680D03*
X769399D03*
X778099Y1151641D03*
X769399D03*
X764541Y1158333D03*
Y1148294D03*
X778099Y1175066D03*
X769399D03*
X778099Y1168373D03*
X769399D03*
X764541Y1171719D03*
Y1165026D03*
X778099Y1188452D03*
X769399D03*
X778099Y1181759D03*
X769399D03*
X764541Y1185105D03*
Y1178412D03*
X769399Y1205184D03*
X778099D03*
Y1198491D03*
X769399D03*
X764541Y1208530D03*
Y1201837D03*
Y1195144D03*
X778099Y1225263D03*
X769399D03*
X778099Y1218570D03*
X769399D03*
Y1211877D03*
X778099D03*
X764541Y1221916D03*
Y1215223D03*
X778099Y1241995D03*
X769399D03*
X778099Y1235302D03*
X769399D03*
X764541Y1238648D03*
Y1231955D03*
X778346Y1257264D03*
X778099Y1248688D03*
X769399D03*
X764541Y1245341D03*
X769399Y1265420D03*
X785541Y766798D03*
X794241D03*
X785541Y773491D03*
X794241D03*
X785541Y780184D03*
X794241D03*
X785541Y803609D03*
X794241D03*
X785541Y790223D03*
X794241D03*
X785541Y796916D03*
X794241D03*
X785541Y816995D03*
X794241D03*
X785541Y810302D03*
X794241D03*
X785541Y833727D03*
X794241D03*
X785541Y827034D03*
X794241D03*
X785541Y840420D03*
X794241D03*
X785541Y847113D03*
X794241D03*
X785541Y853806D03*
X794241D03*
X785541Y863845D03*
X794241D03*
X785541Y883924D03*
X794241D03*
X785541Y870538D03*
X794241D03*
X785541Y877231D03*
X794241D03*
X785541Y900656D03*
X794241D03*
X785541Y890617D03*
X794241D03*
X785541Y907349D03*
X794241D03*
X785541Y914042D03*
X794241D03*
X785541Y920735D03*
X794241D03*
X785541Y927428D03*
X794241D03*
X785541Y937467D03*
X794241D03*
X785541Y944160D03*
X794241D03*
X785541Y960892D03*
X794241D03*
X785541Y950853D03*
X794241D03*
X785541Y980971D03*
X794241D03*
X785541Y974278D03*
X794241D03*
X785541Y967585D03*
X794241D03*
X785541Y987664D03*
X794241D03*
X785541Y1027822D03*
X794241D03*
X785541Y1017782D03*
X794241D03*
X785541Y1047900D03*
X794241D03*
X785541Y1041207D03*
X794241D03*
X785541Y1034515D03*
X794241D03*
X785541Y1054593D03*
X794241D03*
X785541Y1061286D03*
X794241D03*
X785541Y1074672D03*
X794241D03*
X785541Y1067979D03*
X794241D03*
X785541Y1091404D03*
X794241D03*
X785541Y1084711D03*
X794241D03*
X785541Y1111483D03*
X794241D03*
X785541Y1104790D03*
X794241D03*
X785541Y1098097D03*
X794241D03*
X785541Y1128215D03*
X794241D03*
X785541Y1121522D03*
X794241D03*
X785541Y1141601D03*
X794241D03*
X785541Y1134908D03*
X794241D03*
X785541Y1158333D03*
X794241D03*
X785541Y1148294D03*
X794241D03*
X785541Y1171719D03*
X794241D03*
X785541Y1165026D03*
X794241D03*
X785541Y1178412D03*
X794241D03*
X785541Y1185105D03*
X794241D03*
X785541Y1208530D03*
X794241D03*
X785541Y1195144D03*
X794241D03*
X785541Y1201837D03*
X794241D03*
X785541Y1221916D03*
X794241D03*
X785541Y1215223D03*
X794241D03*
X785541Y1238648D03*
X794241D03*
X785541Y1231955D03*
X794241D03*
X785541Y1245341D03*
X794241D03*
X785541Y1265420D03*
Y1262074D03*
X799099Y770144D03*
X807799D03*
X799099Y783530D03*
X807799D03*
X799099Y776837D03*
X807799D03*
X799099Y800263D03*
X807799D03*
X799099Y793570D03*
X807799D03*
X799099Y820341D03*
X807799D03*
X799099Y806955D03*
X807799D03*
X799099Y813648D03*
X807799D03*
X799099Y830381D03*
X807799D03*
X799099Y850459D03*
X807799D03*
X799099Y837074D03*
X807799D03*
X799099Y843766D03*
X807799D03*
X799099Y867192D03*
X807799D03*
X799099Y857152D03*
X807799D03*
X799099Y873885D03*
X807799D03*
X799099Y880577D03*
X807799D03*
X799099Y887270D03*
X807799D03*
X799099Y893963D03*
X807799D03*
X799099Y917389D03*
X807799D03*
X799099Y904003D03*
X807799D03*
X799099Y910696D03*
X807799D03*
X799099Y930774D03*
X807799D03*
X799099Y924081D03*
X807799D03*
X799099Y947507D03*
X807799D03*
X799099Y940814D03*
X807799D03*
X799099Y964239D03*
X807799D03*
X799099Y954200D03*
X807799D03*
X799099Y970932D03*
X807799D03*
X799099Y977625D03*
X807799D03*
X799099Y991011D03*
X807799D03*
X799099Y984318D03*
X807799D03*
X799099Y1031168D03*
X807799D03*
X799099Y1024475D03*
X807799D03*
X799099Y1017782D03*
X807799D03*
X799099Y1037861D03*
X807799D03*
X799099Y1044554D03*
X807799D03*
X799099Y1057940D03*
X807799D03*
X799099Y1051247D03*
X807799D03*
X799099Y1078018D03*
X807799D03*
X799099Y1071326D03*
X807799D03*
X799099Y1064633D03*
X807799D03*
X799099Y1094751D03*
X807799D03*
X799099Y1088058D03*
X807799D03*
X799099Y1108137D03*
X807799D03*
X799099Y1101444D03*
X807799D03*
X799099Y1124869D03*
X807799D03*
X799099Y1114829D03*
X807799D03*
X799099Y1144948D03*
X807799D03*
X799099Y1138255D03*
X807799D03*
X799099Y1131562D03*
X807799D03*
X799099Y1161680D03*
X807799D03*
X799099Y1151641D03*
X807799D03*
X799099Y1175066D03*
X807799D03*
X799099Y1168373D03*
X807799D03*
X799099Y1188452D03*
X807799D03*
X799099Y1181759D03*
X807799D03*
X799099Y1205184D03*
X807799D03*
X799099Y1198491D03*
X807799D03*
X799099Y1225263D03*
X807799D03*
X799099Y1211877D03*
X807799D03*
X799099Y1218570D03*
X807799D03*
X799099Y1241995D03*
X807799D03*
X799099Y1235302D03*
X807799D03*
X799099Y1248688D03*
X807799D03*
X808046Y1257664D03*
X799099Y1265420D03*
X815241Y766798D03*
X823941D03*
X815241Y773491D03*
X823941D03*
X815241Y780184D03*
X823941D03*
X815241Y803609D03*
X823941D03*
X815241Y790223D03*
X823941D03*
X815241Y796916D03*
X823941D03*
X815241Y816995D03*
X823941D03*
X815241Y810302D03*
X823941D03*
X815241Y833727D03*
X823941D03*
X815241Y827034D03*
X823941D03*
X815241Y840420D03*
X823941D03*
X815241Y847113D03*
X823941D03*
X815241Y853806D03*
X823941D03*
X815241Y863845D03*
X823941D03*
X815241Y883924D03*
X823941D03*
X815241Y870538D03*
X823941D03*
X815241Y877231D03*
X823941D03*
X815241Y900656D03*
X823941D03*
X815241Y890617D03*
X823941D03*
X815241Y907349D03*
X823941D03*
X815241Y914042D03*
X823941D03*
X815241Y920735D03*
X823941D03*
X815241Y927428D03*
X823941D03*
X815241Y937467D03*
X823941D03*
X815241Y944160D03*
X823941D03*
X815241Y960892D03*
X823941D03*
X815241Y950853D03*
X823941D03*
X815241Y980971D03*
X823941D03*
X815241Y974278D03*
X823941D03*
X815241Y967585D03*
X823941D03*
X815241Y987664D03*
X823941D03*
X815241Y1027822D03*
X823941D03*
X815241Y1017782D03*
X823941D03*
X815241Y1047900D03*
X823941D03*
X815241Y1041207D03*
X823941D03*
X815241Y1034515D03*
X823941D03*
X815241Y1054593D03*
X823941D03*
X815241Y1061286D03*
X823941D03*
X815241Y1074672D03*
X823941D03*
X815241Y1067979D03*
X823941D03*
X815241Y1091404D03*
X823941D03*
X815241Y1084711D03*
X823941D03*
X815241Y1111483D03*
X823941D03*
X815241Y1104790D03*
X823941D03*
X815241Y1098097D03*
X823941D03*
X815241Y1128215D03*
X823941D03*
X815241Y1121522D03*
X823941D03*
X815241Y1141601D03*
X823941D03*
X815241Y1134908D03*
X823941D03*
X815241Y1158333D03*
X823941D03*
X815241Y1148294D03*
X823941D03*
X815241Y1171719D03*
X823941D03*
X815241Y1165026D03*
X823941D03*
X815241Y1178412D03*
X823941D03*
X815241Y1185105D03*
X823941D03*
X815241Y1208530D03*
X823941D03*
X815241Y1195144D03*
X823941D03*
X815241Y1201837D03*
X823941D03*
X815241Y1221916D03*
X823941D03*
X815241Y1215223D03*
X823941D03*
X815241Y1238648D03*
X823941D03*
X815241Y1231955D03*
X823941D03*
X815241Y1245341D03*
X823941D03*
X815241Y1265420D03*
Y1262074D03*
X828799Y770144D03*
X837499D03*
X828799Y783530D03*
X837499D03*
X828799Y776837D03*
X837499D03*
Y800263D03*
X828799D03*
X837499Y793570D03*
X828799D03*
Y820341D03*
X837499D03*
X828799Y813648D03*
X837499D03*
X828799Y806955D03*
X837499D03*
X828799Y830381D03*
X837499D03*
X828799Y850459D03*
X837499D03*
X828799Y843766D03*
X837499D03*
X828799Y837074D03*
X837499D03*
X828799Y867192D03*
X837499D03*
X828799Y857152D03*
X837499D03*
X828799Y880577D03*
X837499D03*
X828799Y873885D03*
X837499D03*
X828799Y893963D03*
X837499D03*
X828799Y887270D03*
X837499D03*
X828799Y917389D03*
X837499D03*
Y904003D03*
X828799D03*
X837499Y910696D03*
X828799D03*
Y930774D03*
X837499D03*
X828799Y924081D03*
X837499D03*
X828799Y947507D03*
X837499D03*
X828799Y940814D03*
X837499D03*
X828799Y964239D03*
X837499D03*
X828799Y954200D03*
X837499D03*
X828799Y977625D03*
X837499D03*
X828799Y970932D03*
X837499D03*
X828799Y991011D03*
X837499D03*
X828799Y984318D03*
X837499D03*
X828799Y1031168D03*
X837499D03*
X828799Y1024475D03*
X837499D03*
X828799Y1017782D03*
X837499D03*
X828799Y1044554D03*
X837499D03*
X828799Y1037861D03*
X837499D03*
X828799Y1057940D03*
X837499D03*
X828799Y1051247D03*
X837499D03*
X828799Y1078018D03*
X837499D03*
X828799Y1071326D03*
X837499D03*
X828799Y1064633D03*
X837499D03*
X828799Y1094751D03*
X837499D03*
Y1088058D03*
X828799D03*
X837499Y1108137D03*
X828799D03*
Y1101444D03*
X837499D03*
Y1124869D03*
X828799D03*
X837499Y1114829D03*
X828799D03*
X837499Y1144948D03*
X828799D03*
X837499Y1138255D03*
X828799D03*
X837499Y1131562D03*
X828799D03*
X837499Y1161680D03*
X828799D03*
X837499Y1151641D03*
X828799D03*
X837499Y1175066D03*
X828799D03*
X837499Y1168373D03*
X828799D03*
Y1188452D03*
X837499D03*
Y1181759D03*
X828799D03*
X837499Y1205184D03*
X828799D03*
X837499Y1198491D03*
X828799D03*
X837499Y1225263D03*
X828799D03*
X837499Y1218570D03*
X828799D03*
X837499Y1211877D03*
X828799D03*
X837499Y1241995D03*
X828799D03*
X837499Y1235302D03*
X828799D03*
X837499Y1248688D03*
X828799D03*
X837846Y1256964D03*
X828799Y1265420D03*
X844941Y766798D03*
X853641D03*
X844941Y780184D03*
X853641D03*
X844941Y773491D03*
X853641D03*
X844941Y803609D03*
X853641D03*
X844941Y796916D03*
X853641D03*
X844941Y790223D03*
X853641D03*
X844941Y816995D03*
X853641D03*
X844941Y810302D03*
X853641D03*
X844941Y833727D03*
X853641D03*
X844941Y827034D03*
X853641D03*
X844941Y847113D03*
X853641D03*
X844941Y840420D03*
X853641D03*
X844941Y863845D03*
X853641D03*
X844941Y853806D03*
X853641D03*
X844941Y883924D03*
X853641D03*
X844941Y877231D03*
X853641D03*
X844941Y870538D03*
X853641D03*
X844941Y900656D03*
X853641D03*
X844941Y890617D03*
X853641D03*
X844941Y914042D03*
X853641D03*
X844941Y907349D03*
X853641D03*
X844941Y927428D03*
X853641D03*
X844941Y920735D03*
X853641D03*
X844941Y944160D03*
X853641D03*
X844941Y937467D03*
X853641D03*
X844941Y960892D03*
X853641D03*
X844941Y950853D03*
X853641D03*
X844941Y980971D03*
X853641D03*
X844941Y974278D03*
X853641D03*
X844941Y967585D03*
X853641D03*
X844941Y987664D03*
X853641D03*
X844941Y1027822D03*
X853641D03*
X844941Y1017782D03*
X853641D03*
X844941Y1047900D03*
X853641D03*
X844941Y1041207D03*
X853641D03*
X844941Y1034515D03*
X853641D03*
X844941Y1061286D03*
X853641D03*
X844941Y1054593D03*
X853641D03*
X844941Y1074672D03*
X853641D03*
X844941Y1067979D03*
X853641D03*
X844941Y1091404D03*
X853641D03*
X844941Y1084711D03*
X853641D03*
X844941Y1111483D03*
X853641D03*
X844941Y1104790D03*
X853641D03*
X844941Y1098097D03*
X853641D03*
X844941Y1128215D03*
X853641D03*
X844941Y1121522D03*
X853641D03*
X844941Y1141601D03*
X853641D03*
X844941Y1134908D03*
X853641D03*
X844941Y1158333D03*
X853641D03*
X844941Y1148294D03*
X853641D03*
X844941Y1171719D03*
X853641D03*
X844941Y1165026D03*
X853641D03*
X844941Y1185105D03*
X853641D03*
X844941Y1178412D03*
X853641D03*
X844941Y1208530D03*
X853641D03*
X844941Y1201837D03*
X853641D03*
X844941Y1195144D03*
X853641D03*
X844941Y1221916D03*
X853641D03*
X844941Y1215223D03*
X853641D03*
X844941Y1238648D03*
X853641D03*
X844941Y1231955D03*
X853641D03*
X844941Y1245341D03*
X853641D03*
X844941Y1265420D03*
Y1262074D03*
X1003841Y770144D03*
Y783530D03*
Y776837D03*
Y800263D03*
Y793570D03*
Y820341D03*
Y813648D03*
Y806955D03*
Y830381D03*
Y850459D03*
Y843766D03*
Y837074D03*
Y867192D03*
Y857152D03*
Y880577D03*
Y873885D03*
Y893963D03*
Y887270D03*
Y917389D03*
Y910696D03*
Y904003D03*
Y930774D03*
Y924081D03*
Y947507D03*
Y940814D03*
Y964239D03*
Y954200D03*
Y977625D03*
Y970932D03*
Y991011D03*
Y984318D03*
Y1031168D03*
Y1024475D03*
Y1017782D03*
Y1044554D03*
Y1037861D03*
Y1057940D03*
Y1051247D03*
Y1078018D03*
Y1071326D03*
Y1064633D03*
Y1094751D03*
Y1088058D03*
Y1108137D03*
Y1101444D03*
Y1124869D03*
Y1114829D03*
Y1144948D03*
Y1138255D03*
Y1131562D03*
Y1161680D03*
Y1151641D03*
Y1175066D03*
Y1168373D03*
Y1188452D03*
Y1181759D03*
Y1205184D03*
Y1198491D03*
Y1225263D03*
Y1218570D03*
Y1211877D03*
Y1241995D03*
Y1235302D03*
Y1248688D03*
Y1265420D03*
X1019983Y766798D03*
X1012541Y770144D03*
X1019983Y780184D03*
Y773491D03*
X1012541Y783530D03*
Y776837D03*
X1019983Y803609D03*
Y796916D03*
Y790223D03*
X1012541Y800263D03*
Y793570D03*
X1019983Y816995D03*
Y810302D03*
X1012541Y820341D03*
Y813648D03*
Y806955D03*
X1019983Y833727D03*
Y827034D03*
X1012541Y830381D03*
X1019983Y847113D03*
Y840420D03*
X1012541Y850459D03*
Y843766D03*
Y837074D03*
X1019983Y863845D03*
Y853806D03*
X1012541Y867192D03*
Y857152D03*
X1019983Y883924D03*
Y877231D03*
Y870538D03*
X1012541Y880577D03*
Y873885D03*
X1019983Y900656D03*
Y890617D03*
X1012541Y893963D03*
Y887270D03*
X1019983Y914042D03*
Y907349D03*
X1012541Y917389D03*
Y910696D03*
Y904003D03*
X1019983Y927428D03*
Y920735D03*
X1012541Y930774D03*
Y924081D03*
X1019983Y944160D03*
Y937467D03*
X1012541Y947507D03*
Y940814D03*
X1019983Y960892D03*
Y950853D03*
X1012541Y964239D03*
Y954200D03*
X1019983Y980971D03*
Y974278D03*
Y967585D03*
X1012541Y977625D03*
Y970932D03*
X1019983Y987664D03*
X1012541Y991011D03*
Y984318D03*
X1019983Y1027822D03*
Y1017782D03*
X1012541Y1031168D03*
Y1024475D03*
Y1017782D03*
X1019983Y1047900D03*
Y1041207D03*
Y1034515D03*
X1012541Y1044554D03*
Y1037861D03*
X1019983Y1061286D03*
Y1054593D03*
X1012541Y1057940D03*
Y1051247D03*
X1019983Y1067979D03*
Y1074672D03*
X1012541Y1078018D03*
Y1071326D03*
Y1064633D03*
X1019983Y1091404D03*
Y1084711D03*
X1012541Y1094751D03*
Y1088058D03*
X1019983Y1111483D03*
Y1104790D03*
Y1098097D03*
X1012541Y1108137D03*
Y1101444D03*
X1019983Y1128215D03*
Y1121522D03*
X1012541Y1124869D03*
Y1114829D03*
X1019983Y1141601D03*
Y1134908D03*
X1012541Y1144948D03*
Y1138255D03*
Y1131562D03*
X1019983Y1158333D03*
Y1148294D03*
X1012541Y1161680D03*
Y1151641D03*
X1019983Y1171719D03*
Y1165026D03*
X1012541Y1175066D03*
Y1168373D03*
X1019983Y1185105D03*
Y1178412D03*
X1012541Y1188452D03*
Y1181759D03*
X1019983Y1208530D03*
Y1201837D03*
Y1195144D03*
X1012541Y1205184D03*
Y1198491D03*
X1019983Y1221916D03*
Y1215223D03*
X1012541Y1225263D03*
Y1218570D03*
Y1211877D03*
X1019983Y1238648D03*
Y1231955D03*
X1012541Y1241995D03*
Y1235302D03*
X1019983Y1245341D03*
X1012541Y1248688D03*
X1019983Y1262074D03*
Y1265420D03*
X1033541Y770144D03*
X1028683Y766798D03*
X1033541Y783530D03*
Y776837D03*
X1028683Y780184D03*
Y773491D03*
X1033541Y800263D03*
Y793570D03*
X1028683Y803609D03*
Y796916D03*
Y790223D03*
X1033541Y820341D03*
Y813648D03*
Y806955D03*
X1028683Y816995D03*
Y810302D03*
X1033541Y830381D03*
X1028683Y833727D03*
Y827034D03*
X1033541Y850459D03*
Y843766D03*
Y837074D03*
X1028683Y847113D03*
Y840420D03*
X1033541Y867192D03*
Y857152D03*
X1028683Y863845D03*
Y853806D03*
X1033541Y880577D03*
Y873885D03*
X1028683Y883924D03*
Y877231D03*
Y870538D03*
X1033541Y893963D03*
Y887270D03*
X1028683Y900656D03*
Y890617D03*
X1033541Y917389D03*
Y910696D03*
Y904003D03*
X1028683Y914042D03*
Y907349D03*
X1033541Y930774D03*
Y924081D03*
X1028683Y927428D03*
Y920735D03*
X1033541Y947507D03*
Y940814D03*
X1028683Y944160D03*
Y937467D03*
X1033541Y964239D03*
Y954200D03*
X1028683Y960892D03*
Y950853D03*
X1033541Y977625D03*
Y970932D03*
X1028683Y980971D03*
Y974278D03*
Y967585D03*
X1033541Y991011D03*
Y984318D03*
X1028683Y987664D03*
X1033541Y1031168D03*
Y1017782D03*
Y1024475D03*
X1028683Y1027822D03*
Y1017782D03*
X1033541Y1044554D03*
Y1037861D03*
X1028683Y1047900D03*
Y1041207D03*
Y1034515D03*
X1033541Y1057940D03*
Y1051247D03*
X1028683Y1061286D03*
Y1054593D03*
X1033541Y1078018D03*
Y1071326D03*
Y1064633D03*
X1028683Y1067979D03*
Y1074672D03*
X1033541Y1094751D03*
Y1088058D03*
X1028683Y1091404D03*
Y1084711D03*
X1033541Y1108137D03*
Y1101444D03*
X1028683Y1111483D03*
Y1104790D03*
Y1098097D03*
X1033541Y1114829D03*
Y1124869D03*
X1028683Y1128215D03*
Y1121522D03*
X1033541Y1144948D03*
Y1138255D03*
Y1131562D03*
X1028683Y1141601D03*
Y1134908D03*
X1033541Y1161680D03*
Y1151641D03*
X1028683Y1158333D03*
Y1148294D03*
X1033541Y1175066D03*
Y1168373D03*
X1028683Y1171719D03*
Y1165026D03*
X1033541Y1188452D03*
Y1181759D03*
X1028683Y1185105D03*
Y1178412D03*
X1033541Y1205184D03*
Y1198491D03*
X1028683Y1208530D03*
Y1201837D03*
Y1195144D03*
X1033541Y1225263D03*
Y1218570D03*
Y1211877D03*
X1028683Y1221916D03*
Y1215223D03*
X1033541Y1241995D03*
Y1235302D03*
X1028683Y1238648D03*
Y1231955D03*
X1033541Y1248688D03*
X1028683Y1245341D03*
X1033541Y1265420D03*
X1049683Y766798D03*
X1042241Y770144D03*
X1049683Y780184D03*
Y773491D03*
X1042241Y783530D03*
Y776837D03*
X1049683Y803609D03*
Y796916D03*
Y790223D03*
X1042241Y800263D03*
Y793570D03*
X1049683Y816995D03*
Y810302D03*
X1042241Y820341D03*
Y813648D03*
Y806955D03*
X1049683Y833727D03*
Y827034D03*
X1042241Y830381D03*
X1049683Y847113D03*
Y840420D03*
X1042241Y850459D03*
Y843766D03*
Y837074D03*
X1049683Y863845D03*
Y853806D03*
X1042241Y867192D03*
Y857152D03*
X1049683Y883924D03*
Y877231D03*
Y870538D03*
X1042241Y880577D03*
Y873885D03*
X1049683Y900656D03*
Y890617D03*
X1042241Y893963D03*
Y887270D03*
X1049683Y914042D03*
Y907349D03*
X1042241Y917389D03*
Y910696D03*
Y904003D03*
X1049683Y927428D03*
Y920735D03*
X1042241Y930774D03*
Y924081D03*
X1049683Y944160D03*
Y937467D03*
X1042241Y947507D03*
Y940814D03*
X1049683Y960892D03*
Y950853D03*
X1042241Y964239D03*
Y954200D03*
X1049683Y980971D03*
Y974278D03*
Y967585D03*
X1042241Y977625D03*
Y970932D03*
X1049683Y987664D03*
X1042241Y991011D03*
Y984318D03*
X1049683Y1027822D03*
Y1017782D03*
X1042241Y1031168D03*
Y1017782D03*
Y1024475D03*
X1049683Y1047900D03*
Y1041207D03*
Y1034515D03*
X1042241Y1044554D03*
Y1037861D03*
X1049683Y1061286D03*
Y1054593D03*
X1042241Y1057940D03*
Y1051247D03*
X1049683Y1074672D03*
Y1067979D03*
X1042241Y1078018D03*
Y1071326D03*
Y1064633D03*
X1049683Y1091404D03*
Y1084711D03*
X1042241Y1094751D03*
Y1088058D03*
X1049683Y1111483D03*
Y1104790D03*
Y1098097D03*
X1042241Y1108137D03*
Y1101444D03*
Y1114829D03*
X1049683Y1128215D03*
Y1121522D03*
X1042241Y1124869D03*
X1049683Y1141601D03*
Y1134908D03*
X1042241Y1144948D03*
Y1138255D03*
Y1131562D03*
Y1161680D03*
X1049683Y1158333D03*
Y1148294D03*
X1042241Y1151641D03*
X1049683Y1171719D03*
Y1165026D03*
X1042241Y1175066D03*
Y1168373D03*
X1049683Y1185105D03*
Y1178412D03*
X1042241Y1188452D03*
Y1181759D03*
X1049683Y1208530D03*
Y1201837D03*
Y1195144D03*
X1042241Y1205184D03*
Y1198491D03*
X1049683Y1215223D03*
Y1221916D03*
X1042241Y1225263D03*
Y1218570D03*
Y1211877D03*
X1049683Y1238648D03*
Y1231955D03*
X1042241Y1241995D03*
Y1235302D03*
X1049683Y1245341D03*
X1042241Y1248688D03*
X1049683Y1265420D03*
Y1262074D03*
X1063241Y770144D03*
X1058383Y766798D03*
X1063241Y783530D03*
Y776837D03*
X1058383Y780184D03*
Y773491D03*
X1063241Y800263D03*
Y793570D03*
X1058383Y803609D03*
Y796916D03*
Y790223D03*
X1063241Y820341D03*
Y813648D03*
Y806955D03*
X1058383Y816995D03*
Y810302D03*
X1063241Y830381D03*
X1058383Y833727D03*
Y827034D03*
X1063241Y850459D03*
Y843766D03*
Y837074D03*
X1058383Y847113D03*
Y840420D03*
X1063241Y867192D03*
Y857152D03*
X1058383Y863845D03*
Y853806D03*
X1063241Y880577D03*
Y873885D03*
X1058383Y883924D03*
Y877231D03*
Y870538D03*
X1063241Y893963D03*
Y887270D03*
X1058383Y900656D03*
Y890617D03*
X1063241Y917389D03*
Y910696D03*
Y904003D03*
X1058383Y914042D03*
Y907349D03*
X1063241Y930774D03*
Y924081D03*
X1058383Y927428D03*
Y920735D03*
X1063241Y947507D03*
Y940814D03*
X1058383Y944160D03*
Y937467D03*
X1063241Y964239D03*
Y954200D03*
X1058383Y960892D03*
Y950853D03*
X1063241Y977625D03*
Y970932D03*
X1058383Y980971D03*
Y974278D03*
Y967585D03*
X1063241Y991011D03*
Y984318D03*
X1058383Y987664D03*
X1063241Y1031168D03*
Y1024475D03*
Y1017782D03*
X1058383Y1027822D03*
Y1017782D03*
X1063241Y1044554D03*
Y1037861D03*
X1058383Y1047900D03*
Y1041207D03*
Y1034515D03*
X1063241Y1057940D03*
Y1051247D03*
X1058383Y1061286D03*
Y1054593D03*
X1063241Y1078018D03*
Y1071326D03*
Y1064633D03*
X1058383Y1074672D03*
Y1067979D03*
X1063241Y1094751D03*
Y1088058D03*
X1058383Y1091404D03*
Y1084711D03*
X1063241Y1108137D03*
Y1101444D03*
X1058383Y1111483D03*
Y1104790D03*
Y1098097D03*
X1063241Y1124869D03*
Y1114829D03*
X1058383Y1128215D03*
Y1121522D03*
X1063241Y1144948D03*
Y1138255D03*
Y1131562D03*
X1058383Y1141601D03*
Y1134908D03*
X1063241Y1161680D03*
Y1151641D03*
X1058383Y1158333D03*
Y1148294D03*
X1063241Y1175066D03*
Y1168373D03*
X1058383Y1171719D03*
Y1165026D03*
X1063241Y1188452D03*
Y1181759D03*
X1058383Y1185105D03*
Y1178412D03*
X1063241Y1205184D03*
Y1198491D03*
X1058383Y1208530D03*
Y1201837D03*
Y1195144D03*
X1063241Y1225263D03*
Y1218570D03*
Y1211877D03*
X1058383Y1215223D03*
Y1221916D03*
X1063241Y1241995D03*
Y1235302D03*
X1058383Y1238648D03*
Y1231955D03*
X1063241Y1248688D03*
X1058383Y1245341D03*
X1063241Y1265420D03*
X1079383Y766798D03*
X1071941Y770144D03*
X1079383Y780184D03*
Y773491D03*
X1071941Y783530D03*
Y776837D03*
X1079383Y803609D03*
Y796916D03*
Y790223D03*
X1071941Y800263D03*
Y793570D03*
X1079383Y816995D03*
Y810302D03*
X1071941Y820341D03*
Y813648D03*
Y806955D03*
X1079383Y833727D03*
Y827034D03*
X1071941Y830381D03*
X1079383Y847113D03*
Y840420D03*
X1071941Y850459D03*
Y843766D03*
Y837074D03*
X1079383Y863845D03*
Y853806D03*
X1071941Y867192D03*
Y857152D03*
X1079383Y883924D03*
Y877231D03*
Y870538D03*
X1071941Y880577D03*
Y873885D03*
X1079383Y900656D03*
Y890617D03*
X1071941Y893963D03*
Y887270D03*
X1079383Y914042D03*
Y907349D03*
X1071941Y917389D03*
Y910696D03*
Y904003D03*
X1079383Y927428D03*
Y920735D03*
X1071941Y930774D03*
Y924081D03*
X1079383Y944160D03*
Y937467D03*
X1071941Y947507D03*
Y940814D03*
X1079383Y960892D03*
Y950853D03*
X1071941Y964239D03*
Y954200D03*
X1079383Y980971D03*
Y974278D03*
Y967585D03*
X1071941Y977625D03*
Y970932D03*
X1079383Y987664D03*
X1071941Y991011D03*
Y984318D03*
X1079383Y1027822D03*
Y1017782D03*
X1071941Y1031168D03*
Y1024475D03*
Y1017782D03*
X1079383Y1047900D03*
Y1041207D03*
Y1034515D03*
X1071941Y1044554D03*
Y1037861D03*
X1079383Y1061286D03*
Y1054593D03*
X1071941Y1057940D03*
Y1051247D03*
X1079383Y1074672D03*
Y1067979D03*
X1071941Y1078018D03*
Y1071326D03*
Y1064633D03*
X1079383Y1091404D03*
Y1084711D03*
X1071941Y1094751D03*
Y1088058D03*
X1079383Y1111483D03*
Y1104790D03*
Y1098097D03*
X1071941Y1108137D03*
Y1101444D03*
X1079383Y1128215D03*
Y1121522D03*
X1071941Y1124869D03*
Y1114829D03*
X1079383Y1141601D03*
Y1134908D03*
X1071941Y1144948D03*
Y1138255D03*
Y1131562D03*
X1079383Y1158333D03*
Y1148294D03*
X1071941Y1161680D03*
Y1151641D03*
X1079383Y1171719D03*
Y1165026D03*
X1071941Y1175066D03*
Y1168373D03*
X1079383Y1185105D03*
Y1178412D03*
X1071941Y1188452D03*
Y1181759D03*
X1079383Y1208530D03*
Y1201837D03*
Y1195144D03*
X1071941Y1205184D03*
Y1198491D03*
X1079383Y1221916D03*
Y1215223D03*
X1071941Y1225263D03*
Y1218570D03*
Y1211877D03*
X1079383Y1238648D03*
Y1231955D03*
X1071941Y1241995D03*
Y1235302D03*
X1079383Y1245341D03*
X1071941Y1248688D03*
X1079383Y1265420D03*
Y1262074D03*
X1092941Y770144D03*
X1101641D03*
X1088083Y766798D03*
X1092941Y783530D03*
X1101641D03*
X1092941Y776837D03*
X1101641D03*
X1088083Y780184D03*
Y773491D03*
X1101641Y800263D03*
X1092941D03*
X1101641Y793570D03*
X1092941D03*
X1088083Y803609D03*
Y796916D03*
Y790223D03*
X1101641Y820341D03*
X1092941D03*
X1101641Y813648D03*
X1092941D03*
X1101641Y806955D03*
X1092941D03*
X1088083Y816995D03*
Y810302D03*
X1101641Y830381D03*
X1092941D03*
X1088083Y833727D03*
Y827034D03*
X1101641Y850459D03*
X1092941D03*
X1101641Y843766D03*
X1092941D03*
X1101641Y837074D03*
X1092941D03*
X1088083Y847113D03*
Y840420D03*
X1101641Y867192D03*
X1092941D03*
X1101641Y857152D03*
X1092941D03*
X1088083Y863845D03*
Y853806D03*
X1101641Y880577D03*
X1092941D03*
X1101641Y873885D03*
X1092941D03*
X1088083Y883924D03*
Y877231D03*
Y870538D03*
X1101641Y893963D03*
X1092941D03*
X1101641Y887270D03*
X1092941D03*
X1088083Y900656D03*
Y890617D03*
X1101641Y917389D03*
X1092941D03*
X1101641Y910696D03*
X1092941D03*
X1101641Y904003D03*
X1092941D03*
X1088083Y914042D03*
Y907349D03*
X1101641Y930774D03*
X1092941D03*
X1101641Y924081D03*
X1092941D03*
X1088083Y927428D03*
Y920735D03*
X1101641Y947507D03*
X1092941D03*
X1101641Y940814D03*
X1092941D03*
X1088083Y944160D03*
Y937467D03*
X1101641Y964239D03*
X1092941D03*
X1101641Y954200D03*
X1092941D03*
X1088083Y960892D03*
Y950853D03*
X1101641Y977625D03*
X1092941D03*
X1101641Y970932D03*
X1092941D03*
X1088083Y980971D03*
Y974278D03*
Y967585D03*
X1101641Y991011D03*
X1092941D03*
X1101641Y984318D03*
X1092941D03*
X1088083Y987664D03*
X1101641Y1031168D03*
X1092941D03*
X1101641Y1024475D03*
X1092941D03*
X1101641Y1017782D03*
X1092941D03*
X1088083Y1027822D03*
Y1017782D03*
X1101641Y1044554D03*
X1092941D03*
X1101641Y1037861D03*
X1092941D03*
X1088083Y1047900D03*
Y1041207D03*
Y1034515D03*
X1101641Y1057940D03*
X1092941D03*
X1101641Y1051247D03*
X1092941D03*
X1088083Y1061286D03*
Y1054593D03*
X1101641Y1078018D03*
X1092941D03*
X1101641Y1071326D03*
X1092941D03*
X1101641Y1064633D03*
X1092941D03*
X1088083Y1074672D03*
Y1067979D03*
X1101641Y1094751D03*
X1092941D03*
X1101641Y1088058D03*
X1092941D03*
X1088083Y1091404D03*
Y1084711D03*
X1101641Y1108137D03*
X1092941D03*
X1101641Y1101444D03*
X1092941D03*
X1088083Y1111483D03*
Y1104790D03*
Y1098097D03*
X1101641Y1124869D03*
X1092941D03*
X1101641Y1114829D03*
X1092941D03*
X1088083Y1128215D03*
Y1121522D03*
X1101641Y1144948D03*
X1092941D03*
X1101641Y1138255D03*
X1092941D03*
X1101641Y1131562D03*
X1092941D03*
X1088083Y1141601D03*
Y1134908D03*
X1092941Y1161680D03*
X1101641D03*
Y1151641D03*
X1092941D03*
X1088083Y1158333D03*
Y1148294D03*
X1101641Y1175066D03*
X1092941D03*
X1101641Y1168373D03*
X1092941D03*
X1088083Y1171719D03*
Y1165026D03*
X1101641Y1181759D03*
X1092941D03*
Y1188452D03*
X1101641D03*
X1088083Y1185105D03*
Y1178412D03*
X1092941Y1205184D03*
X1101641D03*
X1092941Y1198491D03*
X1101641D03*
X1088083Y1208530D03*
Y1201837D03*
Y1195144D03*
X1101641Y1225263D03*
X1092941D03*
X1101641Y1218570D03*
X1092941D03*
Y1211877D03*
X1101641D03*
X1088083Y1221916D03*
Y1215223D03*
X1101641Y1241995D03*
X1092941D03*
X1101641Y1235302D03*
X1092941D03*
X1088083Y1238648D03*
Y1231955D03*
X1101641Y1248688D03*
X1092941D03*
X1088083Y1245341D03*
X1092941Y1265420D03*
X1109083Y766798D03*
X1117783D03*
Y780184D03*
X1109083D03*
X1117783Y773491D03*
X1109083D03*
X1117783Y803609D03*
X1109083D03*
X1117783Y796916D03*
X1109083D03*
Y790223D03*
X1117783D03*
Y816995D03*
X1109083D03*
X1117783Y810302D03*
X1109083D03*
X1117783Y833727D03*
X1109083D03*
X1117783Y827034D03*
X1109083D03*
X1117783Y847113D03*
X1109083D03*
X1117783Y840420D03*
X1109083D03*
X1117783Y863845D03*
X1109083D03*
X1117783Y853806D03*
X1109083D03*
X1117783Y883924D03*
X1109083D03*
X1117783Y877231D03*
X1109083D03*
X1117783Y870538D03*
X1109083D03*
X1117783Y900656D03*
X1109083D03*
X1117783Y890617D03*
X1109083D03*
X1117783Y914042D03*
X1109083D03*
X1117783Y907349D03*
X1109083D03*
X1117783Y927428D03*
X1109083D03*
X1117783Y920735D03*
X1109083D03*
X1117783Y944160D03*
X1109083D03*
X1117783Y937467D03*
X1109083D03*
X1117783Y960892D03*
X1109083D03*
X1117783Y950853D03*
X1109083D03*
X1117783Y980971D03*
X1109083D03*
X1117783Y974278D03*
X1109083D03*
X1117783Y967585D03*
X1109083D03*
X1117783Y987664D03*
X1109083D03*
X1117783Y1027822D03*
X1109083D03*
X1117783Y1017782D03*
X1109083D03*
X1117783Y1047900D03*
X1109083D03*
X1117783Y1041207D03*
X1109083D03*
X1117783Y1034515D03*
X1109083D03*
X1117783Y1061286D03*
X1109083D03*
X1117783Y1054593D03*
X1109083D03*
X1117783Y1074672D03*
X1109083D03*
X1117783Y1067979D03*
X1109083D03*
X1117783Y1091404D03*
X1109083D03*
X1117783Y1084711D03*
X1109083D03*
X1117783Y1111483D03*
X1109083D03*
X1117783Y1104790D03*
X1109083D03*
X1117783Y1098097D03*
X1109083D03*
X1117783Y1128215D03*
X1109083D03*
X1117783Y1121522D03*
X1109083D03*
X1117783Y1141601D03*
X1109083D03*
X1117783Y1134908D03*
X1109083D03*
X1117783Y1158333D03*
X1109083D03*
X1117783Y1148294D03*
X1109083D03*
X1117783Y1171719D03*
X1109083D03*
X1117783Y1165026D03*
X1109083D03*
X1117783Y1185105D03*
X1109083D03*
X1117783Y1178412D03*
X1109083D03*
X1117783Y1208530D03*
X1109083D03*
X1117783Y1201837D03*
X1109083D03*
X1117783Y1195144D03*
X1109083D03*
X1117783Y1221916D03*
X1109083D03*
X1117783Y1215223D03*
X1109083D03*
X1117783Y1238648D03*
X1109083D03*
X1117783Y1231955D03*
X1109083D03*
X1117783Y1245341D03*
X1109083D03*
Y1265420D03*
X1109050Y1262972D03*
X1131341Y770144D03*
X1122641D03*
X1131341Y783530D03*
X1122641D03*
X1131341Y776837D03*
X1122641D03*
X1131341Y800263D03*
X1122641D03*
X1131341Y793570D03*
X1122641D03*
X1131341Y820341D03*
X1122641D03*
X1131341Y813648D03*
X1122641D03*
X1131341Y806955D03*
X1122641D03*
X1131341Y830381D03*
X1122641D03*
X1131341Y850459D03*
X1122641D03*
X1131341Y843766D03*
X1122641D03*
X1131341Y837074D03*
X1122641D03*
X1131341Y857152D03*
X1122641D03*
X1152341Y770144D03*
X1147483Y766798D03*
X1138783D03*
X1152341Y783530D03*
Y776837D03*
X1147483Y780184D03*
X1138783D03*
Y773491D03*
X1147483D03*
X1152341Y800263D03*
X1147483Y803609D03*
X1138783D03*
X1152341Y793570D03*
X1147483Y796916D03*
X1138783D03*
X1147483Y790223D03*
X1138783D03*
X1152341Y820341D03*
X1147483Y816995D03*
X1138783D03*
X1152341Y813648D03*
Y806955D03*
X1147483Y810302D03*
X1138783D03*
X1147483Y833727D03*
X1138783D03*
X1152341Y830381D03*
X1147483Y827034D03*
X1138783D03*
X1152341Y850459D03*
Y843766D03*
Y837074D03*
X1147483Y847113D03*
X1138783D03*
X1147483Y840420D03*
X1138783D03*
X1152341Y857152D03*
X1147483Y853806D03*
X1138783D03*
X1168483Y766798D03*
X1161041Y770144D03*
X1168483Y780184D03*
Y773491D03*
X1161041Y783530D03*
Y776837D03*
X1168483Y803609D03*
Y796916D03*
Y790223D03*
X1161041Y800263D03*
Y793570D03*
X1168483Y816995D03*
Y810302D03*
X1161041Y820341D03*
Y813648D03*
Y806955D03*
X1168483Y833727D03*
X1167633Y827034D03*
X1161041Y830381D03*
X1168483Y847113D03*
Y840420D03*
X1161041Y850459D03*
Y843766D03*
Y837074D03*
X1168483Y853806D03*
X1161041Y857152D03*
X1182041Y770144D03*
X1177183Y766798D03*
X1182041Y783530D03*
Y776837D03*
X1177183Y780184D03*
Y773491D03*
X1182041Y800263D03*
Y793570D03*
X1177183Y803609D03*
Y796916D03*
Y790223D03*
X1182041Y813648D03*
Y806955D03*
X1181191Y820341D03*
X1177183Y816995D03*
Y810302D03*
X1181191Y830381D03*
X1177183Y833727D03*
Y827034D03*
X1182041Y850459D03*
Y837074D03*
Y843766D03*
X1177183Y847113D03*
Y840420D03*
X1181191Y857152D03*
X1177183Y853806D03*
X1198183Y766798D03*
X1190741Y770144D03*
X1198183Y780184D03*
Y773491D03*
X1190741Y783530D03*
Y776837D03*
X1198183Y803609D03*
Y796916D03*
Y790223D03*
X1190741Y800263D03*
Y793570D03*
X1197333Y816995D03*
X1198183Y810302D03*
X1190741Y813648D03*
Y806955D03*
X1191591Y820341D03*
X1198183Y833727D03*
X1197333Y827034D03*
X1191591Y830381D03*
X1198183Y847113D03*
Y840420D03*
X1190741Y850459D03*
Y837074D03*
Y843766D03*
X1198183Y853806D03*
X1191591Y857152D03*
X1211741Y770144D03*
X1206883Y766798D03*
X1211741Y783530D03*
Y776837D03*
X1206883Y780184D03*
Y773491D03*
X1211741Y800263D03*
Y793570D03*
X1206883Y803609D03*
Y796916D03*
Y790223D03*
X1210891Y820341D03*
Y813648D03*
X1211741Y806955D03*
X1207148Y817554D03*
X1206883Y810302D03*
X1211741Y830381D03*
X1206883Y833727D03*
X1207733Y827034D03*
X1211741Y850459D03*
Y837074D03*
Y843766D03*
X1206883Y847113D03*
Y840420D03*
X1210891Y857152D03*
X1206883Y853806D03*
X1213983Y1000437D03*
X1216663Y1000395D03*
X1212533Y1002557D03*
X1205033D03*
X1207533D03*
X1210033D03*
X1227883Y766798D03*
X1220441Y770144D03*
X1227883Y780184D03*
Y773491D03*
X1220441Y783530D03*
Y776837D03*
X1227883Y803609D03*
Y796916D03*
Y790223D03*
X1220441Y800263D03*
Y793570D03*
X1227033Y816995D03*
X1227883Y810302D03*
X1221291Y820341D03*
Y813648D03*
X1220441Y806955D03*
X1227883Y833727D03*
X1227033Y827034D03*
X1220441Y830381D03*
X1227883Y847113D03*
Y840420D03*
X1220441Y850459D03*
Y837074D03*
Y843766D03*
X1227033Y853806D03*
X1221291Y857152D03*
X1233703Y999608D03*
X1231023Y999650D03*
X1236583Y766798D03*
Y780184D03*
Y773491D03*
Y803609D03*
Y796916D03*
Y790223D03*
X1237433Y816995D03*
X1236583Y810302D03*
Y833727D03*
X1237433Y827034D03*
X1236583Y847113D03*
Y840420D03*
X1237433Y853806D03*
X1314353Y1118243D03*
X1325085Y176402D03*
X1325020Y873810D03*
X1393826Y956619D03*
X1387826D03*
X1391326D03*
X1385526D03*
X1396286Y985549D03*
X1388506Y985609D03*
X1386206D03*
X1385526Y1014539D03*
X1387826D03*
X1383226D03*
X1396546Y1014469D03*
X1388102Y1028854D03*
X1390602D03*
X1393102D03*
X1395602D03*
X1401326Y956619D03*
X1398826D03*
Y985579D03*
X1399156Y1014469D03*
X1398102Y1028854D03*
X1399453Y1079791D03*
X1443420Y899445D03*
X1429726Y944537D03*
Y939937D03*
Y942237D03*
X1429544Y959298D03*
Y956998D03*
X1437565Y956619D03*
X1434545D03*
X1445045D03*
X1429544Y970798D03*
Y973098D03*
X1437565Y971139D03*
X1434545Y971099D03*
X1429544Y986898D03*
Y984598D03*
X1437565Y985579D03*
X1434545D03*
X1445045D03*
X1429544Y998398D03*
Y1012198D03*
Y1000698D03*
X1437565Y1000079D03*
X1434545D03*
X1445045D03*
X1429544Y1014498D03*
X1437436Y1014509D03*
X1434545Y1014539D03*
X1445036Y1014549D03*
X1439321Y1028854D03*
X1436821D03*
X1434321D03*
X1441821D03*
X1447545Y956619D03*
X1450045Y971099D03*
X1445445D03*
X1447745D03*
X1447545Y985579D03*
Y1000079D03*
X1447345Y1014539D03*
X1601922Y1000198D03*
X1599489Y999665D03*
X1621883Y766798D03*
Y773491D03*
Y780184D03*
Y790223D03*
Y796916D03*
Y803609D03*
X1622916Y816995D03*
X1622986Y810302D03*
X1621883Y827034D03*
Y833727D03*
Y840420D03*
X1616609Y1000735D03*
X1616469Y1003135D03*
X1623539Y1000135D03*
X1620489Y1003135D03*
X1623589Y1002865D03*
X1626741Y770144D03*
X1635441D03*
X1626741Y776837D03*
X1635441D03*
X1626741Y783530D03*
X1635441D03*
X1626741Y793570D03*
X1635441D03*
Y800263D03*
X1626741D03*
X1636341Y820341D03*
X1626741D03*
X1636574Y813648D03*
X1626741D03*
X1635441Y806955D03*
X1626741D03*
X1635441Y830381D03*
X1626741D03*
X1635441Y837074D03*
X1626741D03*
Y843766D03*
X1635441D03*
X1626249Y1002825D03*
X1651583Y766798D03*
X1642883D03*
X1656441Y770144D03*
Y776837D03*
X1642883Y773491D03*
X1651583D03*
X1642883Y780184D03*
X1651583D03*
X1656441Y783530D03*
Y793570D03*
X1642883Y790223D03*
X1651583D03*
X1642883Y796916D03*
X1651583D03*
X1656441Y800263D03*
X1651583Y803609D03*
X1642883D03*
X1656441Y806955D03*
Y813648D03*
Y820341D03*
X1651583Y810302D03*
X1642883D03*
X1652545Y816995D03*
X1641945D03*
X1656441Y830381D03*
X1652767Y827034D03*
X1642018D03*
X1651583Y833727D03*
X1642883D03*
X1656441Y837074D03*
Y843766D03*
X1642883Y840420D03*
X1651583D03*
X1665141Y770144D03*
X1672583Y766798D03*
X1665141Y776837D03*
Y783530D03*
X1672583Y773491D03*
Y780184D03*
X1665141Y793570D03*
Y800263D03*
X1672583Y790223D03*
Y796916D03*
Y803609D03*
X1665141Y806955D03*
Y813648D03*
X1666030Y820341D03*
X1672583Y810302D03*
Y816995D03*
X1665141Y830381D03*
X1672583Y827034D03*
Y833727D03*
X1665141Y837074D03*
Y843766D03*
X1672583Y840420D03*
X1681283Y766798D03*
X1686141Y770144D03*
X1681283Y773491D03*
Y780184D03*
X1686141Y776837D03*
Y783530D03*
X1681283Y790223D03*
Y796916D03*
Y803609D03*
X1686141Y793570D03*
Y800263D03*
X1681283Y810302D03*
Y816995D03*
X1686141Y806955D03*
Y813648D03*
Y820341D03*
X1681283Y827034D03*
Y833727D03*
X1686141Y830381D03*
X1681283Y840420D03*
X1686141Y837074D03*
Y843766D03*
X1694841Y770144D03*
X1702283Y766798D03*
X1694841Y776837D03*
Y783530D03*
X1702283Y773491D03*
Y780184D03*
X1694841Y793570D03*
Y800263D03*
X1702283Y790223D03*
Y796916D03*
Y803609D03*
X1694841Y806955D03*
Y813648D03*
Y820341D03*
X1702283Y810302D03*
Y816995D03*
X1694841Y830381D03*
X1702283Y827034D03*
Y833727D03*
X1694841Y837074D03*
Y843766D03*
Y850459D03*
X1702283Y840420D03*
Y847113D03*
X1694841Y857152D03*
Y867192D03*
X1702283Y853806D03*
Y863845D03*
X1694841Y873885D03*
Y880577D03*
X1702283Y870538D03*
Y877231D03*
Y883924D03*
X1694841Y887270D03*
Y893963D03*
X1702283Y890617D03*
Y900656D03*
X1694841Y904003D03*
Y910696D03*
Y917389D03*
X1702283Y907349D03*
Y914042D03*
X1694841Y924081D03*
Y930774D03*
X1702283Y920735D03*
Y927428D03*
X1694841Y940814D03*
Y947507D03*
X1702283Y937467D03*
Y944160D03*
X1694841Y954200D03*
Y964239D03*
X1702283Y950853D03*
Y960892D03*
X1694841Y970932D03*
Y977625D03*
X1702283Y967585D03*
Y974278D03*
Y980971D03*
X1694841Y984318D03*
Y991011D03*
X1702283Y987664D03*
X1694841Y1017782D03*
Y1024475D03*
Y1031168D03*
X1702283Y1017782D03*
Y1027822D03*
X1694841Y1037861D03*
Y1044554D03*
X1702283Y1034515D03*
Y1041207D03*
Y1047900D03*
X1694841Y1051247D03*
Y1057940D03*
X1702283Y1054593D03*
Y1061286D03*
X1694841Y1064633D03*
Y1071326D03*
Y1078018D03*
X1702283Y1067979D03*
Y1074672D03*
X1694841Y1088058D03*
Y1094751D03*
X1702283Y1084711D03*
Y1091404D03*
X1694841Y1101444D03*
Y1108137D03*
X1702283Y1098097D03*
Y1104790D03*
Y1111483D03*
X1694841Y1114829D03*
Y1124869D03*
X1702283Y1121522D03*
Y1128215D03*
X1694841Y1131562D03*
Y1138255D03*
Y1144948D03*
X1702283Y1134908D03*
Y1141601D03*
X1694841Y1151641D03*
Y1161680D03*
X1702283Y1148294D03*
Y1158333D03*
X1694841Y1168373D03*
Y1175066D03*
X1702283Y1165026D03*
Y1171719D03*
X1694841Y1181759D03*
Y1188452D03*
X1702283Y1178412D03*
Y1185105D03*
X1694841Y1198491D03*
Y1205184D03*
X1702283Y1195144D03*
Y1201837D03*
Y1208530D03*
X1694841Y1211877D03*
Y1218570D03*
Y1225263D03*
X1702283Y1215223D03*
Y1221916D03*
X1710983Y766798D03*
X1715841Y770144D03*
X1710983Y773491D03*
Y780184D03*
X1715841Y783530D03*
Y776837D03*
X1710983Y790223D03*
Y796916D03*
Y803609D03*
X1715841Y793570D03*
Y800263D03*
X1710983Y810302D03*
Y816995D03*
X1715841Y806955D03*
Y813648D03*
Y820341D03*
X1710983Y827034D03*
Y833727D03*
X1715841Y830381D03*
X1710983Y840420D03*
Y847113D03*
X1715841Y837074D03*
Y843766D03*
Y850459D03*
X1710983Y853806D03*
Y863845D03*
X1715841Y857152D03*
Y867192D03*
X1710983Y870538D03*
Y877231D03*
Y883924D03*
X1715841Y873885D03*
Y880577D03*
X1710983Y890617D03*
Y900656D03*
X1715841Y893963D03*
Y887270D03*
X1710983Y907349D03*
Y914042D03*
X1715841Y904003D03*
Y910696D03*
Y917389D03*
X1710983Y920735D03*
Y927428D03*
X1715841Y924081D03*
Y930774D03*
X1710983Y937467D03*
Y944160D03*
X1715841Y940814D03*
Y947507D03*
X1710983Y950853D03*
Y960892D03*
X1715841Y954200D03*
Y964239D03*
X1710983Y967585D03*
Y974278D03*
Y980971D03*
X1715841Y970932D03*
Y977625D03*
X1710983Y987664D03*
X1715841Y984318D03*
Y991011D03*
X1710983Y1017782D03*
Y1027822D03*
X1715841Y1017782D03*
Y1024475D03*
Y1031168D03*
X1710983Y1034515D03*
Y1041207D03*
Y1047900D03*
X1715841Y1037861D03*
Y1044554D03*
X1710983Y1054593D03*
Y1061286D03*
X1715841Y1051247D03*
Y1057940D03*
X1710983Y1067979D03*
Y1074672D03*
X1715841Y1071326D03*
Y1064633D03*
Y1078018D03*
X1710983Y1084711D03*
Y1091404D03*
X1715841Y1088058D03*
Y1094751D03*
X1710983Y1098097D03*
Y1104790D03*
Y1111483D03*
X1715841Y1101444D03*
Y1108137D03*
X1710983Y1121522D03*
Y1128215D03*
X1715841Y1114829D03*
Y1124869D03*
X1710983Y1134908D03*
Y1141601D03*
X1715841Y1131562D03*
Y1138255D03*
Y1144948D03*
X1710983Y1148294D03*
Y1158333D03*
X1715841Y1151641D03*
Y1161680D03*
X1710983Y1165026D03*
Y1171719D03*
X1715841Y1168373D03*
Y1175066D03*
X1710983Y1178412D03*
Y1185105D03*
X1715841Y1181759D03*
Y1188452D03*
X1710983Y1195144D03*
Y1201837D03*
Y1208530D03*
X1715841Y1198491D03*
Y1205184D03*
X1710983Y1215223D03*
Y1221916D03*
X1715841Y1211877D03*
Y1218570D03*
Y1225263D03*
X1731983Y766798D03*
X1724541Y770144D03*
X1731983Y773491D03*
Y780184D03*
X1724541Y783530D03*
Y776837D03*
Y793570D03*
Y800263D03*
X1731983Y790223D03*
Y796916D03*
Y803609D03*
X1724541Y806955D03*
Y813648D03*
Y820341D03*
X1731983Y810302D03*
Y816995D03*
X1724541Y830381D03*
X1731983Y827034D03*
Y833727D03*
X1724541Y837074D03*
Y843766D03*
Y850459D03*
X1731983Y840420D03*
Y847113D03*
X1724541Y857152D03*
Y867192D03*
X1731983Y853806D03*
Y863845D03*
X1724541Y873885D03*
Y880577D03*
X1731983Y870538D03*
Y877231D03*
Y883924D03*
X1724541Y893963D03*
Y887270D03*
X1731983Y890617D03*
Y900656D03*
X1724541Y904003D03*
Y910696D03*
Y917389D03*
X1731983Y907349D03*
Y914042D03*
X1724541Y924081D03*
Y930774D03*
X1731983Y920735D03*
Y927428D03*
X1724541Y940814D03*
Y947507D03*
X1731983Y937467D03*
Y944160D03*
X1724541Y954200D03*
Y964239D03*
X1731983Y950853D03*
Y960892D03*
X1724541Y970932D03*
Y977625D03*
X1731983Y967585D03*
Y974278D03*
Y980971D03*
X1724541Y984318D03*
Y991011D03*
X1731983Y987664D03*
X1724541Y1017782D03*
Y1024475D03*
Y1031168D03*
X1731983Y1017782D03*
Y1027822D03*
X1724541Y1037861D03*
Y1044554D03*
X1731983Y1034515D03*
Y1041207D03*
Y1047900D03*
X1724541Y1057940D03*
X1731983Y1054593D03*
Y1061286D03*
X1724541Y1071326D03*
Y1064633D03*
Y1078018D03*
X1731983Y1074672D03*
Y1067979D03*
X1724541Y1088058D03*
Y1094751D03*
X1731983Y1084711D03*
Y1091404D03*
X1724541Y1101444D03*
Y1108137D03*
X1731983Y1098097D03*
Y1104790D03*
Y1111483D03*
X1724541Y1114829D03*
Y1124869D03*
X1731983Y1121522D03*
Y1128215D03*
X1724541Y1131562D03*
Y1138255D03*
Y1144948D03*
X1731983Y1134908D03*
Y1141601D03*
X1724541Y1151641D03*
Y1161680D03*
X1731983Y1148294D03*
Y1158333D03*
X1724541Y1168373D03*
Y1175066D03*
X1731983Y1165026D03*
Y1171719D03*
X1724541Y1181759D03*
Y1188452D03*
X1731983Y1178412D03*
Y1185105D03*
X1724541Y1198491D03*
Y1205184D03*
X1731983Y1195144D03*
Y1201837D03*
Y1208530D03*
X1724541Y1211877D03*
Y1218570D03*
Y1225263D03*
X1731983Y1215223D03*
Y1221916D03*
X1740683Y766798D03*
Y773491D03*
Y780184D03*
Y790223D03*
Y796916D03*
Y803609D03*
Y810302D03*
Y816995D03*
Y827034D03*
Y833727D03*
Y840420D03*
Y847113D03*
Y853806D03*
Y863845D03*
Y870538D03*
Y877231D03*
Y883924D03*
Y890617D03*
Y900656D03*
Y907349D03*
Y914042D03*
Y920735D03*
Y927428D03*
Y937467D03*
Y944160D03*
Y950853D03*
Y960892D03*
Y967585D03*
Y974278D03*
Y980971D03*
Y987664D03*
Y1017782D03*
Y1027822D03*
Y1034515D03*
Y1041207D03*
Y1047900D03*
Y1054593D03*
Y1061286D03*
Y1074672D03*
Y1067979D03*
Y1084711D03*
Y1091404D03*
Y1098097D03*
Y1104790D03*
Y1111483D03*
Y1121522D03*
Y1128215D03*
Y1134908D03*
Y1141601D03*
Y1148294D03*
Y1158333D03*
Y1165026D03*
Y1171719D03*
Y1178412D03*
Y1185105D03*
Y1195144D03*
Y1201837D03*
Y1208530D03*
Y1215223D03*
Y1221916D03*
G54D54*
X841240Y1420330D03*
X1016240D03*
G54D59*
X986642Y-27947D03*
X986627Y-25432D03*
Y-21558D03*
X986642Y-17918D03*
X986627Y-15403D03*
Y-11529D03*
X986642Y-7889D03*
X986627Y-5374D03*
Y4655D03*
X986642Y2140D03*
X986627Y14684D03*
X986642Y12169D03*
X986627Y8529D03*
X986642Y22698D03*
X989910Y22684D03*
X986627Y19058D03*
Y25213D03*
X989895Y25199D03*
X1296019Y-35472D03*
Y-31598D03*
X1296034Y-37987D03*
Y-27958D03*
X1296019Y-25443D03*
Y-21569D03*
X1296034Y-17929D03*
X1296019Y-15414D03*
Y-11540D03*
X1296034Y-7900D03*
X1296019Y-5385D03*
Y4644D03*
X1296034Y2129D03*
X1296019Y-1511D03*
Y14673D03*
X1296034Y12158D03*
X1296019Y8518D03*
X1296034Y22687D03*
X1296019Y19047D03*
Y25202D03*
X1299302Y22673D03*
X1299287Y25188D03*
X1488393Y-27958D03*
X1488378Y-25443D03*
X1488393Y-37987D03*
X1488378Y-35472D03*
Y-31598D03*
X1488393Y-17929D03*
X1488378Y-15414D03*
Y-11540D03*
Y-21569D03*
X1488393Y2129D03*
X1488378Y4644D03*
X1488393Y-7900D03*
X1488378Y-5385D03*
Y-1511D03*
Y14673D03*
X1488393Y12158D03*
Y22687D03*
X1491661Y22673D03*
X1488378Y8518D03*
Y19047D03*
Y25202D03*
X1491646Y25188D03*
G54D63*
X1879155Y344948D03*
Y592848D03*
X1900275Y-19342D03*
X1889155Y344948D03*
Y592848D03*
X1900275Y716808D03*
X1910275Y-19342D03*
Y716808D03*
X1931395Y592868D03*
X1921395D03*
X1952395Y-19152D03*
X1942395D03*
X1963362Y593010D03*
X1984482Y-19180D03*
X1973362Y593010D03*
X1994482Y-19180D03*
X2015452Y593020D03*
X2005452D03*
X2026452Y-19000D03*
X2036452D03*
X2047419Y593162D03*
X2057419D03*
G54D72*
X1903086Y1318228D03*
X1902402Y1683256D03*
X1950484Y1683497D03*
X1993147Y1682875D03*
G54D70*
X1880836Y1317164D03*
X1881165Y1682207D03*
X1929695Y1683220D03*
X1971555Y1683130D03*
%LPC*%
G75*
G54D73*
G01X-6350Y-464479D02*
Y-539479D01*
X493650D01*
Y-464479D01*
X-6350D01*
G01X5650Y-529479D02*
Y-534479D01*
G01X4193Y-529479D02*
X7107D01*
G01X12017Y-534479D02*
X9483D01*
Y-529479D01*
X12017D01*
G01X11003Y-531896D02*
X9483D01*
G01X14583Y-529479D02*
Y-534479D01*
X17117D01*
G01X20950Y-534646D02*
X20823Y-534562D01*
Y-534396D01*
X20950Y-534312D01*
X21077Y-534396D01*
Y-534562D01*
X20950Y-534646D01*
G01Y-532396D02*
X20823Y-532312D01*
Y-532146D01*
X20950Y-532062D01*
X21077Y-532146D01*
Y-532312D01*
X20950Y-532396D01*
G01X25733Y-536146D02*
X25100Y-535312D01*
X24783Y-534479D01*
Y-531146D01*
X25100Y-530312D01*
X25733Y-529479D01*
G01X31150D02*
X30643Y-529646D01*
X30263Y-530062D01*
X30010Y-530562D01*
X29820Y-531229D01*
X29757Y-531979D01*
X29820Y-532729D01*
X30010Y-533396D01*
X30263Y-533896D01*
X30643Y-534312D01*
X31150Y-534479D01*
X31657Y-534312D01*
X32037Y-533896D01*
X32290Y-533396D01*
X32480Y-532729D01*
X32543Y-531979D01*
X32480Y-531229D01*
X32290Y-530562D01*
X32037Y-530062D01*
X31657Y-529646D01*
X31150Y-529479D01*
G01X34857Y-533479D02*
X35237Y-534062D01*
X35743Y-534396D01*
X36313Y-534479D01*
X36820Y-534396D01*
X37327Y-533979D01*
X37643Y-533479D01*
X37707Y-532979D01*
X37580Y-532396D01*
X37137Y-531979D01*
X36693Y-531812D01*
X36123D01*
G01X36693D02*
X37073Y-531562D01*
X37390Y-531146D01*
X37517Y-530646D01*
X37390Y-530146D01*
X37073Y-529729D01*
X36503Y-529479D01*
X35933Y-529562D01*
X35363Y-529896D01*
G01X41667Y-536146D02*
X42300Y-535312D01*
X42617Y-534479D01*
Y-531146D01*
X42300Y-530312D01*
X41667Y-529479D01*
G01X45057Y-533479D02*
X45437Y-534062D01*
X45943Y-534396D01*
X46513Y-534479D01*
X47020Y-534396D01*
X47527Y-533979D01*
X47843Y-533479D01*
X47907Y-532979D01*
X47780Y-532396D01*
X47337Y-531979D01*
X46893Y-531812D01*
X46323D01*
G01X46893D02*
X47273Y-531562D01*
X47590Y-531146D01*
X47717Y-530646D01*
X47590Y-530146D01*
X47273Y-529729D01*
X46703Y-529479D01*
X46133Y-529562D01*
X45563Y-529896D01*
G01X50347Y-530312D02*
X50727Y-529812D01*
X51170Y-529562D01*
X51677Y-529479D01*
X52310Y-529646D01*
X52753Y-530062D01*
X52880Y-530562D01*
X52817Y-531062D01*
X52563Y-531479D01*
X51297Y-532312D01*
X50727Y-532896D01*
X50347Y-533729D01*
X50220Y-534479D01*
X52880D01*
G01X56523D02*
X56650Y-533396D01*
X56840Y-532479D01*
X57093Y-531646D01*
X57410Y-530729D01*
X57917Y-529479D01*
X55383D01*
G01X60927Y-532812D02*
X62573D01*
G01X65647Y-530312D02*
X66027Y-529812D01*
X66470Y-529562D01*
X66977Y-529479D01*
X67610Y-529646D01*
X68053Y-530062D01*
X68180Y-530562D01*
X68117Y-531062D01*
X67863Y-531479D01*
X66597Y-532312D01*
X66027Y-532896D01*
X65647Y-533729D01*
X65520Y-534479D01*
X68180D01*
G01X70557Y-533479D02*
X70937Y-534062D01*
X71443Y-534396D01*
X72013Y-534479D01*
X72520Y-534396D01*
X73027Y-533979D01*
X73343Y-533479D01*
X73407Y-532979D01*
X73280Y-532396D01*
X72837Y-531979D01*
X72393Y-531812D01*
X71823D01*
G01X72393D02*
X72773Y-531562D01*
X73090Y-531146D01*
X73217Y-530646D01*
X73090Y-530146D01*
X72773Y-529729D01*
X72203Y-529479D01*
X71633Y-529562D01*
X71063Y-529896D01*
G01X77810Y-534479D02*
Y-529479D01*
X75467Y-533062D01*
X78633D01*
G01X80757Y-533729D02*
X81137Y-534146D01*
X81580Y-534396D01*
X82150Y-534479D01*
X82720Y-534312D01*
X83163Y-533979D01*
X83480Y-533396D01*
X83543Y-532729D01*
X83417Y-532062D01*
X83100Y-531646D01*
X82657Y-531312D01*
X82213Y-531229D01*
X81770Y-531312D01*
X81200Y-531646D01*
X81390Y-529479D01*
X83100D01*
G01X91147Y-534479D02*
Y-529479D01*
X93553D01*
G01X92667Y-531896D02*
X91147D01*
G01X95867Y-534479D02*
X97450Y-529479D01*
X99033Y-534479D01*
G01X98463Y-532729D02*
X96437D01*
G01X101220Y-534479D02*
X103880Y-529479D01*
G01X101220D02*
X103880Y-534479D01*
G01X107650Y-534646D02*
X107523Y-534562D01*
Y-534396D01*
X107650Y-534312D01*
X107777Y-534396D01*
Y-534562D01*
X107650Y-534646D01*
G01Y-532396D02*
X107523Y-532312D01*
Y-532146D01*
X107650Y-532062D01*
X107777Y-532146D01*
Y-532312D01*
X107650Y-532396D01*
G01X112433Y-536146D02*
X111800Y-535312D01*
X111483Y-534479D01*
Y-531146D01*
X111800Y-530312D01*
X112433Y-529479D01*
G01X117850D02*
X117343Y-529646D01*
X116963Y-530062D01*
X116710Y-530562D01*
X116520Y-531229D01*
X116457Y-531979D01*
X116520Y-532729D01*
X116710Y-533396D01*
X116963Y-533896D01*
X117343Y-534312D01*
X117850Y-534479D01*
X118357Y-534312D01*
X118737Y-533896D01*
X118990Y-533396D01*
X119180Y-532729D01*
X119243Y-531979D01*
X119180Y-531229D01*
X118990Y-530562D01*
X118737Y-530062D01*
X118357Y-529646D01*
X117850Y-529479D01*
G01X121557Y-533479D02*
X121937Y-534062D01*
X122443Y-534396D01*
X123013Y-534479D01*
X123520Y-534396D01*
X124027Y-533979D01*
X124343Y-533479D01*
X124407Y-532979D01*
X124280Y-532396D01*
X123837Y-531979D01*
X123393Y-531812D01*
X122823D01*
G01X123393D02*
X123773Y-531562D01*
X124090Y-531146D01*
X124217Y-530646D01*
X124090Y-530146D01*
X123773Y-529729D01*
X123203Y-529479D01*
X122633Y-529562D01*
X122063Y-529896D01*
G01X128367Y-536146D02*
X129000Y-535312D01*
X129317Y-534479D01*
Y-531146D01*
X129000Y-530312D01*
X128367Y-529479D01*
G01X131757Y-533479D02*
X132137Y-534062D01*
X132643Y-534396D01*
X133213Y-534479D01*
X133720Y-534396D01*
X134227Y-533979D01*
X134543Y-533479D01*
X134607Y-532979D01*
X134480Y-532396D01*
X134037Y-531979D01*
X133593Y-531812D01*
X133023D01*
G01X133593D02*
X133973Y-531562D01*
X134290Y-531146D01*
X134417Y-530646D01*
X134290Y-530146D01*
X133973Y-529729D01*
X133403Y-529479D01*
X132833Y-529562D01*
X132263Y-529896D01*
G01X137173Y-533896D02*
X137617Y-534312D01*
X138123Y-534479D01*
X138630Y-534312D01*
X139073Y-533812D01*
X139390Y-533062D01*
X139517Y-532312D01*
Y-531396D01*
X139390Y-530646D01*
X139073Y-529979D01*
X138693Y-529646D01*
X138250Y-529479D01*
X137743Y-529646D01*
X137363Y-529979D01*
X137110Y-530479D01*
X136983Y-531146D01*
X137110Y-531729D01*
X137427Y-532312D01*
X137807Y-532646D01*
X138250Y-532729D01*
X138757Y-532562D01*
X139137Y-532146D01*
X139517Y-531396D01*
G01X143223Y-534479D02*
X143350Y-533396D01*
X143540Y-532479D01*
X143793Y-531646D01*
X144110Y-530729D01*
X144617Y-529479D01*
X142083D01*
G01X147627Y-532812D02*
X149273D01*
G01X152157Y-533479D02*
X152537Y-534062D01*
X153043Y-534396D01*
X153613Y-534479D01*
X154120Y-534396D01*
X154627Y-533979D01*
X154943Y-533479D01*
X155007Y-532979D01*
X154880Y-532396D01*
X154437Y-531979D01*
X153993Y-531812D01*
X153423D01*
G01X153993D02*
X154373Y-531562D01*
X154690Y-531146D01*
X154817Y-530646D01*
X154690Y-530146D01*
X154373Y-529729D01*
X153803Y-529479D01*
X153233Y-529562D01*
X152663Y-529896D01*
G01X157447Y-532396D02*
X157890Y-531812D01*
X158270Y-531479D01*
X158777Y-531312D01*
X159220Y-531479D01*
X159537Y-531812D01*
X159790Y-532312D01*
X159853Y-532896D01*
X159790Y-533396D01*
X159537Y-533896D01*
X159157Y-534312D01*
X158713Y-534479D01*
X158207Y-534312D01*
X157763Y-533812D01*
X157510Y-533062D01*
X157447Y-532229D01*
X157573Y-531146D01*
X157763Y-530562D01*
X158080Y-529979D01*
X158523Y-529562D01*
X158967Y-529479D01*
X159410Y-529646D01*
X159727Y-530062D01*
G01X163750Y-534479D02*
Y-529479D01*
X162990Y-530479D01*
G01Y-534479D02*
X164510D01*
G01X169610D02*
Y-529479D01*
X167267Y-533062D01*
X170433D01*
G01X188650Y-464479D02*
Y-539479D01*
G01Y-514479D02*
X291650D01*
Y-489479D01*
G01X188650D02*
X291650D01*
G01Y-464479D02*
Y-539479D01*
G01X293650Y-464479D02*
Y-539479D01*
G01X299157Y-524479D02*
Y-519479D01*
X300423D01*
X300930Y-519729D01*
X301310Y-520062D01*
X301627Y-520562D01*
X301880Y-521146D01*
X301943Y-521979D01*
X301880Y-522812D01*
X301627Y-523396D01*
X301310Y-523896D01*
X300930Y-524229D01*
X300423Y-524479D01*
X299157D01*
G01X304067D02*
X305650Y-519479D01*
X307233Y-524479D01*
G01X306663Y-522729D02*
X304637D01*
G01X310750Y-519479D02*
Y-524479D01*
G01X309293Y-519479D02*
X312207D01*
G01X317117Y-524479D02*
X314583D01*
Y-519479D01*
X317117D01*
G01X316103Y-521896D02*
X314583D01*
G01X320950Y-524646D02*
X320823Y-524562D01*
Y-524396D01*
X320950Y-524312D01*
X321077Y-524396D01*
Y-524562D01*
X320950Y-524646D01*
G01Y-522396D02*
X320823Y-522312D01*
Y-522146D01*
X320950Y-522062D01*
X321077Y-522146D01*
Y-522312D01*
X320950Y-522396D01*
G01X299283Y-499479D02*
Y-494479D01*
X300803D01*
X301310Y-494729D01*
X301690Y-495312D01*
X301817Y-495979D01*
X301690Y-496646D01*
X301373Y-497146D01*
X300803Y-497396D01*
X299283D01*
G01X304510Y-499646D02*
X306790Y-494479D01*
G01X309293Y-499479D02*
Y-494479D01*
X312207Y-499479D01*
Y-494479D01*
G01X315850Y-499646D02*
X315723Y-499562D01*
Y-499396D01*
X315850Y-499312D01*
X315977Y-499396D01*
Y-499562D01*
X315850Y-499646D01*
G01Y-497396D02*
X315723Y-497312D01*
Y-497146D01*
X315850Y-497062D01*
X315977Y-497146D01*
Y-497312D01*
X315850Y-497396D01*
G01X293650Y-514479D02*
X493650D01*
G01X293650Y-489479D02*
X493650D01*
G01X299283Y-474479D02*
Y-469479D01*
X300803D01*
X301310Y-469729D01*
X301690Y-470312D01*
X301817Y-470979D01*
X301690Y-471646D01*
X301373Y-472146D01*
X300803Y-472396D01*
X299283D01*
G01X304383Y-474479D02*
Y-469479D01*
X305967D01*
X306473Y-469729D01*
X306790Y-470062D01*
X306917Y-470729D01*
X306790Y-471396D01*
X306410Y-471812D01*
X305967Y-472062D01*
X304383D01*
G01X305967D02*
X306917Y-474479D01*
G01X310750D02*
X310243Y-474396D01*
X309800Y-474062D01*
X309420Y-473562D01*
X309167Y-472979D01*
X309040Y-472312D01*
Y-471646D01*
X309167Y-470979D01*
X309420Y-470396D01*
X309800Y-469896D01*
X310243Y-469562D01*
X310750Y-469479D01*
X311257Y-469562D01*
X311700Y-469896D01*
X312080Y-470396D01*
X312333Y-470979D01*
X312460Y-471646D01*
Y-472312D01*
X312333Y-472979D01*
X312080Y-473562D01*
X311700Y-474062D01*
X311257Y-474396D01*
X310750Y-474479D01*
G01X314583Y-473479D02*
X314900Y-473979D01*
X315280Y-474312D01*
X315723Y-474479D01*
X316230Y-474312D01*
X316610Y-473979D01*
X316990Y-473479D01*
X317117Y-472812D01*
Y-469479D01*
G01X322217Y-474479D02*
X319683D01*
Y-469479D01*
X322217D01*
G01X321203Y-471896D02*
X319683D01*
G01X327443Y-469896D02*
X327063Y-469646D01*
X326620Y-469479D01*
X326113D01*
X325543Y-469729D01*
X325100Y-470146D01*
X324783Y-470646D01*
X324530Y-471479D01*
X324467Y-472229D01*
X324593Y-472979D01*
X324783Y-473479D01*
X325163Y-473979D01*
X325607Y-474312D01*
X326050Y-474479D01*
X326493D01*
X326937Y-474312D01*
X327317Y-474062D01*
X327633Y-473729D01*
G01X331150Y-469479D02*
Y-474479D01*
G01X329693Y-469479D02*
X332607D01*
G01X336250Y-474646D02*
X336123Y-474562D01*
Y-474396D01*
X336250Y-474312D01*
X336377Y-474396D01*
Y-474562D01*
X336250Y-474646D01*
G01Y-472396D02*
X336123Y-472312D01*
Y-472146D01*
X336250Y-472062D01*
X336377Y-472146D01*
Y-472312D01*
X336250Y-472396D01*
G01X408650Y-514479D02*
Y-539479D01*
G01X411283Y-516979D02*
Y-521979D01*
X413817D01*
G01X416890Y-516979D02*
X418410D01*
G01X417650D02*
Y-521979D01*
G01X416890D02*
X418410D01*
G01X423257Y-519312D02*
X423510Y-519062D01*
X423700Y-518646D01*
X423827Y-518062D01*
X423700Y-517562D01*
X423447Y-517229D01*
X423003Y-516979D01*
X421293D01*
Y-521979D01*
X423383D01*
X423827Y-521646D01*
X424080Y-521146D01*
X424207Y-520562D01*
X424080Y-519979D01*
X423700Y-519479D01*
X423257Y-519312D01*
X421293D01*
G01X427850Y-522146D02*
X427723Y-522062D01*
Y-521896D01*
X427850Y-521812D01*
X427977Y-521896D01*
Y-522062D01*
X427850Y-522146D01*
G01Y-519896D02*
X427723Y-519812D01*
Y-519646D01*
X427850Y-519562D01*
X427977Y-519646D01*
Y-519812D01*
X427850Y-519896D01*
G01X451650Y-514479D02*
Y-539479D01*
G01Y-489479D02*
Y-514479D01*
G01X456663Y-541646D02*
X456770Y-541521D01*
X456850Y-541312D01*
X456903Y-541021D01*
X456850Y-540771D01*
X456743Y-540604D01*
X456557Y-540479D01*
X455837D01*
Y-542979D01*
X456717D01*
X456903Y-542812D01*
X457010Y-542562D01*
X457063Y-542271D01*
X457010Y-541979D01*
X456850Y-541729D01*
X456663Y-541646D01*
X455837D01*
G01X459130Y-542979D02*
Y-541312D01*
G01Y-541604D02*
X459023Y-541437D01*
X458863Y-541354D01*
X458677Y-541312D01*
X458490Y-541396D01*
X458330Y-541562D01*
X458223Y-541812D01*
X458170Y-542146D01*
X458223Y-542479D01*
X458330Y-542729D01*
X458490Y-542896D01*
X458677Y-542979D01*
X458863Y-542937D01*
X459023Y-542812D01*
X459130Y-542646D01*
G01X460450Y-542687D02*
X460583Y-542854D01*
X460770Y-542979D01*
X460930D01*
X461090Y-542896D01*
X461197Y-542771D01*
X461250Y-542604D01*
X461223Y-542354D01*
X461117Y-542229D01*
X460637Y-541979D01*
X460530Y-541687D01*
X460583Y-541479D01*
X460690Y-541354D01*
X460850Y-541312D01*
X461010Y-541354D01*
X461170Y-541479D01*
G01X462650Y-541854D02*
X463503D01*
X463423Y-541562D01*
X463290Y-541396D01*
X463103Y-541312D01*
X462917Y-541354D01*
X462757Y-541479D01*
X462650Y-541771D01*
X462597Y-542021D01*
Y-542271D01*
X462650Y-542521D01*
X462783Y-542771D01*
X462943Y-542937D01*
X463130Y-542979D01*
X463317Y-542896D01*
X463503Y-542646D01*
G01X464770Y-542979D02*
Y-540479D01*
G01Y-541729D02*
X464903Y-541479D01*
X465063Y-541354D01*
X465223Y-541312D01*
X465463Y-541396D01*
X465623Y-541562D01*
X465730Y-541854D01*
Y-542187D01*
X465677Y-542521D01*
X465570Y-542771D01*
X465383Y-542937D01*
X465223Y-542979D01*
X465063Y-542937D01*
X464903Y-542812D01*
X464770Y-542604D01*
G01X467450Y-542979D02*
X467290Y-542937D01*
X467130Y-542771D01*
X467023Y-542479D01*
X466970Y-542146D01*
X467023Y-541812D01*
X467130Y-541521D01*
X467290Y-541354D01*
X467450Y-541312D01*
X467610Y-541354D01*
X467770Y-541521D01*
X467877Y-541812D01*
X467903Y-542146D01*
X467877Y-542479D01*
X467770Y-542771D01*
X467610Y-542937D01*
X467450Y-542979D01*
G01X470130D02*
Y-541312D01*
G01Y-541604D02*
X470023Y-541437D01*
X469863Y-541354D01*
X469677Y-541312D01*
X469490Y-541396D01*
X469330Y-541562D01*
X469223Y-541812D01*
X469170Y-542146D01*
X469223Y-542479D01*
X469330Y-542729D01*
X469490Y-542896D01*
X469677Y-542979D01*
X469863Y-542937D01*
X470023Y-542812D01*
X470130Y-542646D01*
G01X471477Y-542979D02*
Y-541312D01*
G01Y-541646D02*
X471610Y-541479D01*
X471743Y-541354D01*
X471930Y-541312D01*
X472063Y-541354D01*
X472223Y-541479D01*
G01X474530Y-540479D02*
Y-542979D01*
G01Y-542604D02*
X474423Y-542812D01*
X474263Y-542937D01*
X474077Y-542979D01*
X473863Y-542896D01*
X473703Y-542687D01*
X473597Y-542437D01*
X473570Y-542146D01*
X473597Y-541854D01*
X473703Y-541604D01*
X473863Y-541396D01*
X474077Y-541312D01*
X474263Y-541354D01*
X474397Y-541437D01*
X474530Y-541604D01*
G01X477917Y-542979D02*
Y-540479D01*
X478583D01*
X478797Y-540604D01*
X478930Y-540771D01*
X478983Y-541104D01*
X478930Y-541437D01*
X478770Y-541646D01*
X478583Y-541771D01*
X477917D01*
G01X478583D02*
X478983Y-542979D01*
G01X480250Y-541854D02*
X481103D01*
X481023Y-541562D01*
X480890Y-541396D01*
X480703Y-541312D01*
X480517Y-541354D01*
X480357Y-541479D01*
X480250Y-541771D01*
X480197Y-542021D01*
Y-542271D01*
X480250Y-542521D01*
X480383Y-542771D01*
X480543Y-542937D01*
X480730Y-542979D01*
X480917Y-542896D01*
X481103Y-542646D01*
G01X482370Y-541312D02*
X482850Y-542979D01*
X483330Y-541312D01*
G01X485050Y-543062D02*
X484997Y-543021D01*
Y-542937D01*
X485050Y-542896D01*
X485103Y-542937D01*
Y-543021D01*
X485050Y-543062D01*
G01X487250Y-542979D02*
X487437Y-542937D01*
X487650Y-542812D01*
X487783Y-542604D01*
X487837Y-542312D01*
X487783Y-542021D01*
X487623Y-541771D01*
X487383Y-541646D01*
X487117D01*
X486957Y-541562D01*
X486823Y-541354D01*
X486770Y-541062D01*
X486850Y-540771D01*
X487037Y-540562D01*
X487250Y-540479D01*
X487463Y-540562D01*
X487650Y-540771D01*
X487730Y-541062D01*
X487677Y-541354D01*
X487543Y-541562D01*
X487383Y-541646D01*
X487117D01*
X486877Y-541771D01*
X486717Y-542021D01*
X486663Y-542312D01*
X486717Y-542604D01*
X486850Y-542812D01*
X487063Y-542937D01*
X487250Y-542979D01*
G01X489663Y-541646D02*
X489770Y-541521D01*
X489850Y-541312D01*
X489903Y-541021D01*
X489850Y-540771D01*
X489743Y-540604D01*
X489557Y-540479D01*
X488837D01*
Y-542979D01*
X489717D01*
X489903Y-542812D01*
X490010Y-542562D01*
X490063Y-542271D01*
X490010Y-541979D01*
X489850Y-541729D01*
X489663Y-541646D01*
X488837D01*
G01X455550Y-516979D02*
Y-521979D01*
G01X454093Y-516979D02*
X457007D01*
G01X460650Y-521979D02*
X460270Y-521896D01*
X459890Y-521562D01*
X459637Y-520979D01*
X459510Y-520312D01*
X459637Y-519646D01*
X459890Y-519062D01*
X460270Y-518729D01*
X460650Y-518646D01*
X461030Y-518729D01*
X461410Y-519062D01*
X461663Y-519646D01*
X461727Y-520312D01*
X461663Y-520979D01*
X461410Y-521562D01*
X461030Y-521896D01*
X460650Y-521979D01*
G01X465750D02*
X465370Y-521896D01*
X464990Y-521562D01*
X464737Y-520979D01*
X464610Y-520312D01*
X464737Y-519646D01*
X464990Y-519062D01*
X465370Y-518729D01*
X465750Y-518646D01*
X466130Y-518729D01*
X466510Y-519062D01*
X466763Y-519646D01*
X466827Y-520312D01*
X466763Y-520979D01*
X466510Y-521562D01*
X466130Y-521896D01*
X465750Y-521979D01*
G01X470850D02*
Y-516979D01*
G01X475950Y-522146D02*
X475823Y-522062D01*
Y-521896D01*
X475950Y-521812D01*
X476077Y-521896D01*
Y-522062D01*
X475950Y-522146D01*
G01Y-519896D02*
X475823Y-519812D01*
Y-519646D01*
X475950Y-519562D01*
X476077Y-519646D01*
Y-519812D01*
X475950Y-519896D01*
G01X454283Y-496979D02*
Y-491979D01*
X455867D01*
X456373Y-492229D01*
X456690Y-492562D01*
X456817Y-493229D01*
X456690Y-493896D01*
X456310Y-494312D01*
X455867Y-494562D01*
X454283D01*
G01X455867D02*
X456817Y-496979D01*
G01X461917D02*
X459383D01*
Y-491979D01*
X461917D01*
G01X460903Y-494396D02*
X459383D01*
G01X464167Y-491979D02*
X465750Y-496979D01*
X467333Y-491979D01*
G01X470850Y-497146D02*
X470723Y-497062D01*
Y-496896D01*
X470850Y-496812D01*
X470977Y-496896D01*
Y-497062D01*
X470850Y-497146D01*
G01Y-494896D02*
X470723Y-494812D01*
Y-494646D01*
X470850Y-494562D01*
X470977Y-494646D01*
Y-494812D01*
X470850Y-494896D01*
G01X-984580Y-698988D02*
Y4193602D01*
X5868320D01*
Y-698988D01*
X-984580D01*
G01X7723Y-521204D02*
X7253Y-520889D01*
X6705Y-520679D01*
X6078D01*
X5373Y-520994D01*
X4825Y-521519D01*
X4433Y-522149D01*
X4120Y-523199D01*
X4042Y-524144D01*
X4198Y-525089D01*
X4433Y-525719D01*
X4903Y-526349D01*
X5452Y-526769D01*
X6000Y-526979D01*
X6548D01*
X7097Y-526769D01*
X7567Y-526454D01*
X7958Y-526034D01*
G01X11360Y-520679D02*
X13240D01*
G01X12300D02*
Y-526979D01*
G01X11360D02*
X13240D01*
G01X18600Y-520679D02*
Y-526979D01*
G01X16798Y-520679D02*
X20402D01*
G01X24900Y-526979D02*
Y-524144D01*
X23333Y-520679D01*
G01X26467D02*
X24900Y-524144D01*
G01X35777Y-525719D02*
X36247Y-526454D01*
X36873Y-526874D01*
X37578Y-526979D01*
X38205Y-526874D01*
X38832Y-526349D01*
X39223Y-525719D01*
X39302Y-525089D01*
X39145Y-524354D01*
X38597Y-523829D01*
X38048Y-523619D01*
X37343D01*
G01X38048D02*
X38518Y-523304D01*
X38910Y-522779D01*
X39067Y-522149D01*
X38910Y-521519D01*
X38518Y-520994D01*
X37813Y-520679D01*
X37108Y-520784D01*
X36403Y-521204D01*
G01X42077Y-525719D02*
X42547Y-526454D01*
X43173Y-526874D01*
X43878Y-526979D01*
X44505Y-526874D01*
X45132Y-526349D01*
X45523Y-525719D01*
X45602Y-525089D01*
X45445Y-524354D01*
X44897Y-523829D01*
X44348Y-523619D01*
X43643D01*
G01X44348D02*
X44818Y-523304D01*
X45210Y-522779D01*
X45367Y-522149D01*
X45210Y-521519D01*
X44818Y-520994D01*
X44113Y-520679D01*
X43408Y-520784D01*
X42703Y-521204D01*
G01X48377Y-525719D02*
X48847Y-526454D01*
X49473Y-526874D01*
X50178Y-526979D01*
X50805Y-526874D01*
X51432Y-526349D01*
X51823Y-525719D01*
X51902Y-525089D01*
X51745Y-524354D01*
X51197Y-523829D01*
X50648Y-523619D01*
X49943D01*
G01X50648D02*
X51118Y-523304D01*
X51510Y-522779D01*
X51667Y-522149D01*
X51510Y-521519D01*
X51118Y-520994D01*
X50413Y-520679D01*
X49708Y-520784D01*
X49003Y-521204D01*
G01X56243Y-526979D02*
X56400Y-525614D01*
X56635Y-524459D01*
X56948Y-523409D01*
X57340Y-522254D01*
X57967Y-520679D01*
X54833D01*
G01X62543Y-526979D02*
X62700Y-525614D01*
X62935Y-524459D01*
X63248Y-523409D01*
X63640Y-522254D01*
X64267Y-520679D01*
X61133D01*
G01X68843Y-528134D02*
X69157Y-526769D01*
G01X75300Y-520679D02*
Y-526979D01*
G01X73498Y-520679D02*
X77102D01*
G01X79642Y-526979D02*
X81600Y-520679D01*
X83558Y-526979D01*
G01X82853Y-524774D02*
X80347D01*
G01X86960Y-520679D02*
X88840D01*
G01X87900D02*
Y-526979D01*
G01X86960D02*
X88840D01*
G01X91850Y-520679D02*
X92947Y-526979D01*
X94200Y-520679D01*
X95453Y-526979D01*
X96550Y-520679D01*
G01X98542Y-526979D02*
X100500Y-520679D01*
X102458Y-526979D01*
G01X101753Y-524774D02*
X99247D01*
G01X104998Y-526979D02*
Y-520679D01*
X108602Y-526979D01*
Y-520679D01*
G01X119008Y-529079D02*
X118225Y-528029D01*
X117833Y-526979D01*
Y-522779D01*
X118225Y-521729D01*
X119008Y-520679D01*
G01X130433Y-526979D02*
Y-520679D01*
X132392D01*
X133018Y-520994D01*
X133410Y-521414D01*
X133567Y-522254D01*
X133410Y-523094D01*
X132940Y-523619D01*
X132392Y-523934D01*
X130433D01*
G01X132392D02*
X133567Y-526979D01*
G01X138300Y-527189D02*
X138143Y-527084D01*
Y-526874D01*
X138300Y-526769D01*
X138457Y-526874D01*
Y-527084D01*
X138300Y-527189D01*
G01X144600Y-526979D02*
X143973Y-526874D01*
X143425Y-526454D01*
X142955Y-525824D01*
X142642Y-525089D01*
X142485Y-524249D01*
Y-523409D01*
X142642Y-522569D01*
X142955Y-521834D01*
X143425Y-521204D01*
X143973Y-520784D01*
X144600Y-520679D01*
X145227Y-520784D01*
X145775Y-521204D01*
X146245Y-521834D01*
X146558Y-522569D01*
X146715Y-523409D01*
Y-524249D01*
X146558Y-525089D01*
X146245Y-525824D01*
X145775Y-526454D01*
X145227Y-526874D01*
X144600Y-526979D01*
G01X150900Y-527189D02*
X150743Y-527084D01*
Y-526874D01*
X150900Y-526769D01*
X151057Y-526874D01*
Y-527084D01*
X150900Y-527189D01*
G01X158923Y-521204D02*
X158453Y-520889D01*
X157905Y-520679D01*
X157278D01*
X156573Y-520994D01*
X156025Y-521519D01*
X155633Y-522149D01*
X155320Y-523199D01*
X155242Y-524144D01*
X155398Y-525089D01*
X155633Y-525719D01*
X156103Y-526349D01*
X156652Y-526769D01*
X157200Y-526979D01*
X157748D01*
X158297Y-526769D01*
X158767Y-526454D01*
X159158Y-526034D01*
G01X163500Y-527189D02*
X163343Y-527084D01*
Y-526874D01*
X163500Y-526769D01*
X163657Y-526874D01*
Y-527084D01*
X163500Y-527189D01*
G01X170192Y-529079D02*
X170975Y-528029D01*
X171367Y-526979D01*
Y-522779D01*
X170975Y-521729D01*
X170192Y-520679D01*
G01X6470Y-513829D02*
X8037D01*
Y-515719D01*
X7567Y-516349D01*
X7018Y-516769D01*
X6235Y-516979D01*
X5452Y-516769D01*
X4903Y-516349D01*
X4433Y-515719D01*
X4120Y-514984D01*
X3963Y-514144D01*
Y-513409D01*
X4120Y-512779D01*
X4433Y-512044D01*
X4903Y-511414D01*
X5373Y-510994D01*
X6000Y-510679D01*
X6548D01*
X7175Y-510889D01*
X7645Y-511309D01*
G01X10577Y-510679D02*
Y-515194D01*
X10890Y-516139D01*
X11517Y-516769D01*
X12300Y-516979D01*
X13083Y-516769D01*
X13710Y-516139D01*
X14023Y-515194D01*
Y-510679D01*
G01X17660D02*
X19540D01*
G01X18600D02*
Y-516979D01*
G01X17660D02*
X19540D01*
G01X23255Y-516139D02*
X23882Y-516664D01*
X24587Y-516979D01*
X25213D01*
X25840Y-516664D01*
X26310Y-516139D01*
X26545Y-515404D01*
X26388Y-514669D01*
X25997Y-514039D01*
X25292Y-513619D01*
X24352Y-513409D01*
X23803Y-512989D01*
X23568Y-512254D01*
X23725Y-511519D01*
X24117Y-510994D01*
X24665Y-510679D01*
X25213D01*
X25762Y-510889D01*
X26232Y-511414D01*
G01X29555Y-516979D02*
Y-510679D01*
G01X32845D02*
Y-516979D01*
G01Y-513829D02*
X29555D01*
G01X35542Y-516979D02*
X37500Y-510679D01*
X39458Y-516979D01*
G01X38753Y-514774D02*
X36247D01*
G01X41998Y-516979D02*
Y-510679D01*
X45602Y-516979D01*
Y-510679D01*
G01X54677Y-516979D02*
Y-510679D01*
X56243D01*
X56870Y-510994D01*
X57340Y-511414D01*
X57732Y-512044D01*
X58045Y-512779D01*
X58123Y-513829D01*
X58045Y-514879D01*
X57732Y-515614D01*
X57340Y-516244D01*
X56870Y-516664D01*
X56243Y-516979D01*
X54677D01*
G01X61760Y-510679D02*
X63640D01*
G01X62700D02*
Y-516979D01*
G01X61760D02*
X63640D01*
G01X67355Y-516139D02*
X67982Y-516664D01*
X68687Y-516979D01*
X69313D01*
X69940Y-516664D01*
X70410Y-516139D01*
X70645Y-515404D01*
X70488Y-514669D01*
X70097Y-514039D01*
X69392Y-513619D01*
X68452Y-513409D01*
X67903Y-512989D01*
X67668Y-512254D01*
X67825Y-511519D01*
X68217Y-510994D01*
X68765Y-510679D01*
X69313D01*
X69862Y-510889D01*
X70332Y-511414D01*
G01X75300Y-510679D02*
Y-516979D01*
G01X73498Y-510679D02*
X77102D01*
G01X81600Y-517189D02*
X81443Y-517084D01*
Y-516874D01*
X81600Y-516769D01*
X81757Y-516874D01*
Y-517084D01*
X81600Y-517189D01*
G01X87743Y-518134D02*
X88057Y-516769D01*
G01X94200Y-510679D02*
Y-516979D01*
G01X92398Y-510679D02*
X96002D01*
G01X98542Y-516979D02*
X100500Y-510679D01*
X102458Y-516979D01*
G01X101753Y-514774D02*
X99247D01*
G01X106800Y-516979D02*
X106173Y-516874D01*
X105625Y-516454D01*
X105155Y-515824D01*
X104842Y-515089D01*
X104685Y-514249D01*
Y-513409D01*
X104842Y-512569D01*
X105155Y-511834D01*
X105625Y-511204D01*
X106173Y-510784D01*
X106800Y-510679D01*
X107427Y-510784D01*
X107975Y-511204D01*
X108445Y-511834D01*
X108758Y-512569D01*
X108915Y-513409D01*
Y-514249D01*
X108758Y-515089D01*
X108445Y-515824D01*
X107975Y-516454D01*
X107427Y-516874D01*
X106800Y-516979D01*
G01X113100D02*
Y-514144D01*
X111533Y-510679D01*
G01X114667D02*
X113100Y-514144D01*
G01X117677Y-510679D02*
Y-515194D01*
X117990Y-516139D01*
X118617Y-516769D01*
X119400Y-516979D01*
X120183Y-516769D01*
X120810Y-516139D01*
X121123Y-515194D01*
Y-510679D01*
G01X123742Y-516979D02*
X125700Y-510679D01*
X127658Y-516979D01*
G01X126953Y-514774D02*
X124447D01*
G01X130198Y-516979D02*
Y-510679D01*
X133802Y-516979D01*
Y-510679D01*
G01X4198Y-506979D02*
Y-500679D01*
X7802Y-506979D01*
Y-500679D01*
G01X12300Y-506979D02*
X11673Y-506874D01*
X11125Y-506454D01*
X10655Y-505824D01*
X10342Y-505089D01*
X10185Y-504249D01*
Y-503409D01*
X10342Y-502569D01*
X10655Y-501834D01*
X11125Y-501204D01*
X11673Y-500784D01*
X12300Y-500679D01*
X12927Y-500784D01*
X13475Y-501204D01*
X13945Y-501834D01*
X14258Y-502569D01*
X14415Y-503409D01*
Y-504249D01*
X14258Y-505089D01*
X13945Y-505824D01*
X13475Y-506454D01*
X12927Y-506874D01*
X12300Y-506979D01*
G01X18600Y-507189D02*
X18443Y-507084D01*
Y-506874D01*
X18600Y-506769D01*
X18757Y-506874D01*
Y-507084D01*
X18600Y-507189D01*
G01X23412Y-501729D02*
X23882Y-501099D01*
X24430Y-500784D01*
X25057Y-500679D01*
X25840Y-500889D01*
X26388Y-501414D01*
X26545Y-502044D01*
X26467Y-502674D01*
X26153Y-503199D01*
X24587Y-504249D01*
X23882Y-504984D01*
X23412Y-506034D01*
X23255Y-506979D01*
X26545D01*
G01X31200D02*
Y-500679D01*
X30260Y-501939D01*
G01Y-506979D02*
X32140D01*
G01X37500D02*
Y-500679D01*
X36560Y-501939D01*
G01Y-506979D02*
X38440D01*
G01X43643Y-508134D02*
X43957Y-506769D01*
G01X47750Y-500679D02*
X48847Y-506979D01*
X50100Y-500679D01*
X51353Y-506979D01*
X52450Y-500679D01*
G01X57967Y-506979D02*
X54833D01*
Y-500679D01*
X57967D01*
G01X56713Y-503724D02*
X54833D01*
G01X60898Y-506979D02*
Y-500679D01*
X64502Y-506979D01*
Y-500679D01*
G01X67355Y-506979D02*
Y-500679D01*
G01X70645D02*
Y-506979D01*
G01Y-503829D02*
X67355D01*
G01X73577Y-500679D02*
Y-505194D01*
X73890Y-506139D01*
X74517Y-506769D01*
X75300Y-506979D01*
X76083Y-506769D01*
X76710Y-506139D01*
X77023Y-505194D01*
Y-500679D01*
G01X79642Y-506979D02*
X81600Y-500679D01*
X83558Y-506979D01*
G01X82853Y-504774D02*
X80347D01*
G01X92712Y-501729D02*
X93182Y-501099D01*
X93730Y-500784D01*
X94357Y-500679D01*
X95140Y-500889D01*
X95688Y-501414D01*
X95845Y-502044D01*
X95767Y-502674D01*
X95453Y-503199D01*
X93887Y-504249D01*
X93182Y-504984D01*
X92712Y-506034D01*
X92555Y-506979D01*
X95845D01*
G01X98698D02*
Y-500679D01*
X102302Y-506979D01*
Y-500679D01*
G01X105077Y-506979D02*
Y-500679D01*
X106643D01*
X107270Y-500994D01*
X107740Y-501414D01*
X108132Y-502044D01*
X108445Y-502779D01*
X108523Y-503829D01*
X108445Y-504879D01*
X108132Y-505614D01*
X107740Y-506244D01*
X107270Y-506664D01*
X106643Y-506979D01*
X105077D01*
G01X117833D02*
Y-500679D01*
X119792D01*
X120418Y-500994D01*
X120810Y-501414D01*
X120967Y-502254D01*
X120810Y-503094D01*
X120340Y-503619D01*
X119792Y-503934D01*
X117833D01*
G01X119792D02*
X120967Y-506979D01*
G01X123977D02*
Y-500679D01*
X125543D01*
X126170Y-500994D01*
X126640Y-501414D01*
X127032Y-502044D01*
X127345Y-502779D01*
X127423Y-503829D01*
X127345Y-504879D01*
X127032Y-505614D01*
X126640Y-506244D01*
X126170Y-506664D01*
X125543Y-506979D01*
X123977D01*
G01X132000Y-507189D02*
X131843Y-507084D01*
Y-506874D01*
X132000Y-506769D01*
X132157Y-506874D01*
Y-507084D01*
X132000Y-507189D01*
G01X28300Y-494279D02*
X25780Y-493862D01*
X23575Y-492196D01*
X21685Y-489696D01*
X20425Y-486779D01*
X19795Y-483446D01*
Y-480112D01*
X20425Y-476779D01*
X21685Y-473862D01*
X23575Y-471363D01*
X25780Y-469696D01*
X28300Y-469279D01*
X30820Y-469696D01*
X33025Y-471363D01*
X34915Y-473862D01*
X36175Y-476779D01*
X36805Y-480112D01*
Y-483446D01*
X36175Y-486779D01*
X34915Y-489696D01*
X33025Y-492196D01*
X30820Y-493862D01*
X28300Y-494279D01*
G01X30820Y-487612D02*
X34600Y-494279D01*
G01X48145Y-477613D02*
Y-489279D01*
X49405Y-492196D01*
X51295Y-493862D01*
X53500Y-494279D01*
X55705Y-493862D01*
X57595Y-492196D01*
X58855Y-489279D01*
G01Y-494279D02*
Y-477613D01*
G01X84370Y-494279D02*
Y-477613D01*
G01Y-480529D02*
X83110Y-478863D01*
X81220Y-478029D01*
X79015Y-477613D01*
X76810Y-478446D01*
X74920Y-480112D01*
X73660Y-482613D01*
X73030Y-485946D01*
X73660Y-489279D01*
X74920Y-491780D01*
X76810Y-493446D01*
X79015Y-494279D01*
X81220Y-493862D01*
X83110Y-492613D01*
X84370Y-490946D01*
G01X98545Y-494279D02*
Y-477613D01*
G01Y-481779D02*
X99805Y-479696D01*
X101695Y-478029D01*
X104215Y-477613D01*
X106420Y-478029D01*
X108310Y-479696D01*
X109255Y-482613D01*
Y-494279D01*
G01X129100Y-469279D02*
Y-494279D01*
G01X124690Y-477613D02*
X133510D01*
G01X159970Y-494279D02*
Y-477613D01*
G01Y-480529D02*
X158710Y-478863D01*
X156820Y-478029D01*
X154615Y-477613D01*
X152410Y-478446D01*
X150520Y-480112D01*
X149260Y-482613D01*
X148630Y-485946D01*
X149260Y-489279D01*
X150520Y-491780D01*
X152410Y-493446D01*
X154615Y-494279D01*
X156820Y-493862D01*
X158710Y-492613D01*
X159970Y-490946D01*
G01X199650Y-473979D02*
Y-481979D01*
X203650D01*
G01X211450D02*
Y-476646D01*
G01Y-477579D02*
X211050Y-477046D01*
X210450Y-476779D01*
X209750Y-476646D01*
X209050Y-476912D01*
X208450Y-477446D01*
X208050Y-478246D01*
X207850Y-479312D01*
X208050Y-480379D01*
X208450Y-481179D01*
X209050Y-481712D01*
X209750Y-481979D01*
X210450Y-481846D01*
X211050Y-481446D01*
X211450Y-480913D01*
G01X215550Y-484379D02*
X216150Y-484646D01*
X216950Y-484379D01*
X217450Y-483846D01*
X217850Y-483179D01*
X218450Y-481046D01*
X219750Y-476646D01*
G01X216550D02*
X218450Y-481046D01*
G01X224150Y-478379D02*
X227350D01*
X227050Y-477446D01*
X226550Y-476912D01*
X225850Y-476646D01*
X225150Y-476779D01*
X224550Y-477179D01*
X224150Y-478112D01*
X223950Y-478913D01*
Y-479712D01*
X224150Y-480512D01*
X224650Y-481312D01*
X225250Y-481846D01*
X225950Y-481979D01*
X226650Y-481712D01*
X227350Y-480913D01*
G01X232250Y-481979D02*
Y-476646D01*
G01Y-477712D02*
X232750Y-477179D01*
X233250Y-476779D01*
X233950Y-476646D01*
X234450Y-476779D01*
X235050Y-477179D01*
G01X223350Y-531979D02*
Y-523979D01*
X227950Y-531979D01*
Y-523979D01*
G01X233650Y-526646D02*
Y-531979D01*
G01Y-524512D02*
X233450Y-524379D01*
Y-524112D01*
X233650Y-523979D01*
X233850Y-524112D01*
Y-524379D01*
X233650Y-524512D01*
G01X239950Y-531979D02*
Y-526646D01*
G01Y-527979D02*
X240350Y-527312D01*
X240950Y-526779D01*
X241750Y-526646D01*
X242450Y-526779D01*
X243050Y-527312D01*
X243350Y-528246D01*
Y-531979D01*
G01X251450D02*
Y-526646D01*
G01Y-527579D02*
X251050Y-527046D01*
X250450Y-526779D01*
X249750Y-526646D01*
X249050Y-526912D01*
X248450Y-527446D01*
X248050Y-528246D01*
X247850Y-529312D01*
X248050Y-530379D01*
X248450Y-531179D01*
X249050Y-531712D01*
X249750Y-531979D01*
X250450Y-531846D01*
X251050Y-531446D01*
X251450Y-530913D01*
G01X224179Y-500436D02*
X226679Y-508436D01*
X229179Y-500436D01*
G01X236879Y-501103D02*
X236279Y-500703D01*
X235579Y-500436D01*
X234779D01*
X233879Y-500836D01*
X233179Y-501503D01*
X232679Y-502303D01*
X232279Y-503636D01*
X232179Y-504836D01*
X232379Y-506036D01*
X232679Y-506836D01*
X233279Y-507636D01*
X233979Y-508169D01*
X234679Y-508436D01*
X235379D01*
X236079Y-508169D01*
X236679Y-507769D01*
X237179Y-507236D01*
G01X244879Y-501103D02*
X244279Y-500703D01*
X243579Y-500436D01*
X242779D01*
X241879Y-500836D01*
X241179Y-501503D01*
X240679Y-502303D01*
X240279Y-503636D01*
X240179Y-504836D01*
X240379Y-506036D01*
X240679Y-506836D01*
X241279Y-507636D01*
X241979Y-508169D01*
X242679Y-508436D01*
X243379D01*
X244079Y-508169D01*
X244679Y-507769D01*
X245179Y-507236D01*
G01X250679Y-508436D02*
Y-500436D01*
X249479Y-502036D01*
G01Y-508436D02*
X251879D01*
G01X246679Y-483436D02*
Y-475436D01*
X245479Y-477036D01*
G01Y-483436D02*
X247879D01*
G01X254679Y-475436D02*
X253879Y-475703D01*
X253279Y-476369D01*
X252879Y-477169D01*
X252579Y-478236D01*
X252479Y-479436D01*
X252579Y-480636D01*
X252879Y-481703D01*
X253279Y-482503D01*
X253879Y-483169D01*
X254679Y-483436D01*
X255479Y-483169D01*
X256079Y-482503D01*
X256479Y-481703D01*
X256779Y-480636D01*
X256879Y-479436D01*
X256779Y-478236D01*
X256479Y-477169D01*
X256079Y-476369D01*
X255479Y-475703D01*
X254679Y-475436D01*
G01X326250Y-525312D02*
X326850Y-524512D01*
X327550Y-524112D01*
X328350Y-523979D01*
X329350Y-524246D01*
X330050Y-524912D01*
X330250Y-525712D01*
X330150Y-526513D01*
X329750Y-527179D01*
X327750Y-528512D01*
X326850Y-529446D01*
X326250Y-530779D01*
X326050Y-531979D01*
X330250D01*
G01X336150Y-523979D02*
X335350Y-524246D01*
X334750Y-524912D01*
X334350Y-525712D01*
X334050Y-526779D01*
X333950Y-527979D01*
X334050Y-529179D01*
X334350Y-530246D01*
X334750Y-531046D01*
X335350Y-531712D01*
X336150Y-531979D01*
X336950Y-531712D01*
X337550Y-531046D01*
X337950Y-530246D01*
X338250Y-529179D01*
X338350Y-527979D01*
X338250Y-526779D01*
X337950Y-525712D01*
X337550Y-524912D01*
X336950Y-524246D01*
X336150Y-523979D01*
G01X342250Y-525312D02*
X342850Y-524512D01*
X343550Y-524112D01*
X344350Y-523979D01*
X345350Y-524246D01*
X346050Y-524912D01*
X346250Y-525712D01*
X346150Y-526513D01*
X345750Y-527179D01*
X343750Y-528512D01*
X342850Y-529446D01*
X342250Y-530779D01*
X342050Y-531979D01*
X346250D01*
G01X349950Y-530379D02*
X350550Y-531312D01*
X351350Y-531846D01*
X352250Y-531979D01*
X353050Y-531846D01*
X353850Y-531179D01*
X354350Y-530379D01*
X354450Y-529579D01*
X354250Y-528646D01*
X353550Y-527979D01*
X352850Y-527712D01*
X351950D01*
G01X352850D02*
X353450Y-527312D01*
X353950Y-526646D01*
X354150Y-525846D01*
X353950Y-525046D01*
X353450Y-524379D01*
X352550Y-523979D01*
X351650Y-524112D01*
X350750Y-524646D01*
G01X358350Y-532246D02*
X361950Y-523979D01*
G01X368150D02*
X367350Y-524246D01*
X366750Y-524912D01*
X366350Y-525712D01*
X366050Y-526779D01*
X365950Y-527979D01*
X366050Y-529179D01*
X366350Y-530246D01*
X366750Y-531046D01*
X367350Y-531712D01*
X368150Y-531979D01*
X368950Y-531712D01*
X369550Y-531046D01*
X369950Y-530246D01*
X370250Y-529179D01*
X370350Y-527979D01*
X370250Y-526779D01*
X369950Y-525712D01*
X369550Y-524912D01*
X368950Y-524246D01*
X368150Y-523979D01*
G01X373950Y-530379D02*
X374550Y-531312D01*
X375350Y-531846D01*
X376250Y-531979D01*
X377050Y-531846D01*
X377850Y-531179D01*
X378350Y-530379D01*
X378450Y-529579D01*
X378250Y-528646D01*
X377550Y-527979D01*
X376850Y-527712D01*
X375950D01*
G01X376850D02*
X377450Y-527312D01*
X377950Y-526646D01*
X378150Y-525846D01*
X377950Y-525046D01*
X377450Y-524379D01*
X376550Y-523979D01*
X375650Y-524112D01*
X374750Y-524646D01*
G01X382350Y-532246D02*
X385950Y-523979D01*
G01X390250Y-525312D02*
X390850Y-524512D01*
X391550Y-524112D01*
X392350Y-523979D01*
X393350Y-524246D01*
X394050Y-524912D01*
X394250Y-525712D01*
X394150Y-526513D01*
X393750Y-527179D01*
X391750Y-528512D01*
X390850Y-529446D01*
X390250Y-530779D01*
X390050Y-531979D01*
X394250D01*
G01X401350D02*
Y-523979D01*
X397650Y-529712D01*
X402650D01*
G01X325950Y-506979D02*
Y-498979D01*
X327950D01*
X328750Y-499379D01*
X329350Y-499912D01*
X329850Y-500712D01*
X330250Y-501646D01*
X330350Y-502979D01*
X330250Y-504312D01*
X329850Y-505246D01*
X329350Y-506046D01*
X328750Y-506579D01*
X327950Y-506979D01*
X325950D01*
G01X333650D02*
X336150Y-498979D01*
X338650Y-506979D01*
G01X337750Y-504179D02*
X334550D01*
G01X344150Y-498979D02*
X343350Y-499246D01*
X342750Y-499912D01*
X342350Y-500712D01*
X342050Y-501779D01*
X341950Y-502979D01*
X342050Y-504179D01*
X342350Y-505246D01*
X342750Y-506046D01*
X343350Y-506712D01*
X344150Y-506979D01*
X344950Y-506712D01*
X345550Y-506046D01*
X345950Y-505246D01*
X346250Y-504179D01*
X346350Y-502979D01*
X346250Y-501779D01*
X345950Y-500712D01*
X345550Y-499912D01*
X344950Y-499246D01*
X344150Y-498979D01*
G01X350250Y-506979D02*
Y-498979D01*
X354050D01*
G01X352650Y-502846D02*
X350250D01*
G01X360150Y-498979D02*
X359350Y-499246D01*
X358750Y-499912D01*
X358350Y-500712D01*
X358050Y-501779D01*
X357950Y-502979D01*
X358050Y-504179D01*
X358350Y-505246D01*
X358750Y-506046D01*
X359350Y-506712D01*
X360150Y-506979D01*
X360950Y-506712D01*
X361550Y-506046D01*
X361950Y-505246D01*
X362250Y-504179D01*
X362350Y-502979D01*
X362250Y-501779D01*
X361950Y-500712D01*
X361550Y-499912D01*
X360950Y-499246D01*
X360150Y-498979D01*
G01X368150D02*
Y-506979D01*
G01X365850Y-498979D02*
X370450D01*
G01X373550Y-506979D02*
Y-498979D01*
X376150Y-505646D01*
X378750Y-498979D01*
Y-506979D01*
G01X384950Y-502712D02*
X385350Y-502312D01*
X385650Y-501646D01*
X385850Y-500712D01*
X385650Y-499912D01*
X385250Y-499379D01*
X384550Y-498979D01*
X381850D01*
Y-506979D01*
X385150D01*
X385850Y-506446D01*
X386250Y-505646D01*
X386450Y-504712D01*
X386250Y-503779D01*
X385650Y-502979D01*
X384950Y-502712D01*
X381850D01*
G01X390950Y-498979D02*
X393350D01*
G01X392150D02*
Y-506979D01*
G01X390950D02*
X393350D01*
G01X398150Y-505379D02*
X398650Y-506179D01*
X399250Y-506712D01*
X399950Y-506979D01*
X400750Y-506712D01*
X401350Y-506179D01*
X401950Y-505379D01*
X402150Y-504312D01*
Y-498979D01*
G01X408150D02*
X407350Y-499246D01*
X406750Y-499912D01*
X406350Y-500712D01*
X406050Y-501779D01*
X405950Y-502979D01*
X406050Y-504179D01*
X406350Y-505246D01*
X406750Y-506046D01*
X407350Y-506712D01*
X408150Y-506979D01*
X408950Y-506712D01*
X409550Y-506046D01*
X409950Y-505246D01*
X410250Y-504179D01*
X410350Y-502979D01*
X410250Y-501779D01*
X409950Y-500712D01*
X409550Y-499912D01*
X408950Y-499246D01*
X408150Y-498979D01*
G01X343750Y-481979D02*
Y-473979D01*
X347550D01*
G01X346150Y-477846D02*
X343750D01*
G01X353650Y-473979D02*
X352850Y-474246D01*
X352250Y-474912D01*
X351850Y-475712D01*
X351550Y-476779D01*
X351450Y-477979D01*
X351550Y-479179D01*
X351850Y-480246D01*
X352250Y-481046D01*
X352850Y-481712D01*
X353650Y-481979D01*
X354450Y-481712D01*
X355050Y-481046D01*
X355450Y-480246D01*
X355750Y-479179D01*
X355850Y-477979D01*
X355750Y-476779D01*
X355450Y-475712D01*
X355050Y-474912D01*
X354450Y-474246D01*
X353650Y-473979D01*
G01X361650D02*
Y-481979D01*
G01X359350Y-473979D02*
X363950D01*
G01X366650Y-484646D02*
X372650D01*
G01X375050Y-481979D02*
Y-473979D01*
X377650Y-480646D01*
X380250Y-473979D01*
Y-481979D01*
G01X386450Y-477712D02*
X386850Y-477312D01*
X387150Y-476646D01*
X387350Y-475712D01*
X387150Y-474912D01*
X386750Y-474379D01*
X386050Y-473979D01*
X383350D01*
Y-481979D01*
X386650D01*
X387350Y-481446D01*
X387750Y-480646D01*
X387950Y-479712D01*
X387750Y-478779D01*
X387150Y-477979D01*
X386450Y-477712D01*
X383350D01*
G01X390650Y-484646D02*
X396650D01*
G01X403650Y-481979D02*
X399650D01*
Y-473979D01*
X403650D01*
G01X402050Y-477846D02*
X399650D01*
G01X407050Y-481979D02*
Y-473979D01*
X409650Y-480646D01*
X412250Y-473979D01*
Y-481979D01*
G01X417650D02*
X418350Y-481846D01*
X419150Y-481446D01*
X419650Y-480779D01*
X419850Y-479846D01*
X419650Y-478913D01*
X419050Y-478112D01*
X418150Y-477712D01*
X417150D01*
X416550Y-477446D01*
X416050Y-476779D01*
X415850Y-475846D01*
X416150Y-474912D01*
X416850Y-474246D01*
X417650Y-473979D01*
X418450Y-474246D01*
X419150Y-474912D01*
X419450Y-475846D01*
X419250Y-476779D01*
X418750Y-477446D01*
X418150Y-477712D01*
X417150D01*
X416250Y-478112D01*
X415650Y-478913D01*
X415450Y-479846D01*
X415650Y-480779D01*
X416150Y-481446D01*
X416950Y-481846D01*
X417650Y-481979D01*
G01X423950Y-481046D02*
X424650Y-481712D01*
X425450Y-481979D01*
X426250Y-481712D01*
X426950Y-480913D01*
X427450Y-479712D01*
X427650Y-478512D01*
Y-477046D01*
X427450Y-475846D01*
X426950Y-474779D01*
X426350Y-474246D01*
X425650Y-473979D01*
X424850Y-474246D01*
X424250Y-474779D01*
X423850Y-475579D01*
X423650Y-476646D01*
X423850Y-477579D01*
X424350Y-478512D01*
X424950Y-479046D01*
X425650Y-479179D01*
X426450Y-478913D01*
X427050Y-478246D01*
X427650Y-477046D01*
G01X433650Y-473979D02*
X432850Y-474246D01*
X432250Y-474912D01*
X431850Y-475712D01*
X431550Y-476779D01*
X431450Y-477979D01*
X431550Y-479179D01*
X431850Y-480246D01*
X432250Y-481046D01*
X432850Y-481712D01*
X433650Y-481979D01*
X434450Y-481712D01*
X435050Y-481046D01*
X435450Y-480246D01*
X435750Y-479179D01*
X435850Y-477979D01*
X435750Y-476779D01*
X435450Y-475712D01*
X435050Y-474912D01*
X434450Y-474246D01*
X433650Y-473979D01*
G01X439450Y-481979D02*
Y-473979D01*
G01X443250D02*
X439450Y-478913D01*
G01X443850Y-481979D02*
X441150Y-476646D01*
G01X414650Y-534979D02*
Y-526979D01*
X413450Y-528579D01*
G01Y-534979D02*
X415850D01*
G01X420750Y-531646D02*
X421450Y-530712D01*
X422050Y-530179D01*
X422850Y-529912D01*
X423550Y-530179D01*
X424050Y-530712D01*
X424450Y-531512D01*
X424550Y-532446D01*
X424450Y-533246D01*
X424050Y-534046D01*
X423450Y-534712D01*
X422750Y-534979D01*
X421950Y-534712D01*
X421250Y-533913D01*
X420850Y-532712D01*
X420750Y-531379D01*
X420950Y-529646D01*
X421250Y-528712D01*
X421750Y-527779D01*
X422450Y-527112D01*
X423150Y-526979D01*
X423850Y-527246D01*
X424350Y-527912D01*
G01X430650Y-535246D02*
X430450Y-535112D01*
Y-534846D01*
X430650Y-534712D01*
X430850Y-534846D01*
Y-535112D01*
X430650Y-535246D01*
G01X436750Y-531646D02*
X437450Y-530712D01*
X438050Y-530179D01*
X438850Y-529912D01*
X439550Y-530179D01*
X440050Y-530712D01*
X440450Y-531512D01*
X440550Y-532446D01*
X440450Y-533246D01*
X440050Y-534046D01*
X439450Y-534712D01*
X438750Y-534979D01*
X437950Y-534712D01*
X437250Y-533913D01*
X436850Y-532712D01*
X436750Y-531379D01*
X436950Y-529646D01*
X437250Y-528712D01*
X437750Y-527779D01*
X438450Y-527112D01*
X439150Y-526979D01*
X439850Y-527246D01*
X440350Y-527912D01*
G01X459650Y-534979D02*
Y-526979D01*
X458450Y-528579D01*
G01Y-534979D02*
X460850D01*
G01X467450D02*
X467650Y-533246D01*
X467950Y-531779D01*
X468350Y-530446D01*
X468850Y-528979D01*
X469650Y-526979D01*
X465650D01*
G01X475650Y-535246D02*
X475450Y-535112D01*
Y-534846D01*
X475650Y-534712D01*
X475850Y-534846D01*
Y-535112D01*
X475650Y-535246D01*
G01X481750Y-528312D02*
X482350Y-527512D01*
X483050Y-527112D01*
X483850Y-526979D01*
X484850Y-527246D01*
X485550Y-527912D01*
X485750Y-528712D01*
X485650Y-529513D01*
X485250Y-530179D01*
X483250Y-531512D01*
X482350Y-532446D01*
X481750Y-533779D01*
X481550Y-534979D01*
X485750D01*
G01X479650Y-508379D02*
X480150Y-509179D01*
X480750Y-509712D01*
X481450Y-509979D01*
X482250Y-509712D01*
X482850Y-509179D01*
X483450Y-508379D01*
X483650Y-507312D01*
Y-501979D01*
M02*
